{ Packager-XL run on 14-Sep-2023 AT 16:11:04 }
FILE_TYPE = BACK_ANNOTATION;
DRAWING = "@t6g_mb_lib.t6g(sch_1):page10";
BODY = "GENOA_SP5","I200": #LOCATION = "U25" !CDS_LOCATION = "U25" &SEC = "1" #&CDS_SEC = "1";
"MA0_CLK_H":   PN = "BC74"  !CDS_PN = "BC74";
"MA0_CLK_L":   PN = "BD74"  !CDS_PN = "BD74";
"MA1_CLK_H":   PN = "BF74"  !CDS_PN = "BF74";
"MA1_CLK_L":   PN = "BG74"  !CDS_PN = "BG74";
"MA_ALERT_L":   PN = "AR74"  !CDS_PN = "AR74";
"MA_RESET_L":   PN = "AT74"  !CDS_PN = "AT74";
"MAA0_CS_L0":   PN = "AV74"  !CDS_PN = "AV74";
"MAA0_CS_L1":   PN = "AW73"  !CDS_PN = "AW73";
"MAA0_RSP_L":   PN = "BN73"  !CDS_PN = "BN73";
"MAA1_CS_L0":   PN = "AU74"  !CDS_PN = "AU74";
"MAA1_CS_L1":   PN = "AV72"  !CDS_PN = "AV72";
"MAA1_RSP_L":   PN = "BP72"  !CDS_PN = "BP72";
"MAA_CA0":   PN = "AW74"  !CDS_PN = "AW74";
"MAA_CA1":   PN = "AY74"  !CDS_PN = "AY74";
"MAA_CA2":   PN = "AY72"  !CDS_PN = "AY72";
"MAA_CA3":   PN = "BA73"  !CDS_PN = "BA73";
"MAA_CA4":   PN = "BA74"  !CDS_PN = "BA74";
"MAA_CA5":   PN = "BB74"  !CDS_PN = "BB74";
"MAA_CA6":   PN = "BB72"  !CDS_PN = "BB72";
"MAA_CHECK0":   PN = "AJ74"  !CDS_PN = "AJ74";
"MAA_CHECK1":   PN = "AK72"  !CDS_PN = "AK72";
"MAA_CHECK2":   PN = "AK74"  !CDS_PN = "AK74";
"MAA_CHECK3":   PN = "AL73"  !CDS_PN = "AL73";
"MAA_CHECK4":   PN = "AN74"  !CDS_PN = "AN74";
"MAA_CHECK5":   PN = "AP72"  !CDS_PN = "AP72";
"MAA_CHECK6":   PN = "AP74"  !CDS_PN = "AP74";
"MAA_CHECK7":   PN = "AR73"  !CDS_PN = "AR73";
"MAA_DATA0":   PN = "E74"  !CDS_PN = "E74";
"MAA_DATA1":   PN = "F72"  !CDS_PN = "F72";
"MAA_DATA2":   PN = "F74"  !CDS_PN = "F74";
"MAA_DATA3":   PN = "G73"  !CDS_PN = "G73";
"MAA_DATA4":   PN = "J74"  !CDS_PN = "J74";
"MAA_DATA5":   PN = "K72"  !CDS_PN = "K72";
"MAA_DATA6":   PN = "K74"  !CDS_PN = "K74";
"MAA_DATA7":   PN = "L73"  !CDS_PN = "L73";
"MAA_DATA8":   PN = "L74"  !CDS_PN = "L74";
"MAA_DATA9":   PN = "M72"  !CDS_PN = "M72";
"MAA_DATA10":   PN = "M74"  !CDS_PN = "M74";
"MAA_DATA11":   PN = "N73"  !CDS_PN = "N73";
"MAA_DATA12":   PN = "R74"  !CDS_PN = "R74";
"MAA_DATA13":   PN = "T72"  !CDS_PN = "T72";
"MAA_DATA14":   PN = "T74"  !CDS_PN = "T74";
"MAA_DATA15":   PN = "U73"  !CDS_PN = "U73";
"MAA_DATA16":   PN = "U74"  !CDS_PN = "U74";
"MAA_DATA17":   PN = "V72"  !CDS_PN = "V72";
"MAA_DATA18":   PN = "V74"  !CDS_PN = "V74";
"MAA_DATA19":   PN = "W73"  !CDS_PN = "W73";
"MAA_DATA20":   PN = "AA74"  !CDS_PN = "AA74";
"MAA_DATA21":   PN = "AB72"  !CDS_PN = "AB72";
"MAA_DATA22":   PN = "AB74"  !CDS_PN = "AB74";
"MAA_DATA23":   PN = "AC73"  !CDS_PN = "AC73";
"MAA_DATA24":   PN = "AC74"  !CDS_PN = "AC74";
"MAA_DATA25":   PN = "AD72"  !CDS_PN = "AD72";
"MAA_DATA26":   PN = "AD74"  !CDS_PN = "AD74";
"MAA_DATA27":   PN = "AE73"  !CDS_PN = "AE73";
"MAA_DATA28":   PN = "AG74"  !CDS_PN = "AG74";
"MAA_DATA29":   PN = "AH72"  !CDS_PN = "AH72";
"MAA_DATA30":   PN = "AH74"  !CDS_PN = "AH74";
"MAA_DATA31":   PN = "AJ73"  !CDS_PN = "AJ73";
"MAA_DQS_H0":   PN = "G74"  !CDS_PN = "G74";
"MAA_DQS_H1":   PN = "N74"  !CDS_PN = "N74";
"MAA_DQS_H2":   PN = "W74"  !CDS_PN = "W74";
"MAA_DQS_H3":   PN = "AE74"  !CDS_PN = "AE74";
"MAA_DQS_H4":   PN = "AL74"  !CDS_PN = "AL74";
"MAA_DQS_H5":   PN = "J73"  !CDS_PN = "J73";
"MAA_DQS_H6":   PN = "R73"  !CDS_PN = "R73";
"MAA_DQS_H7":   PN = "AA73"  !CDS_PN = "AA73";
"MAA_DQS_H8":   PN = "AG73"  !CDS_PN = "AG73";
"MAA_DQS_H9":   PN = "AN73"  !CDS_PN = "AN73";
"MAA_DQS_L0":   PN = "H74"  !CDS_PN = "H74";
"MAA_DQS_L1":   PN = "P74"  !CDS_PN = "P74";
"MAA_DQS_L2":   PN = "Y74"  !CDS_PN = "Y74";
"MAA_DQS_L3":   PN = "AF74"  !CDS_PN = "AF74";
"MAA_DQS_L4":   PN = "AM74"  !CDS_PN = "AM74";
"MAA_DQS_L5":   PN = "H72"  !CDS_PN = "H72";
"MAA_DQS_L6":   PN = "P72"  !CDS_PN = "P72";
"MAA_DQS_L7":   PN = "Y72"  !CDS_PN = "Y72";
"MAA_DQS_L8":   PN = "AF72"  !CDS_PN = "AF72";
"MAA_DQS_L9":   PN = "AM72"  !CDS_PN = "AM72";
"MAA_PAR":   PN = "BC73"  !CDS_PN = "BC73";
"MAB0_CS_L0":   PN = "BM72"  !CDS_PN = "BM72";
"MAB0_CS_L1":   PN = "BN74"  !CDS_PN = "BN74";
"MAB0_RSP_L":   PN = "BP74"  !CDS_PN = "BP74";
"MAB1_CS_L0":   PN = "BL73"  !CDS_PN = "BL73";
"MAB1_CS_L1":   PN = "BM74"  !CDS_PN = "BM74";
"MAB1_RSP_L":   PN = "BR74"  !CDS_PN = "BR74";
"MAB_CA0":   PN = "BG73"  !CDS_PN = "BG73";
"MAB_CA1":   PN = "BH72"  !CDS_PN = "BH72";
"MAB_CA2":   PN = "BH74"  !CDS_PN = "BH74";
"MAB_CA3":   PN = "BJ74"  !CDS_PN = "BJ74";
"MAB_CA4":   PN = "BJ73"  !CDS_PN = "BJ73";
"MAB_CA5":   PN = "BK72"  !CDS_PN = "BK72";
"MAB_CA6":   PN = "BK74"  !CDS_PN = "BK74";
"MAB_CHECK0":   PN = "BY74"  !CDS_PN = "BY74";
"MAB_CHECK1":   PN = "CA73"  !CDS_PN = "CA73";
"MAB_CHECK2":   PN = "CA74"  !CDS_PN = "CA74";
"MAB_CHECK3":   PN = "CB72"  !CDS_PN = "CB72";
"MAB_CHECK4":   PN = "BT74"  !CDS_PN = "BT74";
"MAB_CHECK5":   PN = "BU73"  !CDS_PN = "BU73";
"MAB_CHECK6":   PN = "BU74"  !CDS_PN = "BU74";
"MAB_CHECK7":   PN = "BV72"  !CDS_PN = "BV72";
"MAB_DATA0":   PN = "CB74"  !CDS_PN = "CB74";
"MAB_DATA1":   PN = "CC73"  !CDS_PN = "CC73";
"MAB_DATA2":   PN = "CC74"  !CDS_PN = "CC74";
"MAB_DATA3":   PN = "CD72"  !CDS_PN = "CD72";
"MAB_DATA4":   PN = "CF74"  !CDS_PN = "CF74";
"MAB_DATA5":   PN = "CG73"  !CDS_PN = "CG73";
"MAB_DATA6":   PN = "CG74"  !CDS_PN = "CG74";
"MAB_DATA7":   PN = "CH72"  !CDS_PN = "CH72";
"MAB_DATA8":   PN = "CH74"  !CDS_PN = "CH74";
"MAB_DATA9":   PN = "CJ73"  !CDS_PN = "CJ73";
"MAB_DATA10":   PN = "CJ74"  !CDS_PN = "CJ74";
"MAB_DATA11":   PN = "CK72"  !CDS_PN = "CK72";
"MAB_DATA12":   PN = "CM74"  !CDS_PN = "CM74";
"MAB_DATA13":   PN = "CN73"  !CDS_PN = "CN73";
"MAB_DATA14":   PN = "CN74"  !CDS_PN = "CN74";
"MAB_DATA15":   PN = "CP72"  !CDS_PN = "CP72";
"MAB_DATA16":   PN = "CP74"  !CDS_PN = "CP74";
"MAB_DATA17":   PN = "CR73"  !CDS_PN = "CR73";
"MAB_DATA18":   PN = "CR74"  !CDS_PN = "CR74";
"MAB_DATA19":   PN = "CT72"  !CDS_PN = "CT72";
"MAB_DATA20":   PN = "CV74"  !CDS_PN = "CV74";
"MAB_DATA21":   PN = "CW73"  !CDS_PN = "CW73";
"MAB_DATA22":   PN = "CW74"  !CDS_PN = "CW74";
"MAB_DATA23":   PN = "CY72"  !CDS_PN = "CY72";
"MAB_DATA24":   PN = "CY74"  !CDS_PN = "CY74";
"MAB_DATA25":   PN = "DA73"  !CDS_PN = "DA73";
"MAB_DATA26":   PN = "DA74"  !CDS_PN = "DA74";
"MAB_DATA27":   PN = "DB72"  !CDS_PN = "DB72";
"MAB_DATA28":   PN = "DD74"  !CDS_PN = "DD74";
"MAB_DATA29":   PN = "DE73"  !CDS_PN = "DE73";
"MAB_DATA30":   PN = "DE74"  !CDS_PN = "DE74";
"MAB_DATA31":   PN = "DF74"  !CDS_PN = "DF74";
"MAB_DQS_H0":   PN = "CD74"  !CDS_PN = "CD74";
"MAB_DQS_H1":   PN = "CK74"  !CDS_PN = "CK74";
"MAB_DQS_H2":   PN = "CT74"  !CDS_PN = "CT74";
"MAB_DQS_H3":   PN = "DB74"  !CDS_PN = "DB74";
"MAB_DQS_H4":   PN = "BY72"  !CDS_PN = "BY72";
"MAB_DQS_H5":   PN = "CF72"  !CDS_PN = "CF72";
"MAB_DQS_H6":   PN = "CM72"  !CDS_PN = "CM72";
"MAB_DQS_H7":   PN = "CV72"  !CDS_PN = "CV72";
"MAB_DQS_H8":   PN = "DD72"  !CDS_PN = "DD72";
"MAB_DQS_H9":   PN = "BV74"  !CDS_PN = "BV74";
"MAB_DQS_L0":   PN = "CE74"  !CDS_PN = "CE74";
"MAB_DQS_L1":   PN = "CL74"  !CDS_PN = "CL74";
"MAB_DQS_L2":   PN = "CU74"  !CDS_PN = "CU74";
"MAB_DQS_L3":   PN = "DC74"  !CDS_PN = "DC74";
"MAB_DQS_L4":   PN = "BW73"  !CDS_PN = "BW73";
"MAB_DQS_L5":   PN = "CE73"  !CDS_PN = "CE73";
"MAB_DQS_L6":   PN = "CL73"  !CDS_PN = "CL73";
"MAB_DQS_L7":   PN = "CU73"  !CDS_PN = "CU73";
"MAB_DQS_L8":   PN = "DC73"  !CDS_PN = "DC73";
"MAB_DQS_L9":   PN = "BW74"  !CDS_PN = "BW74";
"MAB_PAR":   PN = "BL74"  !CDS_PN = "BL74";
"TEST39A":   PN = "BF72"  !CDS_PN = "BF72";
"TEST40":   PN = "C60"  !CDS_PN = "C60";
BODY = "Q_RES","I837": #LOCATION = "R375" !CDS_LOCATION = "R375" &SEC = "1" #&CDS_SEC = "1";
"A":   PN = "1"  !CDS_PN = "1";
"B":   PN = "2"  !CDS_PN = "2";
DRAWING = "@t6g_mb_lib.t6g(sch_1):page11";
BODY = "GENOA_SP5","I171": #LOCATION = "U25" !CDS_LOCATION = "U25" &SEC = "2" #&CDS_SEC = "2";
"MB0_CLK_H":   PN = "BC64"  !CDS_PN = "BC64";
"MB0_CLK_L":   PN = "BD63"  !CDS_PN = "BD63";
"MB1_CLK_H":   PN = "BF63"  !CDS_PN = "BF63";
"MB1_CLK_L":   PN = "BG64"  !CDS_PN = "BG64";
"MB_ALERT_L":   PN = "AT62"  !CDS_PN = "AT62";
"MB_RESET_L":   PN = "AU62"  !CDS_PN = "AU62";
"MBA0_CS_L0":   PN = "AV63"  !CDS_PN = "AV63";
"MBA0_CS_L1":   PN = "AW62"  !CDS_PN = "AW62";
"MBA0_RSP_L":   PN = "BN62"  !CDS_PN = "BN62";
"MBA1_CS_L0":   PN = "AU64"  !CDS_PN = "AU64";
"MBA1_CS_L1":   PN = "AV62"  !CDS_PN = "AV62";
"MBA1_RSP_L":   PN = "BP62"  !CDS_PN = "BP62";
"MBA_CA0":   PN = "AW64"  !CDS_PN = "AW64";
"MBA_CA1":   PN = "AY63"  !CDS_PN = "AY63";
"MBA_CA2":   PN = "AY62"  !CDS_PN = "AY62";
"MBA_CA3":   PN = "BA62"  !CDS_PN = "BA62";
"MBA_CA4":   PN = "BA64"  !CDS_PN = "BA64";
"MBA_CA5":   PN = "BB63"  !CDS_PN = "BB63";
"MBA_CA6":   PN = "BB62"  !CDS_PN = "BB62";
"MBA_CHECK0":   PN = "AJ64"  !CDS_PN = "AJ64";
"MBA_CHECK1":   PN = "AK62"  !CDS_PN = "AK62";
"MBA_CHECK2":   PN = "AK63"  !CDS_PN = "AK63";
"MBA_CHECK3":   PN = "AL62"  !CDS_PN = "AL62";
"MBA_CHECK4":   PN = "AN64"  !CDS_PN = "AN64";
"MBA_CHECK5":   PN = "AP62"  !CDS_PN = "AP62";
"MBA_CHECK6":   PN = "AP63"  !CDS_PN = "AP63";
"MBA_CHECK7":   PN = "AR62"  !CDS_PN = "AR62";
"MBA_DATA0":   PN = "E64"  !CDS_PN = "E64";
"MBA_DATA1":   PN = "F62"  !CDS_PN = "F62";
"MBA_DATA2":   PN = "F63"  !CDS_PN = "F63";
"MBA_DATA3":   PN = "G62"  !CDS_PN = "G62";
"MBA_DATA4":   PN = "J64"  !CDS_PN = "J64";
"MBA_DATA5":   PN = "K62"  !CDS_PN = "K62";
"MBA_DATA6":   PN = "K63"  !CDS_PN = "K63";
"MBA_DATA7":   PN = "L62"  !CDS_PN = "L62";
"MBA_DATA8":   PN = "L64"  !CDS_PN = "L64";
"MBA_DATA9":   PN = "M62"  !CDS_PN = "M62";
"MBA_DATA10":   PN = "M63"  !CDS_PN = "M63";
"MBA_DATA11":   PN = "N62"  !CDS_PN = "N62";
"MBA_DATA12":   PN = "R64"  !CDS_PN = "R64";
"MBA_DATA13":   PN = "T62"  !CDS_PN = "T62";
"MBA_DATA14":   PN = "T63"  !CDS_PN = "T63";
"MBA_DATA15":   PN = "U62"  !CDS_PN = "U62";
"MBA_DATA16":   PN = "U64"  !CDS_PN = "U64";
"MBA_DATA17":   PN = "V62"  !CDS_PN = "V62";
"MBA_DATA18":   PN = "V63"  !CDS_PN = "V63";
"MBA_DATA19":   PN = "W62"  !CDS_PN = "W62";
"MBA_DATA20":   PN = "AA64"  !CDS_PN = "AA64";
"MBA_DATA21":   PN = "AB62"  !CDS_PN = "AB62";
"MBA_DATA22":   PN = "AB63"  !CDS_PN = "AB63";
"MBA_DATA23":   PN = "AC62"  !CDS_PN = "AC62";
"MBA_DATA24":   PN = "AC64"  !CDS_PN = "AC64";
"MBA_DATA25":   PN = "AD62"  !CDS_PN = "AD62";
"MBA_DATA26":   PN = "AD63"  !CDS_PN = "AD63";
"MBA_DATA27":   PN = "AE62"  !CDS_PN = "AE62";
"MBA_DATA28":   PN = "AG64"  !CDS_PN = "AG64";
"MBA_DATA29":   PN = "AH62"  !CDS_PN = "AH62";
"MBA_DATA30":   PN = "AH63"  !CDS_PN = "AH63";
"MBA_DATA31":   PN = "AJ62"  !CDS_PN = "AJ62";
"MBA_DQS_H0":   PN = "G64"  !CDS_PN = "G64";
"MBA_DQS_H1":   PN = "N64"  !CDS_PN = "N64";
"MBA_DQS_H2":   PN = "W64"  !CDS_PN = "W64";
"MBA_DQS_H3":   PN = "AE64"  !CDS_PN = "AE64";
"MBA_DQS_H4":   PN = "AL64"  !CDS_PN = "AL64";
"MBA_DQS_H5":   PN = "J62"  !CDS_PN = "J62";
"MBA_DQS_H6":   PN = "R62"  !CDS_PN = "R62";
"MBA_DQS_H7":   PN = "AA62"  !CDS_PN = "AA62";
"MBA_DQS_H8":   PN = "AG62"  !CDS_PN = "AG62";
"MBA_DQS_H9":   PN = "AN62"  !CDS_PN = "AN62";
"MBA_DQS_L0":   PN = "H63"  !CDS_PN = "H63";
"MBA_DQS_L1":   PN = "P63"  !CDS_PN = "P63";
"MBA_DQS_L2":   PN = "Y63"  !CDS_PN = "Y63";
"MBA_DQS_L3":   PN = "AF63"  !CDS_PN = "AF63";
"MBA_DQS_L4":   PN = "AM63"  !CDS_PN = "AM63";
"MBA_DQS_L5":   PN = "H62"  !CDS_PN = "H62";
"MBA_DQS_L6":   PN = "P62"  !CDS_PN = "P62";
"MBA_DQS_L7":   PN = "Y62"  !CDS_PN = "Y62";
"MBA_DQS_L8":   PN = "AF62"  !CDS_PN = "AF62";
"MBA_DQS_L9":   PN = "AM62"  !CDS_PN = "AM62";
"MBA_PAR":   PN = "BC62"  !CDS_PN = "BC62";
"MBB0_CS_L0":   PN = "BM62"  !CDS_PN = "BM62";
"MBB0_CS_L1":   PN = "BN64"  !CDS_PN = "BN64";
"MBB0_RSP_L":   PN = "BP63"  !CDS_PN = "BP63";
"MBB1_CS_L0":   PN = "BL62"  !CDS_PN = "BL62";
"MBB1_CS_L1":   PN = "BM63"  !CDS_PN = "BM63";
"MBB1_RSP_L":   PN = "BR64"  !CDS_PN = "BR64";
"MBB_CA0":   PN = "BG62"  !CDS_PN = "BG62";
"MBB_CA1":   PN = "BH62"  !CDS_PN = "BH62";
"MBB_CA2":   PN = "BH63"  !CDS_PN = "BH63";
"MBB_CA3":   PN = "BJ64"  !CDS_PN = "BJ64";
"MBB_CA4":   PN = "BJ62"  !CDS_PN = "BJ62";
"MBB_CA5":   PN = "BK62"  !CDS_PN = "BK62";
"MBB_CA6":   PN = "BK63"  !CDS_PN = "BK63";
"MBB_CHECK0":   PN = "BY63"  !CDS_PN = "BY63";
"MBB_CHECK1":   PN = "CA62"  !CDS_PN = "CA62";
"MBB_CHECK2":   PN = "CA64"  !CDS_PN = "CA64";
"MBB_CHECK3":   PN = "CB62"  !CDS_PN = "CB62";
"MBB_CHECK4":   PN = "BT63"  !CDS_PN = "BT63";
"MBB_CHECK5":   PN = "BU62"  !CDS_PN = "BU62";
"MBB_CHECK6":   PN = "BU64"  !CDS_PN = "BU64";
"MBB_CHECK7":   PN = "BV62"  !CDS_PN = "BV62";
"MBB_DATA0":   PN = "CB63"  !CDS_PN = "CB63";
"MBB_DATA1":   PN = "CC62"  !CDS_PN = "CC62";
"MBB_DATA2":   PN = "CC64"  !CDS_PN = "CC64";
"MBB_DATA3":   PN = "CD62"  !CDS_PN = "CD62";
"MBB_DATA4":   PN = "CF63"  !CDS_PN = "CF63";
"MBB_DATA5":   PN = "CG62"  !CDS_PN = "CG62";
"MBB_DATA6":   PN = "CG64"  !CDS_PN = "CG64";
"MBB_DATA7":   PN = "CH62"  !CDS_PN = "CH62";
"MBB_DATA8":   PN = "CH63"  !CDS_PN = "CH63";
"MBB_DATA9":   PN = "CJ62"  !CDS_PN = "CJ62";
"MBB_DATA10":   PN = "CJ64"  !CDS_PN = "CJ64";
"MBB_DATA11":   PN = "CK62"  !CDS_PN = "CK62";
"MBB_DATA12":   PN = "CM63"  !CDS_PN = "CM63";
"MBB_DATA13":   PN = "CN62"  !CDS_PN = "CN62";
"MBB_DATA14":   PN = "CN64"  !CDS_PN = "CN64";
"MBB_DATA15":   PN = "CP62"  !CDS_PN = "CP62";
"MBB_DATA16":   PN = "CP63"  !CDS_PN = "CP63";
"MBB_DATA17":   PN = "CR62"  !CDS_PN = "CR62";
"MBB_DATA18":   PN = "CR64"  !CDS_PN = "CR64";
"MBB_DATA19":   PN = "CT62"  !CDS_PN = "CT62";
"MBB_DATA20":   PN = "CV63"  !CDS_PN = "CV63";
"MBB_DATA21":   PN = "CW62"  !CDS_PN = "CW62";
"MBB_DATA22":   PN = "CW64"  !CDS_PN = "CW64";
"MBB_DATA23":   PN = "CY62"  !CDS_PN = "CY62";
"MBB_DATA24":   PN = "CY63"  !CDS_PN = "CY63";
"MBB_DATA25":   PN = "DA62"  !CDS_PN = "DA62";
"MBB_DATA26":   PN = "DA64"  !CDS_PN = "DA64";
"MBB_DATA27":   PN = "DB62"  !CDS_PN = "DB62";
"MBB_DATA28":   PN = "DD63"  !CDS_PN = "DD63";
"MBB_DATA29":   PN = "DE62"  !CDS_PN = "DE62";
"MBB_DATA30":   PN = "DE64"  !CDS_PN = "DE64";
"MBB_DATA31":   PN = "DF62"  !CDS_PN = "DF62";
"MBB_DQS_H0":   PN = "CD63"  !CDS_PN = "CD63";
"MBB_DQS_H1":   PN = "CK63"  !CDS_PN = "CK63";
"MBB_DQS_H2":   PN = "CT63"  !CDS_PN = "CT63";
"MBB_DQS_H3":   PN = "DB63"  !CDS_PN = "DB63";
"MBB_DQS_H4":   PN = "BY62"  !CDS_PN = "BY62";
"MBB_DQS_H5":   PN = "CF62"  !CDS_PN = "CF62";
"MBB_DQS_H6":   PN = "CM62"  !CDS_PN = "CM62";
"MBB_DQS_H7":   PN = "CV62"  !CDS_PN = "CV62";
"MBB_DQS_H8":   PN = "DD62"  !CDS_PN = "DD62";
"MBB_DQS_H9":   PN = "BV63"  !CDS_PN = "BV63";
"MBB_DQS_L0":   PN = "CE64"  !CDS_PN = "CE64";
"MBB_DQS_L1":   PN = "CL64"  !CDS_PN = "CL64";
"MBB_DQS_L2":   PN = "CU64"  !CDS_PN = "CU64";
"MBB_DQS_L3":   PN = "DC64"  !CDS_PN = "DC64";
"MBB_DQS_L4":   PN = "BW62"  !CDS_PN = "BW62";
"MBB_DQS_L5":   PN = "CE62"  !CDS_PN = "CE62";
"MBB_DQS_L6":   PN = "CL62"  !CDS_PN = "CL62";
"MBB_DQS_L7":   PN = "CU62"  !CDS_PN = "CU62";
"MBB_DQS_L8":   PN = "DC62"  !CDS_PN = "DC62";
"MBB_DQS_L9":   PN = "BW64"  !CDS_PN = "BW64";
"MBB_PAR":   PN = "BL64"  !CDS_PN = "BL64";
"TEST39B":   PN = "BF62"  !CDS_PN = "BF62";
BODY = "Q_RES","I327": #LOCATION = "R376" !CDS_LOCATION = "R376" &SEC = "1" #&CDS_SEC = "1";
"A":   PN = "1"  !CDS_PN = "1";
"B":   PN = "2"  !CDS_PN = "2";
DRAWING = "@t6g_mb_lib.t6g(sch_1):page12";
BODY = "GENOA_SP5","I159": #LOCATION = "U25" !CDS_LOCATION = "U25" &SEC = "3" #&CDS_SEC = "3";
"MC0_CLK_H":   PN = "BC57"  !CDS_PN = "BC57";
"MC0_CLK_L":   PN = "BD56"  !CDS_PN = "BD56";
"MC1_CLK_H":   PN = "BF56"  !CDS_PN = "BF56";
"MC1_CLK_L":   PN = "BG57"  !CDS_PN = "BG57";
"MC_ALERT_L":   PN = "AT55"  !CDS_PN = "AT55";
"MC_RESET_L":   PN = "AU55"  !CDS_PN = "AU55";
"MCA0_CS_L0":   PN = "AV56"  !CDS_PN = "AV56";
"MCA0_CS_L1":   PN = "AW55"  !CDS_PN = "AW55";
"MCA0_RSP_L":   PN = "BN55"  !CDS_PN = "BN55";
"MCA1_CS_L0":   PN = "AU57"  !CDS_PN = "AU57";
"MCA1_CS_L1":   PN = "AV55"  !CDS_PN = "AV55";
"MCA1_RSP_L":   PN = "BP55"  !CDS_PN = "BP55";
"MCA_CA0":   PN = "AW57"  !CDS_PN = "AW57";
"MCA_CA1":   PN = "AY56"  !CDS_PN = "AY56";
"MCA_CA2":   PN = "AY55"  !CDS_PN = "AY55";
"MCA_CA3":   PN = "BA55"  !CDS_PN = "BA55";
"MCA_CA4":   PN = "BA57"  !CDS_PN = "BA57";
"MCA_CA5":   PN = "BB56"  !CDS_PN = "BB56";
"MCA_CA6":   PN = "BB55"  !CDS_PN = "BB55";
"MCA_CHECK0":   PN = "AJ57"  !CDS_PN = "AJ57";
"MCA_CHECK1":   PN = "AK55"  !CDS_PN = "AK55";
"MCA_CHECK2":   PN = "AK56"  !CDS_PN = "AK56";
"MCA_CHECK3":   PN = "AL55"  !CDS_PN = "AL55";
"MCA_CHECK4":   PN = "AN57"  !CDS_PN = "AN57";
"MCA_CHECK5":   PN = "AP55"  !CDS_PN = "AP55";
"MCA_CHECK6":   PN = "AP56"  !CDS_PN = "AP56";
"MCA_CHECK7":   PN = "AR55"  !CDS_PN = "AR55";
"MCA_DATA0":   PN = "E57"  !CDS_PN = "E57";
"MCA_DATA1":   PN = "F55"  !CDS_PN = "F55";
"MCA_DATA2":   PN = "F56"  !CDS_PN = "F56";
"MCA_DATA3":   PN = "G55"  !CDS_PN = "G55";
"MCA_DATA4":   PN = "J57"  !CDS_PN = "J57";
"MCA_DATA5":   PN = "K55"  !CDS_PN = "K55";
"MCA_DATA6":   PN = "K56"  !CDS_PN = "K56";
"MCA_DATA7":   PN = "L55"  !CDS_PN = "L55";
"MCA_DATA8":   PN = "L57"  !CDS_PN = "L57";
"MCA_DATA9":   PN = "M55"  !CDS_PN = "M55";
"MCA_DATA10":   PN = "M56"  !CDS_PN = "M56";
"MCA_DATA11":   PN = "N55"  !CDS_PN = "N55";
"MCA_DATA12":   PN = "R57"  !CDS_PN = "R57";
"MCA_DATA13":   PN = "T55"  !CDS_PN = "T55";
"MCA_DATA14":   PN = "T56"  !CDS_PN = "T56";
"MCA_DATA15":   PN = "U55"  !CDS_PN = "U55";
"MCA_DATA16":   PN = "U57"  !CDS_PN = "U57";
"MCA_DATA17":   PN = "V55"  !CDS_PN = "V55";
"MCA_DATA18":   PN = "V56"  !CDS_PN = "V56";
"MCA_DATA19":   PN = "W55"  !CDS_PN = "W55";
"MCA_DATA20":   PN = "AA57"  !CDS_PN = "AA57";
"MCA_DATA21":   PN = "AB55"  !CDS_PN = "AB55";
"MCA_DATA22":   PN = "AB56"  !CDS_PN = "AB56";
"MCA_DATA23":   PN = "AC55"  !CDS_PN = "AC55";
"MCA_DATA24":   PN = "AC57"  !CDS_PN = "AC57";
"MCA_DATA25":   PN = "AD55"  !CDS_PN = "AD55";
"MCA_DATA26":   PN = "AD56"  !CDS_PN = "AD56";
"MCA_DATA27":   PN = "AE55"  !CDS_PN = "AE55";
"MCA_DATA28":   PN = "AG57"  !CDS_PN = "AG57";
"MCA_DATA29":   PN = "AH55"  !CDS_PN = "AH55";
"MCA_DATA30":   PN = "AH56"  !CDS_PN = "AH56";
"MCA_DATA31":   PN = "AJ55"  !CDS_PN = "AJ55";
"MCA_DQS_H0":   PN = "G57"  !CDS_PN = "G57";
"MCA_DQS_H1":   PN = "N57"  !CDS_PN = "N57";
"MCA_DQS_H2":   PN = "W57"  !CDS_PN = "W57";
"MCA_DQS_H3":   PN = "AE57"  !CDS_PN = "AE57";
"MCA_DQS_H4":   PN = "AL57"  !CDS_PN = "AL57";
"MCA_DQS_H5":   PN = "J55"  !CDS_PN = "J55";
"MCA_DQS_H6":   PN = "R55"  !CDS_PN = "R55";
"MCA_DQS_H7":   PN = "AA55"  !CDS_PN = "AA55";
"MCA_DQS_H8":   PN = "AG55"  !CDS_PN = "AG55";
"MCA_DQS_H9":   PN = "AN55"  !CDS_PN = "AN55";
"MCA_DQS_L0":   PN = "H56"  !CDS_PN = "H56";
"MCA_DQS_L1":   PN = "P56"  !CDS_PN = "P56";
"MCA_DQS_L2":   PN = "Y56"  !CDS_PN = "Y56";
"MCA_DQS_L3":   PN = "AF56"  !CDS_PN = "AF56";
"MCA_DQS_L4":   PN = "AM56"  !CDS_PN = "AM56";
"MCA_DQS_L5":   PN = "H55"  !CDS_PN = "H55";
"MCA_DQS_L6":   PN = "P55"  !CDS_PN = "P55";
"MCA_DQS_L7":   PN = "Y55"  !CDS_PN = "Y55";
"MCA_DQS_L8":   PN = "AF55"  !CDS_PN = "AF55";
"MCA_DQS_L9":   PN = "AM55"  !CDS_PN = "AM55";
"MCA_PAR":   PN = "BC55"  !CDS_PN = "BC55";
"MCB0_CS_L0":   PN = "BM55"  !CDS_PN = "BM55";
"MCB0_CS_L1":   PN = "BN57"  !CDS_PN = "BN57";
"MCB0_RSP_L":   PN = "BP56"  !CDS_PN = "BP56";
"MCB1_CS_L0":   PN = "BL55"  !CDS_PN = "BL55";
"MCB1_CS_L1":   PN = "BM56"  !CDS_PN = "BM56";
"MCB1_RSP_L":   PN = "BR57"  !CDS_PN = "BR57";
"MCB_CA0":   PN = "BG55"  !CDS_PN = "BG55";
"MCB_CA1":   PN = "BH55"  !CDS_PN = "BH55";
"MCB_CA2":   PN = "BH56"  !CDS_PN = "BH56";
"MCB_CA3":   PN = "BJ57"  !CDS_PN = "BJ57";
"MCB_CA4":   PN = "BJ55"  !CDS_PN = "BJ55";
"MCB_CA5":   PN = "BK55"  !CDS_PN = "BK55";
"MCB_CA6":   PN = "BK56"  !CDS_PN = "BK56";
"MCB_CHECK0":   PN = "BY56"  !CDS_PN = "BY56";
"MCB_CHECK1":   PN = "CA55"  !CDS_PN = "CA55";
"MCB_CHECK2":   PN = "CA57"  !CDS_PN = "CA57";
"MCB_CHECK3":   PN = "CB55"  !CDS_PN = "CB55";
"MCB_CHECK4":   PN = "BT56"  !CDS_PN = "BT56";
"MCB_CHECK5":   PN = "BU55"  !CDS_PN = "BU55";
"MCB_CHECK6":   PN = "BU57"  !CDS_PN = "BU57";
"MCB_CHECK7":   PN = "BV55"  !CDS_PN = "BV55";
"MCB_DATA0":   PN = "CB56"  !CDS_PN = "CB56";
"MCB_DATA1":   PN = "CC55"  !CDS_PN = "CC55";
"MCB_DATA2":   PN = "CC57"  !CDS_PN = "CC57";
"MCB_DATA3":   PN = "CD55"  !CDS_PN = "CD55";
"MCB_DATA4":   PN = "CF56"  !CDS_PN = "CF56";
"MCB_DATA5":   PN = "CG55"  !CDS_PN = "CG55";
"MCB_DATA6":   PN = "CG57"  !CDS_PN = "CG57";
"MCB_DATA7":   PN = "CH55"  !CDS_PN = "CH55";
"MCB_DATA8":   PN = "CH56"  !CDS_PN = "CH56";
"MCB_DATA9":   PN = "CJ55"  !CDS_PN = "CJ55";
"MCB_DATA10":   PN = "CJ57"  !CDS_PN = "CJ57";
"MCB_DATA11":   PN = "CK55"  !CDS_PN = "CK55";
"MCB_DATA12":   PN = "CM56"  !CDS_PN = "CM56";
"MCB_DATA13":   PN = "CN55"  !CDS_PN = "CN55";
"MCB_DATA14":   PN = "CN57"  !CDS_PN = "CN57";
"MCB_DATA15":   PN = "CP55"  !CDS_PN = "CP55";
"MCB_DATA16":   PN = "CP56"  !CDS_PN = "CP56";
"MCB_DATA17":   PN = "CR55"  !CDS_PN = "CR55";
"MCB_DATA18":   PN = "CR57"  !CDS_PN = "CR57";
"MCB_DATA19":   PN = "CT55"  !CDS_PN = "CT55";
"MCB_DATA20":   PN = "CV56"  !CDS_PN = "CV56";
"MCB_DATA21":   PN = "CW55"  !CDS_PN = "CW55";
"MCB_DATA22":   PN = "CW57"  !CDS_PN = "CW57";
"MCB_DATA23":   PN = "CY55"  !CDS_PN = "CY55";
"MCB_DATA24":   PN = "CY56"  !CDS_PN = "CY56";
"MCB_DATA25":   PN = "DA55"  !CDS_PN = "DA55";
"MCB_DATA26":   PN = "DA57"  !CDS_PN = "DA57";
"MCB_DATA27":   PN = "DB55"  !CDS_PN = "DB55";
"MCB_DATA28":   PN = "DD56"  !CDS_PN = "DD56";
"MCB_DATA29":   PN = "DE55"  !CDS_PN = "DE55";
"MCB_DATA30":   PN = "DE57"  !CDS_PN = "DE57";
"MCB_DATA31":   PN = "DF55"  !CDS_PN = "DF55";
"MCB_DQS_H0":   PN = "CD56"  !CDS_PN = "CD56";
"MCB_DQS_H1":   PN = "CK56"  !CDS_PN = "CK56";
"MCB_DQS_H2":   PN = "CT56"  !CDS_PN = "CT56";
"MCB_DQS_H3":   PN = "DB56"  !CDS_PN = "DB56";
"MCB_DQS_H4":   PN = "BY55"  !CDS_PN = "BY55";
"MCB_DQS_H5":   PN = "CF55"  !CDS_PN = "CF55";
"MCB_DQS_H6":   PN = "CM55"  !CDS_PN = "CM55";
"MCB_DQS_H7":   PN = "CV55"  !CDS_PN = "CV55";
"MCB_DQS_H8":   PN = "DD55"  !CDS_PN = "DD55";
"MCB_DQS_H9":   PN = "BV56"  !CDS_PN = "BV56";
"MCB_DQS_L0":   PN = "CE57"  !CDS_PN = "CE57";
"MCB_DQS_L1":   PN = "CL57"  !CDS_PN = "CL57";
"MCB_DQS_L2":   PN = "CU57"  !CDS_PN = "CU57";
"MCB_DQS_L3":   PN = "DC57"  !CDS_PN = "DC57";
"MCB_DQS_L4":   PN = "BW55"  !CDS_PN = "BW55";
"MCB_DQS_L5":   PN = "CE55"  !CDS_PN = "CE55";
"MCB_DQS_L6":   PN = "CL55"  !CDS_PN = "CL55";
"MCB_DQS_L7":   PN = "CU55"  !CDS_PN = "CU55";
"MCB_DQS_L8":   PN = "DC55"  !CDS_PN = "DC55";
"MCB_DQS_L9":   PN = "BW57"  !CDS_PN = "BW57";
"MCB_PAR":   PN = "BL57"  !CDS_PN = "BL57";
"TEST39C":   PN = "BF55"  !CDS_PN = "BF55";
BODY = "Q_RES","I314": #LOCATION = "R377" !CDS_LOCATION = "R377" &SEC = "1" #&CDS_SEC = "1";
"A":   PN = "1"  !CDS_PN = "1";
"B":   PN = "2"  !CDS_PN = "2";
DRAWING = "@t6g_mb_lib.t6g(sch_1):page13";
BODY = "GENOA_SP5","I159": #LOCATION = "U25" !CDS_LOCATION = "U25" &SEC = "4" #&CDS_SEC = "4";
"MD0_CLK_H":   PN = "BC60"  !CDS_PN = "BC60";
"MD0_CLK_L":   PN = "BD60"  !CDS_PN = "BD60";
"MD1_CLK_H":   PN = "BF60"  !CDS_PN = "BF60";
"MD1_CLK_L":   PN = "BG60"  !CDS_PN = "BG60";
"MD_ALERT_L":   PN = "AT58"  !CDS_PN = "AT58";
"MD_RESET_L":   PN = "AU59"  !CDS_PN = "AU59";
"MDA0_CS_L0":   PN = "AV60"  !CDS_PN = "AV60";
"MDA0_CS_L1":   PN = "AW59"  !CDS_PN = "AW59";
"MDA0_RSP_L":   PN = "BN59"  !CDS_PN = "BN59";
"MDA1_CS_L0":   PN = "AU60"  !CDS_PN = "AU60";
"MDA1_CS_L1":   PN = "AV58"  !CDS_PN = "AV58";
"MDA1_RSP_L":   PN = "BP58"  !CDS_PN = "BP58";
"MDA_CA0":   PN = "AW60"  !CDS_PN = "AW60";
"MDA_CA1":   PN = "AY60"  !CDS_PN = "AY60";
"MDA_CA2":   PN = "AY58"  !CDS_PN = "AY58";
"MDA_CA3":   PN = "BA59"  !CDS_PN = "BA59";
"MDA_CA4":   PN = "BA60"  !CDS_PN = "BA60";
"MDA_CA5":   PN = "BB60"  !CDS_PN = "BB60";
"MDA_CA6":   PN = "BB58"  !CDS_PN = "BB58";
"MDA_CHECK0":   PN = "AJ60"  !CDS_PN = "AJ60";
"MDA_CHECK1":   PN = "AK58"  !CDS_PN = "AK58";
"MDA_CHECK2":   PN = "AK60"  !CDS_PN = "AK60";
"MDA_CHECK3":   PN = "AL59"  !CDS_PN = "AL59";
"MDA_CHECK4":   PN = "AN60"  !CDS_PN = "AN60";
"MDA_CHECK5":   PN = "AP58"  !CDS_PN = "AP58";
"MDA_CHECK6":   PN = "AP60"  !CDS_PN = "AP60";
"MDA_CHECK7":   PN = "AR59"  !CDS_PN = "AR59";
"MDA_DATA0":   PN = "E60"  !CDS_PN = "E60";
"MDA_DATA1":   PN = "F58"  !CDS_PN = "F58";
"MDA_DATA2":   PN = "F60"  !CDS_PN = "F60";
"MDA_DATA3":   PN = "G59"  !CDS_PN = "G59";
"MDA_DATA4":   PN = "J60"  !CDS_PN = "J60";
"MDA_DATA5":   PN = "K58"  !CDS_PN = "K58";
"MDA_DATA6":   PN = "K60"  !CDS_PN = "K60";
"MDA_DATA7":   PN = "L59"  !CDS_PN = "L59";
"MDA_DATA8":   PN = "L60"  !CDS_PN = "L60";
"MDA_DATA9":   PN = "M58"  !CDS_PN = "M58";
"MDA_DATA10":   PN = "M60"  !CDS_PN = "M60";
"MDA_DATA11":   PN = "N59"  !CDS_PN = "N59";
"MDA_DATA12":   PN = "R60"  !CDS_PN = "R60";
"MDA_DATA13":   PN = "T58"  !CDS_PN = "T58";
"MDA_DATA14":   PN = "T60"  !CDS_PN = "T60";
"MDA_DATA15":   PN = "U59"  !CDS_PN = "U59";
"MDA_DATA16":   PN = "U60"  !CDS_PN = "U60";
"MDA_DATA17":   PN = "V58"  !CDS_PN = "V58";
"MDA_DATA18":   PN = "V60"  !CDS_PN = "V60";
"MDA_DATA19":   PN = "W59"  !CDS_PN = "W59";
"MDA_DATA20":   PN = "AA60"  !CDS_PN = "AA60";
"MDA_DATA21":   PN = "AB58"  !CDS_PN = "AB58";
"MDA_DATA22":   PN = "AB60"  !CDS_PN = "AB60";
"MDA_DATA23":   PN = "AC59"  !CDS_PN = "AC59";
"MDA_DATA24":   PN = "AC60"  !CDS_PN = "AC60";
"MDA_DATA25":   PN = "AD58"  !CDS_PN = "AD58";
"MDA_DATA26":   PN = "AD60"  !CDS_PN = "AD60";
"MDA_DATA27":   PN = "AE59"  !CDS_PN = "AE59";
"MDA_DATA28":   PN = "AG60"  !CDS_PN = "AG60";
"MDA_DATA29":   PN = "AH58"  !CDS_PN = "AH58";
"MDA_DATA30":   PN = "AH60"  !CDS_PN = "AH60";
"MDA_DATA31":   PN = "AJ59"  !CDS_PN = "AJ59";
"MDA_DQS_H0":   PN = "G60"  !CDS_PN = "G60";
"MDA_DQS_H1":   PN = "N60"  !CDS_PN = "N60";
"MDA_DQS_H2":   PN = "W60"  !CDS_PN = "W60";
"MDA_DQS_H3":   PN = "AE60"  !CDS_PN = "AE60";
"MDA_DQS_H4":   PN = "AL60"  !CDS_PN = "AL60";
"MDA_DQS_H5":   PN = "J59"  !CDS_PN = "J59";
"MDA_DQS_H6":   PN = "R59"  !CDS_PN = "R59";
"MDA_DQS_H7":   PN = "AA59"  !CDS_PN = "AA59";
"MDA_DQS_H8":   PN = "AG59"  !CDS_PN = "AG59";
"MDA_DQS_H9":   PN = "AN59"  !CDS_PN = "AN59";
"MDA_DQS_L0":   PN = "H60"  !CDS_PN = "H60";
"MDA_DQS_L1":   PN = "P60"  !CDS_PN = "P60";
"MDA_DQS_L2":   PN = "Y60"  !CDS_PN = "Y60";
"MDA_DQS_L3":   PN = "AF60"  !CDS_PN = "AF60";
"MDA_DQS_L4":   PN = "AM60"  !CDS_PN = "AM60";
"MDA_DQS_L5":   PN = "H58"  !CDS_PN = "H58";
"MDA_DQS_L6":   PN = "P58"  !CDS_PN = "P58";
"MDA_DQS_L7":   PN = "Y58"  !CDS_PN = "Y58";
"MDA_DQS_L8":   PN = "AF58"  !CDS_PN = "AF58";
"MDA_DQS_L9":   PN = "AM58"  !CDS_PN = "AM58";
"MDA_PAR":   PN = "BC59"  !CDS_PN = "BC59";
"MDB0_CS_L0":   PN = "BM58"  !CDS_PN = "BM58";
"MDB0_CS_L1":   PN = "BN60"  !CDS_PN = "BN60";
"MDB0_RSP_L":   PN = "BP60"  !CDS_PN = "BP60";
"MDB1_CS_L0":   PN = "BL59"  !CDS_PN = "BL59";
"MDB1_CS_L1":   PN = "BM60"  !CDS_PN = "BM60";
"MDB1_RSP_L":   PN = "BR60"  !CDS_PN = "BR60";
"MDB_CA0":   PN = "BG59"  !CDS_PN = "BG59";
"MDB_CA1":   PN = "BH58"  !CDS_PN = "BH58";
"MDB_CA2":   PN = "BH60"  !CDS_PN = "BH60";
"MDB_CA3":   PN = "BJ60"  !CDS_PN = "BJ60";
"MDB_CA4":   PN = "BJ59"  !CDS_PN = "BJ59";
"MDB_CA5":   PN = "BK58"  !CDS_PN = "BK58";
"MDB_CA6":   PN = "BK60"  !CDS_PN = "BK60";
"MDB_CHECK0":   PN = "BY60"  !CDS_PN = "BY60";
"MDB_CHECK1":   PN = "CA59"  !CDS_PN = "CA59";
"MDB_CHECK2":   PN = "CA60"  !CDS_PN = "CA60";
"MDB_CHECK3":   PN = "CB58"  !CDS_PN = "CB58";
"MDB_CHECK4":   PN = "BT60"  !CDS_PN = "BT60";
"MDB_CHECK5":   PN = "BU59"  !CDS_PN = "BU59";
"MDB_CHECK6":   PN = "BU60"  !CDS_PN = "BU60";
"MDB_CHECK7":   PN = "BV58"  !CDS_PN = "BV58";
"MDB_DATA0":   PN = "CB60"  !CDS_PN = "CB60";
"MDB_DATA1":   PN = "CC59"  !CDS_PN = "CC59";
"MDB_DATA2":   PN = "CC60"  !CDS_PN = "CC60";
"MDB_DATA3":   PN = "CD58"  !CDS_PN = "CD58";
"MDB_DATA4":   PN = "CF60"  !CDS_PN = "CF60";
"MDB_DATA5":   PN = "CG59"  !CDS_PN = "CG59";
"MDB_DATA6":   PN = "CG60"  !CDS_PN = "CG60";
"MDB_DATA7":   PN = "CH58"  !CDS_PN = "CH58";
"MDB_DATA8":   PN = "CH60"  !CDS_PN = "CH60";
"MDB_DATA9":   PN = "CJ59"  !CDS_PN = "CJ59";
"MDB_DATA10":   PN = "CJ60"  !CDS_PN = "CJ60";
"MDB_DATA11":   PN = "CK58"  !CDS_PN = "CK58";
"MDB_DATA12":   PN = "CM60"  !CDS_PN = "CM60";
"MDB_DATA13":   PN = "CN59"  !CDS_PN = "CN59";
"MDB_DATA14":   PN = "CN60"  !CDS_PN = "CN60";
"MDB_DATA15":   PN = "CP58"  !CDS_PN = "CP58";
"MDB_DATA16":   PN = "CP60"  !CDS_PN = "CP60";
"MDB_DATA17":   PN = "CR59"  !CDS_PN = "CR59";
"MDB_DATA18":   PN = "CR60"  !CDS_PN = "CR60";
"MDB_DATA19":   PN = "CT58"  !CDS_PN = "CT58";
"MDB_DATA20":   PN = "CV60"  !CDS_PN = "CV60";
"MDB_DATA21":   PN = "CW59"  !CDS_PN = "CW59";
"MDB_DATA22":   PN = "CW60"  !CDS_PN = "CW60";
"MDB_DATA23":   PN = "CY58"  !CDS_PN = "CY58";
"MDB_DATA24":   PN = "CY60"  !CDS_PN = "CY60";
"MDB_DATA25":   PN = "DA59"  !CDS_PN = "DA59";
"MDB_DATA26":   PN = "DA60"  !CDS_PN = "DA60";
"MDB_DATA27":   PN = "DB58"  !CDS_PN = "DB58";
"MDB_DATA28":   PN = "DD60"  !CDS_PN = "DD60";
"MDB_DATA29":   PN = "DE59"  !CDS_PN = "DE59";
"MDB_DATA30":   PN = "DE60"  !CDS_PN = "DE60";
"MDB_DATA31":   PN = "DF60"  !CDS_PN = "DF60";
"MDB_DQS_H0":   PN = "CD60"  !CDS_PN = "CD60";
"MDB_DQS_H1":   PN = "CK60"  !CDS_PN = "CK60";
"MDB_DQS_H2":   PN = "CT60"  !CDS_PN = "CT60";
"MDB_DQS_H3":   PN = "DB60"  !CDS_PN = "DB60";
"MDB_DQS_H4":   PN = "BY58"  !CDS_PN = "BY58";
"MDB_DQS_H5":   PN = "CF58"  !CDS_PN = "CF58";
"MDB_DQS_H6":   PN = "CM58"  !CDS_PN = "CM58";
"MDB_DQS_H7":   PN = "CV58"  !CDS_PN = "CV58";
"MDB_DQS_H8":   PN = "DD58"  !CDS_PN = "DD58";
"MDB_DQS_H9":   PN = "BV60"  !CDS_PN = "BV60";
"MDB_DQS_L0":   PN = "CE60"  !CDS_PN = "CE60";
"MDB_DQS_L1":   PN = "CL60"  !CDS_PN = "CL60";
"MDB_DQS_L2":   PN = "CU60"  !CDS_PN = "CU60";
"MDB_DQS_L3":   PN = "DC60"  !CDS_PN = "DC60";
"MDB_DQS_L4":   PN = "BW59"  !CDS_PN = "BW59";
"MDB_DQS_L5":   PN = "CE59"  !CDS_PN = "CE59";
"MDB_DQS_L6":   PN = "CL59"  !CDS_PN = "CL59";
"MDB_DQS_L7":   PN = "CU59"  !CDS_PN = "CU59";
"MDB_DQS_L8":   PN = "DC59"  !CDS_PN = "DC59";
"MDB_DQS_L9":   PN = "BW60"  !CDS_PN = "BW60";
"MDB_PAR":   PN = "BL60"  !CDS_PN = "BL60";
"TEST39D":   PN = "BF58"  !CDS_PN = "BF58";
BODY = "Q_RES","I314": #LOCATION = "R378" !CDS_LOCATION = "R378" &SEC = "1" #&CDS_SEC = "1";
"A":   PN = "1"  !CDS_PN = "1";
"B":   PN = "2"  !CDS_PN = "2";
DRAWING = "@t6g_mb_lib.t6g(sch_1):page14";
BODY = "GENOA_SP5","I159": #LOCATION = "U25" !CDS_LOCATION = "U25" &SEC = "5" #&CDS_SEC = "5";
"ME0_CLK_H":   PN = "BC71"  !CDS_PN = "BC71";
"ME0_CLK_L":   PN = "BD70"  !CDS_PN = "BD70";
"ME1_CLK_H":   PN = "BF70"  !CDS_PN = "BF70";
"ME1_CLK_L":   PN = "BG71"  !CDS_PN = "BG71";
"ME_ALERT_L":   PN = "AT69"  !CDS_PN = "AT69";
"ME_RESET_L":   PN = "AU69"  !CDS_PN = "AU69";
"MEA0_CS_L0":   PN = "AV70"  !CDS_PN = "AV70";
"MEA0_CS_L1":   PN = "AW69"  !CDS_PN = "AW69";
"MEA0_RSP_L":   PN = "BN69"  !CDS_PN = "BN69";
"MEA1_CS_L0":   PN = "AU71"  !CDS_PN = "AU71";
"MEA1_CS_L1":   PN = "AV69"  !CDS_PN = "AV69";
"MEA1_RSP_L":   PN = "BP69"  !CDS_PN = "BP69";
"MEA_CA0":   PN = "AW71"  !CDS_PN = "AW71";
"MEA_CA1":   PN = "AY70"  !CDS_PN = "AY70";
"MEA_CA2":   PN = "AY69"  !CDS_PN = "AY69";
"MEA_CA3":   PN = "BA69"  !CDS_PN = "BA69";
"MEA_CA4":   PN = "BA71"  !CDS_PN = "BA71";
"MEA_CA5":   PN = "BB70"  !CDS_PN = "BB70";
"MEA_CA6":   PN = "BB69"  !CDS_PN = "BB69";
"MEA_CHECK0":   PN = "AJ71"  !CDS_PN = "AJ71";
"MEA_CHECK1":   PN = "AK69"  !CDS_PN = "AK69";
"MEA_CHECK2":   PN = "AK70"  !CDS_PN = "AK70";
"MEA_CHECK3":   PN = "AL69"  !CDS_PN = "AL69";
"MEA_CHECK4":   PN = "AN71"  !CDS_PN = "AN71";
"MEA_CHECK5":   PN = "AP69"  !CDS_PN = "AP69";
"MEA_CHECK6":   PN = "AP70"  !CDS_PN = "AP70";
"MEA_CHECK7":   PN = "AR69"  !CDS_PN = "AR69";
"MEA_DATA0":   PN = "E71"  !CDS_PN = "E71";
"MEA_DATA1":   PN = "F69"  !CDS_PN = "F69";
"MEA_DATA2":   PN = "F70"  !CDS_PN = "F70";
"MEA_DATA3":   PN = "G69"  !CDS_PN = "G69";
"MEA_DATA4":   PN = "J71"  !CDS_PN = "J71";
"MEA_DATA5":   PN = "K69"  !CDS_PN = "K69";
"MEA_DATA6":   PN = "K70"  !CDS_PN = "K70";
"MEA_DATA7":   PN = "L69"  !CDS_PN = "L69";
"MEA_DATA8":   PN = "L71"  !CDS_PN = "L71";
"MEA_DATA9":   PN = "M69"  !CDS_PN = "M69";
"MEA_DATA10":   PN = "M70"  !CDS_PN = "M70";
"MEA_DATA11":   PN = "N69"  !CDS_PN = "N69";
"MEA_DATA12":   PN = "R71"  !CDS_PN = "R71";
"MEA_DATA13":   PN = "T69"  !CDS_PN = "T69";
"MEA_DATA14":   PN = "T70"  !CDS_PN = "T70";
"MEA_DATA15":   PN = "U69"  !CDS_PN = "U69";
"MEA_DATA16":   PN = "U71"  !CDS_PN = "U71";
"MEA_DATA17":   PN = "V69"  !CDS_PN = "V69";
"MEA_DATA18":   PN = "V70"  !CDS_PN = "V70";
"MEA_DATA19":   PN = "W69"  !CDS_PN = "W69";
"MEA_DATA20":   PN = "AA71"  !CDS_PN = "AA71";
"MEA_DATA21":   PN = "AB69"  !CDS_PN = "AB69";
"MEA_DATA22":   PN = "AB70"  !CDS_PN = "AB70";
"MEA_DATA23":   PN = "AC69"  !CDS_PN = "AC69";
"MEA_DATA24":   PN = "AC71"  !CDS_PN = "AC71";
"MEA_DATA25":   PN = "AD69"  !CDS_PN = "AD69";
"MEA_DATA26":   PN = "AD70"  !CDS_PN = "AD70";
"MEA_DATA27":   PN = "AE69"  !CDS_PN = "AE69";
"MEA_DATA28":   PN = "AG71"  !CDS_PN = "AG71";
"MEA_DATA29":   PN = "AH69"  !CDS_PN = "AH69";
"MEA_DATA30":   PN = "AH70"  !CDS_PN = "AH70";
"MEA_DATA31":   PN = "AJ69"  !CDS_PN = "AJ69";
"MEA_DQS_H0":   PN = "G71"  !CDS_PN = "G71";
"MEA_DQS_H1":   PN = "N71"  !CDS_PN = "N71";
"MEA_DQS_H2":   PN = "W71"  !CDS_PN = "W71";
"MEA_DQS_H3":   PN = "AE71"  !CDS_PN = "AE71";
"MEA_DQS_H4":   PN = "AL71"  !CDS_PN = "AL71";
"MEA_DQS_H5":   PN = "J69"  !CDS_PN = "J69";
"MEA_DQS_H6":   PN = "R69"  !CDS_PN = "R69";
"MEA_DQS_H7":   PN = "AA69"  !CDS_PN = "AA69";
"MEA_DQS_H8":   PN = "AG69"  !CDS_PN = "AG69";
"MEA_DQS_H9":   PN = "AN69"  !CDS_PN = "AN69";
"MEA_DQS_L0":   PN = "H70"  !CDS_PN = "H70";
"MEA_DQS_L1":   PN = "P70"  !CDS_PN = "P70";
"MEA_DQS_L2":   PN = "Y70"  !CDS_PN = "Y70";
"MEA_DQS_L3":   PN = "AF70"  !CDS_PN = "AF70";
"MEA_DQS_L4":   PN = "AM70"  !CDS_PN = "AM70";
"MEA_DQS_L5":   PN = "H69"  !CDS_PN = "H69";
"MEA_DQS_L6":   PN = "P69"  !CDS_PN = "P69";
"MEA_DQS_L7":   PN = "Y69"  !CDS_PN = "Y69";
"MEA_DQS_L8":   PN = "AF69"  !CDS_PN = "AF69";
"MEA_DQS_L9":   PN = "AM69"  !CDS_PN = "AM69";
"MEA_PAR":   PN = "BC69"  !CDS_PN = "BC69";
"MEB0_CS_L0":   PN = "BM69"  !CDS_PN = "BM69";
"MEB0_CS_L1":   PN = "BN71"  !CDS_PN = "BN71";
"MEB0_RSP_L":   PN = "BP70"  !CDS_PN = "BP70";
"MEB1_CS_L0":   PN = "BL69"  !CDS_PN = "BL69";
"MEB1_CS_L1":   PN = "BM70"  !CDS_PN = "BM70";
"MEB1_RSP_L":   PN = "BR71"  !CDS_PN = "BR71";
"MEB_CA0":   PN = "BG69"  !CDS_PN = "BG69";
"MEB_CA1":   PN = "BH69"  !CDS_PN = "BH69";
"MEB_CA2":   PN = "BH70"  !CDS_PN = "BH70";
"MEB_CA3":   PN = "BJ71"  !CDS_PN = "BJ71";
"MEB_CA4":   PN = "BJ69"  !CDS_PN = "BJ69";
"MEB_CA5":   PN = "BK69"  !CDS_PN = "BK69";
"MEB_CA6":   PN = "BK70"  !CDS_PN = "BK70";
"MEB_CHECK0":   PN = "BY70"  !CDS_PN = "BY70";
"MEB_CHECK1":   PN = "CA69"  !CDS_PN = "CA69";
"MEB_CHECK2":   PN = "CA71"  !CDS_PN = "CA71";
"MEB_CHECK3":   PN = "CB69"  !CDS_PN = "CB69";
"MEB_CHECK4":   PN = "BT70"  !CDS_PN = "BT70";
"MEB_CHECK5":   PN = "BU69"  !CDS_PN = "BU69";
"MEB_CHECK6":   PN = "BU71"  !CDS_PN = "BU71";
"MEB_CHECK7":   PN = "BV69"  !CDS_PN = "BV69";
"MEB_DATA0":   PN = "CB70"  !CDS_PN = "CB70";
"MEB_DATA1":   PN = "CC69"  !CDS_PN = "CC69";
"MEB_DATA2":   PN = "CC71"  !CDS_PN = "CC71";
"MEB_DATA3":   PN = "CD69"  !CDS_PN = "CD69";
"MEB_DATA4":   PN = "CF70"  !CDS_PN = "CF70";
"MEB_DATA5":   PN = "CG69"  !CDS_PN = "CG69";
"MEB_DATA6":   PN = "CG71"  !CDS_PN = "CG71";
"MEB_DATA7":   PN = "CH69"  !CDS_PN = "CH69";
"MEB_DATA8":   PN = "CH70"  !CDS_PN = "CH70";
"MEB_DATA9":   PN = "CJ69"  !CDS_PN = "CJ69";
"MEB_DATA10":   PN = "CJ71"  !CDS_PN = "CJ71";
"MEB_DATA11":   PN = "CK69"  !CDS_PN = "CK69";
"MEB_DATA12":   PN = "CM70"  !CDS_PN = "CM70";
"MEB_DATA13":   PN = "CN69"  !CDS_PN = "CN69";
"MEB_DATA14":   PN = "CN71"  !CDS_PN = "CN71";
"MEB_DATA15":   PN = "CP69"  !CDS_PN = "CP69";
"MEB_DATA16":   PN = "CP70"  !CDS_PN = "CP70";
"MEB_DATA17":   PN = "CR69"  !CDS_PN = "CR69";
"MEB_DATA18":   PN = "CR71"  !CDS_PN = "CR71";
"MEB_DATA19":   PN = "CT69"  !CDS_PN = "CT69";
"MEB_DATA20":   PN = "CV70"  !CDS_PN = "CV70";
"MEB_DATA21":   PN = "CW69"  !CDS_PN = "CW69";
"MEB_DATA22":   PN = "CW71"  !CDS_PN = "CW71";
"MEB_DATA23":   PN = "CY69"  !CDS_PN = "CY69";
"MEB_DATA24":   PN = "CY70"  !CDS_PN = "CY70";
"MEB_DATA25":   PN = "DA69"  !CDS_PN = "DA69";
"MEB_DATA26":   PN = "DA71"  !CDS_PN = "DA71";
"MEB_DATA27":   PN = "DB69"  !CDS_PN = "DB69";
"MEB_DATA28":   PN = "DD70"  !CDS_PN = "DD70";
"MEB_DATA29":   PN = "DE69"  !CDS_PN = "DE69";
"MEB_DATA30":   PN = "DE71"  !CDS_PN = "DE71";
"MEB_DATA31":   PN = "DF69"  !CDS_PN = "DF69";
"MEB_DQS_H0":   PN = "CD70"  !CDS_PN = "CD70";
"MEB_DQS_H1":   PN = "CK70"  !CDS_PN = "CK70";
"MEB_DQS_H2":   PN = "CT70"  !CDS_PN = "CT70";
"MEB_DQS_H3":   PN = "DB70"  !CDS_PN = "DB70";
"MEB_DQS_H4":   PN = "BY69"  !CDS_PN = "BY69";
"MEB_DQS_H5":   PN = "CF69"  !CDS_PN = "CF69";
"MEB_DQS_H6":   PN = "CM69"  !CDS_PN = "CM69";
"MEB_DQS_H7":   PN = "CV69"  !CDS_PN = "CV69";
"MEB_DQS_H8":   PN = "DD69"  !CDS_PN = "DD69";
"MEB_DQS_H9":   PN = "BV70"  !CDS_PN = "BV70";
"MEB_DQS_L0":   PN = "CE71"  !CDS_PN = "CE71";
"MEB_DQS_L1":   PN = "CL71"  !CDS_PN = "CL71";
"MEB_DQS_L2":   PN = "CU71"  !CDS_PN = "CU71";
"MEB_DQS_L3":   PN = "DC71"  !CDS_PN = "DC71";
"MEB_DQS_L4":   PN = "BW69"  !CDS_PN = "BW69";
"MEB_DQS_L5":   PN = "CE69"  !CDS_PN = "CE69";
"MEB_DQS_L6":   PN = "CL69"  !CDS_PN = "CL69";
"MEB_DQS_L7":   PN = "CU69"  !CDS_PN = "CU69";
"MEB_DQS_L8":   PN = "DC69"  !CDS_PN = "DC69";
"MEB_DQS_L9":   PN = "BW71"  !CDS_PN = "BW71";
"MEB_PAR":   PN = "BL71"  !CDS_PN = "BL71";
"TEST39E":   PN = "BF69"  !CDS_PN = "BF69";
BODY = "Q_RES","I315": #LOCATION = "R379" !CDS_LOCATION = "R379" &SEC = "1" #&CDS_SEC = "1";
"A":   PN = "1"  !CDS_PN = "1";
"B":   PN = "2"  !CDS_PN = "2";
DRAWING = "@t6g_mb_lib.t6g(sch_1):page15";
BODY = "GENOA_SP5","I159": #LOCATION = "U25" !CDS_LOCATION = "U25" &SEC = "6" #&CDS_SEC = "6";
"MF0_CLK_H":   PN = "BC67"  !CDS_PN = "BC67";
"MF0_CLK_L":   PN = "BD67"  !CDS_PN = "BD67";
"MF1_CLK_H":   PN = "BF67"  !CDS_PN = "BF67";
"MF1_CLK_L":   PN = "BG67"  !CDS_PN = "BG67";
"MF_ALERT_L":   PN = "AT65"  !CDS_PN = "AT65";
"MF_RESET_L":   PN = "AU66"  !CDS_PN = "AU66";
"MFA0_CS_L0":   PN = "AV67"  !CDS_PN = "AV67";
"MFA0_CS_L1":   PN = "AW66"  !CDS_PN = "AW66";
"MFA0_RSP_L":   PN = "BN66"  !CDS_PN = "BN66";
"MFA1_CS_L0":   PN = "AU67"  !CDS_PN = "AU67";
"MFA1_CS_L1":   PN = "AV65"  !CDS_PN = "AV65";
"MFA1_RSP_L":   PN = "BP65"  !CDS_PN = "BP65";
"MFA_CA0":   PN = "AW67"  !CDS_PN = "AW67";
"MFA_CA1":   PN = "AY67"  !CDS_PN = "AY67";
"MFA_CA2":   PN = "AY65"  !CDS_PN = "AY65";
"MFA_CA3":   PN = "BA66"  !CDS_PN = "BA66";
"MFA_CA4":   PN = "BA67"  !CDS_PN = "BA67";
"MFA_CA5":   PN = "BB67"  !CDS_PN = "BB67";
"MFA_CA6":   PN = "BB65"  !CDS_PN = "BB65";
"MFA_CHECK0":   PN = "AJ67"  !CDS_PN = "AJ67";
"MFA_CHECK1":   PN = "AK65"  !CDS_PN = "AK65";
"MFA_CHECK2":   PN = "AK67"  !CDS_PN = "AK67";
"MFA_CHECK3":   PN = "AL66"  !CDS_PN = "AL66";
"MFA_CHECK4":   PN = "AN67"  !CDS_PN = "AN67";
"MFA_CHECK5":   PN = "AP65"  !CDS_PN = "AP65";
"MFA_CHECK6":   PN = "AP67"  !CDS_PN = "AP67";
"MFA_CHECK7":   PN = "AR66"  !CDS_PN = "AR66";
"MFA_DATA0":   PN = "E67"  !CDS_PN = "E67";
"MFA_DATA1":   PN = "F65"  !CDS_PN = "F65";
"MFA_DATA2":   PN = "F67"  !CDS_PN = "F67";
"MFA_DATA3":   PN = "G66"  !CDS_PN = "G66";
"MFA_DATA4":   PN = "J67"  !CDS_PN = "J67";
"MFA_DATA5":   PN = "K65"  !CDS_PN = "K65";
"MFA_DATA6":   PN = "K67"  !CDS_PN = "K67";
"MFA_DATA7":   PN = "L66"  !CDS_PN = "L66";
"MFA_DATA8":   PN = "L67"  !CDS_PN = "L67";
"MFA_DATA9":   PN = "M65"  !CDS_PN = "M65";
"MFA_DATA10":   PN = "M67"  !CDS_PN = "M67";
"MFA_DATA11":   PN = "N66"  !CDS_PN = "N66";
"MFA_DATA12":   PN = "R67"  !CDS_PN = "R67";
"MFA_DATA13":   PN = "T65"  !CDS_PN = "T65";
"MFA_DATA14":   PN = "T67"  !CDS_PN = "T67";
"MFA_DATA15":   PN = "U66"  !CDS_PN = "U66";
"MFA_DATA16":   PN = "U67"  !CDS_PN = "U67";
"MFA_DATA17":   PN = "V65"  !CDS_PN = "V65";
"MFA_DATA18":   PN = "V67"  !CDS_PN = "V67";
"MFA_DATA19":   PN = "W66"  !CDS_PN = "W66";
"MFA_DATA20":   PN = "AA67"  !CDS_PN = "AA67";
"MFA_DATA21":   PN = "AB65"  !CDS_PN = "AB65";
"MFA_DATA22":   PN = "AB67"  !CDS_PN = "AB67";
"MFA_DATA23":   PN = "AC66"  !CDS_PN = "AC66";
"MFA_DATA24":   PN = "AC67"  !CDS_PN = "AC67";
"MFA_DATA25":   PN = "AD65"  !CDS_PN = "AD65";
"MFA_DATA26":   PN = "AD67"  !CDS_PN = "AD67";
"MFA_DATA27":   PN = "AE66"  !CDS_PN = "AE66";
"MFA_DATA28":   PN = "AG67"  !CDS_PN = "AG67";
"MFA_DATA29":   PN = "AH65"  !CDS_PN = "AH65";
"MFA_DATA30":   PN = "AH67"  !CDS_PN = "AH67";
"MFA_DATA31":   PN = "AJ66"  !CDS_PN = "AJ66";
"MFA_DQS_H0":   PN = "G67"  !CDS_PN = "G67";
"MFA_DQS_H1":   PN = "N67"  !CDS_PN = "N67";
"MFA_DQS_H2":   PN = "W67"  !CDS_PN = "W67";
"MFA_DQS_H3":   PN = "AE67"  !CDS_PN = "AE67";
"MFA_DQS_H4":   PN = "AL67"  !CDS_PN = "AL67";
"MFA_DQS_H5":   PN = "J66"  !CDS_PN = "J66";
"MFA_DQS_H6":   PN = "R66"  !CDS_PN = "R66";
"MFA_DQS_H7":   PN = "AA66"  !CDS_PN = "AA66";
"MFA_DQS_H8":   PN = "AG66"  !CDS_PN = "AG66";
"MFA_DQS_H9":   PN = "AN66"  !CDS_PN = "AN66";
"MFA_DQS_L0":   PN = "H67"  !CDS_PN = "H67";
"MFA_DQS_L1":   PN = "P67"  !CDS_PN = "P67";
"MFA_DQS_L2":   PN = "Y67"  !CDS_PN = "Y67";
"MFA_DQS_L3":   PN = "AF67"  !CDS_PN = "AF67";
"MFA_DQS_L4":   PN = "AM67"  !CDS_PN = "AM67";
"MFA_DQS_L5":   PN = "H65"  !CDS_PN = "H65";
"MFA_DQS_L6":   PN = "P65"  !CDS_PN = "P65";
"MFA_DQS_L7":   PN = "Y65"  !CDS_PN = "Y65";
"MFA_DQS_L8":   PN = "AF65"  !CDS_PN = "AF65";
"MFA_DQS_L9":   PN = "AM65"  !CDS_PN = "AM65";
"MFA_PAR":   PN = "BC66"  !CDS_PN = "BC66";
"MFB0_CS_L0":   PN = "BM65"  !CDS_PN = "BM65";
"MFB0_CS_L1":   PN = "BN67"  !CDS_PN = "BN67";
"MFB0_RSP_L":   PN = "BP67"  !CDS_PN = "BP67";
"MFB1_CS_L0":   PN = "BL66"  !CDS_PN = "BL66";
"MFB1_CS_L1":   PN = "BM67"  !CDS_PN = "BM67";
"MFB1_RSP_L":   PN = "BR67"  !CDS_PN = "BR67";
"MFB_CA0":   PN = "BG66"  !CDS_PN = "BG66";
"MFB_CA1":   PN = "BH65"  !CDS_PN = "BH65";
"MFB_CA2":   PN = "BH67"  !CDS_PN = "BH67";
"MFB_CA3":   PN = "BJ67"  !CDS_PN = "BJ67";
"MFB_CA4":   PN = "BJ66"  !CDS_PN = "BJ66";
"MFB_CA5":   PN = "BK65"  !CDS_PN = "BK65";
"MFB_CA6":   PN = "BK67"  !CDS_PN = "BK67";
"MFB_CHECK0":   PN = "BY67"  !CDS_PN = "BY67";
"MFB_CHECK1":   PN = "CA66"  !CDS_PN = "CA66";
"MFB_CHECK2":   PN = "CA67"  !CDS_PN = "CA67";
"MFB_CHECK3":   PN = "CB65"  !CDS_PN = "CB65";
"MFB_CHECK4":   PN = "BT67"  !CDS_PN = "BT67";
"MFB_CHECK5":   PN = "BU66"  !CDS_PN = "BU66";
"MFB_CHECK6":   PN = "BU67"  !CDS_PN = "BU67";
"MFB_CHECK7":   PN = "BV65"  !CDS_PN = "BV65";
"MFB_DATA0":   PN = "CB67"  !CDS_PN = "CB67";
"MFB_DATA1":   PN = "CC66"  !CDS_PN = "CC66";
"MFB_DATA2":   PN = "CC67"  !CDS_PN = "CC67";
"MFB_DATA3":   PN = "CD65"  !CDS_PN = "CD65";
"MFB_DATA4":   PN = "CF67"  !CDS_PN = "CF67";
"MFB_DATA5":   PN = "CG66"  !CDS_PN = "CG66";
"MFB_DATA6":   PN = "CG67"  !CDS_PN = "CG67";
"MFB_DATA7":   PN = "CH65"  !CDS_PN = "CH65";
"MFB_DATA8":   PN = "CH67"  !CDS_PN = "CH67";
"MFB_DATA9":   PN = "CJ66"  !CDS_PN = "CJ66";
"MFB_DATA10":   PN = "CJ67"  !CDS_PN = "CJ67";
"MFB_DATA11":   PN = "CK65"  !CDS_PN = "CK65";
"MFB_DATA12":   PN = "CM67"  !CDS_PN = "CM67";
"MFB_DATA13":   PN = "CN66"  !CDS_PN = "CN66";
"MFB_DATA14":   PN = "CN67"  !CDS_PN = "CN67";
"MFB_DATA15":   PN = "CP65"  !CDS_PN = "CP65";
"MFB_DATA16":   PN = "CP67"  !CDS_PN = "CP67";
"MFB_DATA17":   PN = "CR66"  !CDS_PN = "CR66";
"MFB_DATA18":   PN = "CR67"  !CDS_PN = "CR67";
"MFB_DATA19":   PN = "CT65"  !CDS_PN = "CT65";
"MFB_DATA20":   PN = "CV67"  !CDS_PN = "CV67";
"MFB_DATA21":   PN = "CW66"  !CDS_PN = "CW66";
"MFB_DATA22":   PN = "CW67"  !CDS_PN = "CW67";
"MFB_DATA23":   PN = "CY65"  !CDS_PN = "CY65";
"MFB_DATA24":   PN = "CY67"  !CDS_PN = "CY67";
"MFB_DATA25":   PN = "DA66"  !CDS_PN = "DA66";
"MFB_DATA26":   PN = "DA67"  !CDS_PN = "DA67";
"MFB_DATA27":   PN = "DB65"  !CDS_PN = "DB65";
"MFB_DATA28":   PN = "DD67"  !CDS_PN = "DD67";
"MFB_DATA29":   PN = "DE66"  !CDS_PN = "DE66";
"MFB_DATA30":   PN = "DE67"  !CDS_PN = "DE67";
"MFB_DATA31":   PN = "DF67"  !CDS_PN = "DF67";
"MFB_DQS_H0":   PN = "CD67"  !CDS_PN = "CD67";
"MFB_DQS_H1":   PN = "CK67"  !CDS_PN = "CK67";
"MFB_DQS_H2":   PN = "CT67"  !CDS_PN = "CT67";
"MFB_DQS_H3":   PN = "DB67"  !CDS_PN = "DB67";
"MFB_DQS_H4":   PN = "BY65"  !CDS_PN = "BY65";
"MFB_DQS_H5":   PN = "CF65"  !CDS_PN = "CF65";
"MFB_DQS_H6":   PN = "CM65"  !CDS_PN = "CM65";
"MFB_DQS_H7":   PN = "CV65"  !CDS_PN = "CV65";
"MFB_DQS_H8":   PN = "DD65"  !CDS_PN = "DD65";
"MFB_DQS_H9":   PN = "BV67"  !CDS_PN = "BV67";
"MFB_DQS_L0":   PN = "CE67"  !CDS_PN = "CE67";
"MFB_DQS_L1":   PN = "CL67"  !CDS_PN = "CL67";
"MFB_DQS_L2":   PN = "CU67"  !CDS_PN = "CU67";
"MFB_DQS_L3":   PN = "DC67"  !CDS_PN = "DC67";
"MFB_DQS_L4":   PN = "BW66"  !CDS_PN = "BW66";
"MFB_DQS_L5":   PN = "CE66"  !CDS_PN = "CE66";
"MFB_DQS_L6":   PN = "CL66"  !CDS_PN = "CL66";
"MFB_DQS_L7":   PN = "CU66"  !CDS_PN = "CU66";
"MFB_DQS_L8":   PN = "DC66"  !CDS_PN = "DC66";
"MFB_DQS_L9":   PN = "BW67"  !CDS_PN = "BW67";
"MFB_PAR":   PN = "BL67"  !CDS_PN = "BL67";
"TEST39F":   PN = "BF65"  !CDS_PN = "BF65";
BODY = "Q_RES","I314": #LOCATION = "R380" !CDS_LOCATION = "R380" &SEC = "1" #&CDS_SEC = "1";
"A":   PN = "1"  !CDS_PN = "1";
"B":   PN = "2"  !CDS_PN = "2";
DRAWING = "@t6g_mb_lib.t6g(sch_1):page16";
BODY = "GENOA_SP5","I167": #LOCATION = "U25" !CDS_LOCATION = "U25" &SEC = "7" #&CDS_SEC = "7";
"MG0_CLK_H":   PN = "BC2"  !CDS_PN = "BC2";
"MG0_CLK_L":   PN = "BD2"  !CDS_PN = "BD2";
"MG1_CLK_H":   PN = "BF2"  !CDS_PN = "BF2";
"MG1_CLK_L":   PN = "BG2"  !CDS_PN = "BG2";
"MG_ALERT_L":   PN = "AR2"  !CDS_PN = "AR2";
"MG_RESET_L":   PN = "AT2"  !CDS_PN = "AT2";
"MGA0_CS_L0":   PN = "AU2"  !CDS_PN = "AU2";
"MGA0_CS_L1":   PN = "AV4"  !CDS_PN = "AV4";
"MGA0_RSP_L":   PN = "BN3"  !CDS_PN = "BN3";
"MGA1_CS_L0":   PN = "AV2"  !CDS_PN = "AV2";
"MGA1_CS_L1":   PN = "AW3"  !CDS_PN = "AW3";
"MGA1_RSP_L":   PN = "BP4"  !CDS_PN = "BP4";
"MGA_CA0":   PN = "AW2"  !CDS_PN = "AW2";
"MGA_CA1":   PN = "AY2"  !CDS_PN = "AY2";
"MGA_CA2":   PN = "AY4"  !CDS_PN = "AY4";
"MGA_CA3":   PN = "BA3"  !CDS_PN = "BA3";
"MGA_CA4":   PN = "BA2"  !CDS_PN = "BA2";
"MGA_CA5":   PN = "BB2"  !CDS_PN = "BB2";
"MGA_CA6":   PN = "BB4"  !CDS_PN = "BB4";
"MGA_CHECK0":   PN = "AJ2"  !CDS_PN = "AJ2";
"MGA_CHECK1":   PN = "AK4"  !CDS_PN = "AK4";
"MGA_CHECK2":   PN = "AK2"  !CDS_PN = "AK2";
"MGA_CHECK3":   PN = "AL3"  !CDS_PN = "AL3";
"MGA_CHECK4":   PN = "AN2"  !CDS_PN = "AN2";
"MGA_CHECK5":   PN = "AP4"  !CDS_PN = "AP4";
"MGA_CHECK6":   PN = "AP2"  !CDS_PN = "AP2";
"MGA_CHECK7":   PN = "AR3"  !CDS_PN = "AR3";
"MGA_DATA0":   PN = "E2"  !CDS_PN = "E2";
"MGA_DATA1":   PN = "F4"  !CDS_PN = "F4";
"MGA_DATA2":   PN = "F2"  !CDS_PN = "F2";
"MGA_DATA3":   PN = "G3"  !CDS_PN = "G3";
"MGA_DATA4":   PN = "J2"  !CDS_PN = "J2";
"MGA_DATA5":   PN = "K4"  !CDS_PN = "K4";
"MGA_DATA6":   PN = "K2"  !CDS_PN = "K2";
"MGA_DATA7":   PN = "L3"  !CDS_PN = "L3";
"MGA_DATA8":   PN = "L2"  !CDS_PN = "L2";
"MGA_DATA9":   PN = "M4"  !CDS_PN = "M4";
"MGA_DATA10":   PN = "M2"  !CDS_PN = "M2";
"MGA_DATA11":   PN = "N3"  !CDS_PN = "N3";
"MGA_DATA12":   PN = "R2"  !CDS_PN = "R2";
"MGA_DATA13":   PN = "T4"  !CDS_PN = "T4";
"MGA_DATA14":   PN = "T2"  !CDS_PN = "T2";
"MGA_DATA15":   PN = "U3"  !CDS_PN = "U3";
"MGA_DATA16":   PN = "U2"  !CDS_PN = "U2";
"MGA_DATA17":   PN = "V4"  !CDS_PN = "V4";
"MGA_DATA18":   PN = "V2"  !CDS_PN = "V2";
"MGA_DATA19":   PN = "W3"  !CDS_PN = "W3";
"MGA_DATA20":   PN = "AA2"  !CDS_PN = "AA2";
"MGA_DATA21":   PN = "AB4"  !CDS_PN = "AB4";
"MGA_DATA22":   PN = "AB2"  !CDS_PN = "AB2";
"MGA_DATA23":   PN = "AC3"  !CDS_PN = "AC3";
"MGA_DATA24":   PN = "AC2"  !CDS_PN = "AC2";
"MGA_DATA25":   PN = "AD4"  !CDS_PN = "AD4";
"MGA_DATA26":   PN = "AD2"  !CDS_PN = "AD2";
"MGA_DATA27":   PN = "AE3"  !CDS_PN = "AE3";
"MGA_DATA28":   PN = "AG2"  !CDS_PN = "AG2";
"MGA_DATA29":   PN = "AH4"  !CDS_PN = "AH4";
"MGA_DATA30":   PN = "AH2"  !CDS_PN = "AH2";
"MGA_DATA31":   PN = "AJ3"  !CDS_PN = "AJ3";
"MGA_DQS_H0":   PN = "G2"  !CDS_PN = "G2";
"MGA_DQS_H1":   PN = "N2"  !CDS_PN = "N2";
"MGA_DQS_H2":   PN = "W2"  !CDS_PN = "W2";
"MGA_DQS_H3":   PN = "AE2"  !CDS_PN = "AE2";
"MGA_DQS_H4":   PN = "AL2"  !CDS_PN = "AL2";
"MGA_DQS_H5":   PN = "J3"  !CDS_PN = "J3";
"MGA_DQS_H6":   PN = "R3"  !CDS_PN = "R3";
"MGA_DQS_H7":   PN = "AA3"  !CDS_PN = "AA3";
"MGA_DQS_H8":   PN = "AG3"  !CDS_PN = "AG3";
"MGA_DQS_H9":   PN = "AN3"  !CDS_PN = "AN3";
"MGA_DQS_L0":   PN = "H2"  !CDS_PN = "H2";
"MGA_DQS_L1":   PN = "P2"  !CDS_PN = "P2";
"MGA_DQS_L2":   PN = "Y2"  !CDS_PN = "Y2";
"MGA_DQS_L3":   PN = "AF2"  !CDS_PN = "AF2";
"MGA_DQS_L4":   PN = "AM2"  !CDS_PN = "AM2";
"MGA_DQS_L5":   PN = "H4"  !CDS_PN = "H4";
"MGA_DQS_L6":   PN = "P4"  !CDS_PN = "P4";
"MGA_DQS_L7":   PN = "Y4"  !CDS_PN = "Y4";
"MGA_DQS_L8":   PN = "AF4"  !CDS_PN = "AF4";
"MGA_DQS_L9":   PN = "AM4"  !CDS_PN = "AM4";
"MGA_PAR":   PN = "BC3"  !CDS_PN = "BC3";
"MGB0_CS_L0":   PN = "BM4"  !CDS_PN = "BM4";
"MGB0_CS_L1":   PN = "BN2"  !CDS_PN = "BN2";
"MGB0_RSP_L":   PN = "BP2"  !CDS_PN = "BP2";
"MGB1_CS_L0":   PN = "BL2"  !CDS_PN = "BL2";
"MGB1_CS_L1":   PN = "BM2"  !CDS_PN = "BM2";
"MGB1_RSP_L":   PN = "BR2"  !CDS_PN = "BR2";
"MGB_CA0":   PN = "BG3"  !CDS_PN = "BG3";
"MGB_CA1":   PN = "BH4"  !CDS_PN = "BH4";
"MGB_CA2":   PN = "BH2"  !CDS_PN = "BH2";
"MGB_CA3":   PN = "BJ2"  !CDS_PN = "BJ2";
"MGB_CA4":   PN = "BJ3"  !CDS_PN = "BJ3";
"MGB_CA5":   PN = "BK4"  !CDS_PN = "BK4";
"MGB_CA6":   PN = "BK2"  !CDS_PN = "BK2";
"MGB_CHECK0":   PN = "BY2"  !CDS_PN = "BY2";
"MGB_CHECK1":   PN = "CA3"  !CDS_PN = "CA3";
"MGB_CHECK2":   PN = "CA2"  !CDS_PN = "CA2";
"MGB_CHECK3":   PN = "CB4"  !CDS_PN = "CB4";
"MGB_CHECK4":   PN = "BT2"  !CDS_PN = "BT2";
"MGB_CHECK5":   PN = "BU3"  !CDS_PN = "BU3";
"MGB_CHECK6":   PN = "BU2"  !CDS_PN = "BU2";
"MGB_CHECK7":   PN = "BV4"  !CDS_PN = "BV4";
"MGB_DATA0":   PN = "CB2"  !CDS_PN = "CB2";
"MGB_DATA1":   PN = "CC3"  !CDS_PN = "CC3";
"MGB_DATA2":   PN = "CC2"  !CDS_PN = "CC2";
"MGB_DATA3":   PN = "CD4"  !CDS_PN = "CD4";
"MGB_DATA4":   PN = "CF2"  !CDS_PN = "CF2";
"MGB_DATA5":   PN = "CG3"  !CDS_PN = "CG3";
"MGB_DATA6":   PN = "CG2"  !CDS_PN = "CG2";
"MGB_DATA7":   PN = "CH4"  !CDS_PN = "CH4";
"MGB_DATA8":   PN = "CH2"  !CDS_PN = "CH2";
"MGB_DATA9":   PN = "CJ3"  !CDS_PN = "CJ3";
"MGB_DATA10":   PN = "CJ2"  !CDS_PN = "CJ2";
"MGB_DATA11":   PN = "CK4"  !CDS_PN = "CK4";
"MGB_DATA12":   PN = "CM2"  !CDS_PN = "CM2";
"MGB_DATA13":   PN = "CN3"  !CDS_PN = "CN3";
"MGB_DATA14":   PN = "CN2"  !CDS_PN = "CN2";
"MGB_DATA15":   PN = "CP4"  !CDS_PN = "CP4";
"MGB_DATA16":   PN = "CP2"  !CDS_PN = "CP2";
"MGB_DATA17":   PN = "CR3"  !CDS_PN = "CR3";
"MGB_DATA18":   PN = "CR2"  !CDS_PN = "CR2";
"MGB_DATA19":   PN = "CT4"  !CDS_PN = "CT4";
"MGB_DATA20":   PN = "CV2"  !CDS_PN = "CV2";
"MGB_DATA21":   PN = "CW3"  !CDS_PN = "CW3";
"MGB_DATA22":   PN = "CW2"  !CDS_PN = "CW2";
"MGB_DATA23":   PN = "CY4"  !CDS_PN = "CY4";
"MGB_DATA24":   PN = "CY2"  !CDS_PN = "CY2";
"MGB_DATA25":   PN = "DA3"  !CDS_PN = "DA3";
"MGB_DATA26":   PN = "DA2"  !CDS_PN = "DA2";
"MGB_DATA27":   PN = "DB4"  !CDS_PN = "DB4";
"MGB_DATA28":   PN = "DD2"  !CDS_PN = "DD2";
"MGB_DATA29":   PN = "DE3"  !CDS_PN = "DE3";
"MGB_DATA30":   PN = "DE2"  !CDS_PN = "DE2";
"MGB_DATA31":   PN = "DF2"  !CDS_PN = "DF2";
"MGB_DQS_H0":   PN = "CD2"  !CDS_PN = "CD2";
"MGB_DQS_H1":   PN = "CK2"  !CDS_PN = "CK2";
"MGB_DQS_H2":   PN = "CT2"  !CDS_PN = "CT2";
"MGB_DQS_H3":   PN = "DB2"  !CDS_PN = "DB2";
"MGB_DQS_H4":   PN = "BY4"  !CDS_PN = "BY4";
"MGB_DQS_H5":   PN = "CF4"  !CDS_PN = "CF4";
"MGB_DQS_H6":   PN = "CM4"  !CDS_PN = "CM4";
"MGB_DQS_H7":   PN = "CV4"  !CDS_PN = "CV4";
"MGB_DQS_H8":   PN = "DD4"  !CDS_PN = "DD4";
"MGB_DQS_H9":   PN = "BV2"  !CDS_PN = "BV2";
"MGB_DQS_L0":   PN = "CE2"  !CDS_PN = "CE2";
"MGB_DQS_L1":   PN = "CL2"  !CDS_PN = "CL2";
"MGB_DQS_L2":   PN = "CU2"  !CDS_PN = "CU2";
"MGB_DQS_L3":   PN = "DC2"  !CDS_PN = "DC2";
"MGB_DQS_L4":   PN = "BW3"  !CDS_PN = "BW3";
"MGB_DQS_L5":   PN = "CE3"  !CDS_PN = "CE3";
"MGB_DQS_L6":   PN = "CL3"  !CDS_PN = "CL3";
"MGB_DQS_L7":   PN = "CU3"  !CDS_PN = "CU3";
"MGB_DQS_L8":   PN = "DC3"  !CDS_PN = "DC3";
"MGB_DQS_L9":   PN = "BW2"  !CDS_PN = "BW2";
"MGB_PAR":   PN = "BL3"  !CDS_PN = "BL3";
"TEST39G":   PN = "BF4"  !CDS_PN = "BF4";
BODY = "Q_RES","I323": #LOCATION = "R381" !CDS_LOCATION = "R381" &SEC = "1" #&CDS_SEC = "1";
"A":   PN = "1"  !CDS_PN = "1";
"B":   PN = "2"  !CDS_PN = "2";
DRAWING = "@t6g_mb_lib.t6g(sch_1):page17";
BODY = "GENOA_SP5","I159": #LOCATION = "U25" !CDS_LOCATION = "U25" &SEC = "8" #&CDS_SEC = "8";
"MH0_CLK_H":   PN = "BC12"  !CDS_PN = "BC12";
"MH0_CLK_L":   PN = "BD13"  !CDS_PN = "BD13";
"MH1_CLK_H":   PN = "BF13"  !CDS_PN = "BF13";
"MH1_CLK_L":   PN = "BG12"  !CDS_PN = "BG12";
"MH_ALERT_L":   PN = "AT14"  !CDS_PN = "AT14";
"MH_RESET_L":   PN = "AU14"  !CDS_PN = "AU14";
"MHA0_CS_L0":   PN = "AU12"  !CDS_PN = "AU12";
"MHA0_CS_L1":   PN = "AV14"  !CDS_PN = "AV14";
"MHA0_RSP_L":   PN = "BN14"  !CDS_PN = "BN14";
"MHA1_CS_L0":   PN = "AV13"  !CDS_PN = "AV13";
"MHA1_CS_L1":   PN = "AW14"  !CDS_PN = "AW14";
"MHA1_RSP_L":   PN = "BP14"  !CDS_PN = "BP14";
"MHA_CA0":   PN = "AW12"  !CDS_PN = "AW12";
"MHA_CA1":   PN = "AY13"  !CDS_PN = "AY13";
"MHA_CA2":   PN = "AY14"  !CDS_PN = "AY14";
"MHA_CA3":   PN = "BA14"  !CDS_PN = "BA14";
"MHA_CA4":   PN = "BA12"  !CDS_PN = "BA12";
"MHA_CA5":   PN = "BB13"  !CDS_PN = "BB13";
"MHA_CA6":   PN = "BB14"  !CDS_PN = "BB14";
"MHA_CHECK0":   PN = "AJ12"  !CDS_PN = "AJ12";
"MHA_CHECK1":   PN = "AK14"  !CDS_PN = "AK14";
"MHA_CHECK2":   PN = "AK13"  !CDS_PN = "AK13";
"MHA_CHECK3":   PN = "AL14"  !CDS_PN = "AL14";
"MHA_CHECK4":   PN = "AN12"  !CDS_PN = "AN12";
"MHA_CHECK5":   PN = "AP14"  !CDS_PN = "AP14";
"MHA_CHECK6":   PN = "AP13"  !CDS_PN = "AP13";
"MHA_CHECK7":   PN = "AR14"  !CDS_PN = "AR14";
"MHA_DATA0":   PN = "E12"  !CDS_PN = "E12";
"MHA_DATA1":   PN = "F14"  !CDS_PN = "F14";
"MHA_DATA2":   PN = "F13"  !CDS_PN = "F13";
"MHA_DATA3":   PN = "G14"  !CDS_PN = "G14";
"MHA_DATA4":   PN = "J12"  !CDS_PN = "J12";
"MHA_DATA5":   PN = "K14"  !CDS_PN = "K14";
"MHA_DATA6":   PN = "K13"  !CDS_PN = "K13";
"MHA_DATA7":   PN = "L14"  !CDS_PN = "L14";
"MHA_DATA8":   PN = "L12"  !CDS_PN = "L12";
"MHA_DATA9":   PN = "M14"  !CDS_PN = "M14";
"MHA_DATA10":   PN = "M13"  !CDS_PN = "M13";
"MHA_DATA11":   PN = "N14"  !CDS_PN = "N14";
"MHA_DATA12":   PN = "R12"  !CDS_PN = "R12";
"MHA_DATA13":   PN = "T14"  !CDS_PN = "T14";
"MHA_DATA14":   PN = "T13"  !CDS_PN = "T13";
"MHA_DATA15":   PN = "U14"  !CDS_PN = "U14";
"MHA_DATA16":   PN = "U12"  !CDS_PN = "U12";
"MHA_DATA17":   PN = "V14"  !CDS_PN = "V14";
"MHA_DATA18":   PN = "V13"  !CDS_PN = "V13";
"MHA_DATA19":   PN = "W14"  !CDS_PN = "W14";
"MHA_DATA20":   PN = "AA12"  !CDS_PN = "AA12";
"MHA_DATA21":   PN = "AB14"  !CDS_PN = "AB14";
"MHA_DATA22":   PN = "AB13"  !CDS_PN = "AB13";
"MHA_DATA23":   PN = "AC14"  !CDS_PN = "AC14";
"MHA_DATA24":   PN = "AC12"  !CDS_PN = "AC12";
"MHA_DATA25":   PN = "AD14"  !CDS_PN = "AD14";
"MHA_DATA26":   PN = "AD13"  !CDS_PN = "AD13";
"MHA_DATA27":   PN = "AE14"  !CDS_PN = "AE14";
"MHA_DATA28":   PN = "AG12"  !CDS_PN = "AG12";
"MHA_DATA29":   PN = "AH14"  !CDS_PN = "AH14";
"MHA_DATA30":   PN = "AH13"  !CDS_PN = "AH13";
"MHA_DATA31":   PN = "AJ14"  !CDS_PN = "AJ14";
"MHA_DQS_H0":   PN = "G12"  !CDS_PN = "G12";
"MHA_DQS_H1":   PN = "N12"  !CDS_PN = "N12";
"MHA_DQS_H2":   PN = "W12"  !CDS_PN = "W12";
"MHA_DQS_H3":   PN = "AE12"  !CDS_PN = "AE12";
"MHA_DQS_H4":   PN = "AL12"  !CDS_PN = "AL12";
"MHA_DQS_H5":   PN = "J14"  !CDS_PN = "J14";
"MHA_DQS_H6":   PN = "R14"  !CDS_PN = "R14";
"MHA_DQS_H7":   PN = "AA14"  !CDS_PN = "AA14";
"MHA_DQS_H8":   PN = "AG14"  !CDS_PN = "AG14";
"MHA_DQS_H9":   PN = "AN14"  !CDS_PN = "AN14";
"MHA_DQS_L0":   PN = "H13"  !CDS_PN = "H13";
"MHA_DQS_L1":   PN = "P13"  !CDS_PN = "P13";
"MHA_DQS_L2":   PN = "Y13"  !CDS_PN = "Y13";
"MHA_DQS_L3":   PN = "AF13"  !CDS_PN = "AF13";
"MHA_DQS_L4":   PN = "AM13"  !CDS_PN = "AM13";
"MHA_DQS_L5":   PN = "H14"  !CDS_PN = "H14";
"MHA_DQS_L6":   PN = "P14"  !CDS_PN = "P14";
"MHA_DQS_L7":   PN = "Y14"  !CDS_PN = "Y14";
"MHA_DQS_L8":   PN = "AF14"  !CDS_PN = "AF14";
"MHA_DQS_L9":   PN = "AM14"  !CDS_PN = "AM14";
"MHA_PAR":   PN = "BC14"  !CDS_PN = "BC14";
"MHB0_CS_L0":   PN = "BM14"  !CDS_PN = "BM14";
"MHB0_CS_L1":   PN = "BN12"  !CDS_PN = "BN12";
"MHB0_RSP_L":   PN = "BP13"  !CDS_PN = "BP13";
"MHB1_CS_L0":   PN = "BL12"  !CDS_PN = "BL12";
"MHB1_CS_L1":   PN = "BM13"  !CDS_PN = "BM13";
"MHB1_RSP_L":   PN = "BR12"  !CDS_PN = "BR12";
"MHB_CA0":   PN = "BG14"  !CDS_PN = "BG14";
"MHB_CA1":   PN = "BH14"  !CDS_PN = "BH14";
"MHB_CA2":   PN = "BH13"  !CDS_PN = "BH13";
"MHB_CA3":   PN = "BJ12"  !CDS_PN = "BJ12";
"MHB_CA4":   PN = "BJ14"  !CDS_PN = "BJ14";
"MHB_CA5":   PN = "BK14"  !CDS_PN = "BK14";
"MHB_CA6":   PN = "BK13"  !CDS_PN = "BK13";
"MHB_CHECK0":   PN = "BY13"  !CDS_PN = "BY13";
"MHB_CHECK1":   PN = "CA14"  !CDS_PN = "CA14";
"MHB_CHECK2":   PN = "CA12"  !CDS_PN = "CA12";
"MHB_CHECK3":   PN = "CB14"  !CDS_PN = "CB14";
"MHB_CHECK4":   PN = "BT13"  !CDS_PN = "BT13";
"MHB_CHECK5":   PN = "BU14"  !CDS_PN = "BU14";
"MHB_CHECK6":   PN = "BU12"  !CDS_PN = "BU12";
"MHB_CHECK7":   PN = "BV14"  !CDS_PN = "BV14";
"MHB_DATA0":   PN = "CB13"  !CDS_PN = "CB13";
"MHB_DATA1":   PN = "CC14"  !CDS_PN = "CC14";
"MHB_DATA2":   PN = "CC12"  !CDS_PN = "CC12";
"MHB_DATA3":   PN = "CD14"  !CDS_PN = "CD14";
"MHB_DATA4":   PN = "CF13"  !CDS_PN = "CF13";
"MHB_DATA5":   PN = "CG14"  !CDS_PN = "CG14";
"MHB_DATA6":   PN = "CG12"  !CDS_PN = "CG12";
"MHB_DATA7":   PN = "CH14"  !CDS_PN = "CH14";
"MHB_DATA8":   PN = "CH13"  !CDS_PN = "CH13";
"MHB_DATA9":   PN = "CJ14"  !CDS_PN = "CJ14";
"MHB_DATA10":   PN = "CJ12"  !CDS_PN = "CJ12";
"MHB_DATA11":   PN = "CK14"  !CDS_PN = "CK14";
"MHB_DATA12":   PN = "CM13"  !CDS_PN = "CM13";
"MHB_DATA13":   PN = "CN14"  !CDS_PN = "CN14";
"MHB_DATA14":   PN = "CN12"  !CDS_PN = "CN12";
"MHB_DATA15":   PN = "CP14"  !CDS_PN = "CP14";
"MHB_DATA16":   PN = "CP13"  !CDS_PN = "CP13";
"MHB_DATA17":   PN = "CR14"  !CDS_PN = "CR14";
"MHB_DATA18":   PN = "CR12"  !CDS_PN = "CR12";
"MHB_DATA19":   PN = "CT14"  !CDS_PN = "CT14";
"MHB_DATA20":   PN = "CV13"  !CDS_PN = "CV13";
"MHB_DATA21":   PN = "CW14"  !CDS_PN = "CW14";
"MHB_DATA22":   PN = "CW12"  !CDS_PN = "CW12";
"MHB_DATA23":   PN = "CY14"  !CDS_PN = "CY14";
"MHB_DATA24":   PN = "CY13"  !CDS_PN = "CY13";
"MHB_DATA25":   PN = "DA14"  !CDS_PN = "DA14";
"MHB_DATA26":   PN = "DA12"  !CDS_PN = "DA12";
"MHB_DATA27":   PN = "DB14"  !CDS_PN = "DB14";
"MHB_DATA28":   PN = "DD13"  !CDS_PN = "DD13";
"MHB_DATA29":   PN = "DE14"  !CDS_PN = "DE14";
"MHB_DATA30":   PN = "DE12"  !CDS_PN = "DE12";
"MHB_DATA31":   PN = "DF14"  !CDS_PN = "DF14";
"MHB_DQS_H0":   PN = "CD13"  !CDS_PN = "CD13";
"MHB_DQS_H1":   PN = "CK13"  !CDS_PN = "CK13";
"MHB_DQS_H2":   PN = "CT13"  !CDS_PN = "CT13";
"MHB_DQS_H3":   PN = "DB13"  !CDS_PN = "DB13";
"MHB_DQS_H4":   PN = "BY14"  !CDS_PN = "BY14";
"MHB_DQS_H5":   PN = "CF14"  !CDS_PN = "CF14";
"MHB_DQS_H6":   PN = "CM14"  !CDS_PN = "CM14";
"MHB_DQS_H7":   PN = "CV14"  !CDS_PN = "CV14";
"MHB_DQS_H8":   PN = "DD14"  !CDS_PN = "DD14";
"MHB_DQS_H9":   PN = "BV13"  !CDS_PN = "BV13";
"MHB_DQS_L0":   PN = "CE12"  !CDS_PN = "CE12";
"MHB_DQS_L1":   PN = "CL12"  !CDS_PN = "CL12";
"MHB_DQS_L2":   PN = "CU12"  !CDS_PN = "CU12";
"MHB_DQS_L3":   PN = "DC12"  !CDS_PN = "DC12";
"MHB_DQS_L4":   PN = "BW14"  !CDS_PN = "BW14";
"MHB_DQS_L5":   PN = "CE14"  !CDS_PN = "CE14";
"MHB_DQS_L6":   PN = "CL14"  !CDS_PN = "CL14";
"MHB_DQS_L7":   PN = "CU14"  !CDS_PN = "CU14";
"MHB_DQS_L8":   PN = "DC14"  !CDS_PN = "DC14";
"MHB_DQS_L9":   PN = "BW12"  !CDS_PN = "BW12";
"MHB_PAR":   PN = "BL14"  !CDS_PN = "BL14";
"TEST39H":   PN = "BF14"  !CDS_PN = "BF14";
BODY = "Q_RES","I314": #LOCATION = "R382" !CDS_LOCATION = "R382" &SEC = "1" #&CDS_SEC = "1";
"A":   PN = "1"  !CDS_PN = "1";
"B":   PN = "2"  !CDS_PN = "2";
DRAWING = "@t6g_mb_lib.t6g(sch_1):page18";
BODY = "GENOA_SP5","I159": #LOCATION = "U25" !CDS_LOCATION = "U25" &SEC = "9" #&CDS_SEC = "9";
"MI0_CLK_H":   PN = "BC19"  !CDS_PN = "BC19";
"MI0_CLK_L":   PN = "BD20"  !CDS_PN = "BD20";
"MI1_CLK_H":   PN = "BF20"  !CDS_PN = "BF20";
"MI1_CLK_L":   PN = "BG19"  !CDS_PN = "BG19";
"MI_ALERT_L":   PN = "AT21"  !CDS_PN = "AT21";
"MI_RESET_L":   PN = "AU21"  !CDS_PN = "AU21";
"MIA0_CS_L0":   PN = "AU19"  !CDS_PN = "AU19";
"MIA0_CS_L1":   PN = "AV21"  !CDS_PN = "AV21";
"MIA0_RSP_L":   PN = "BN21"  !CDS_PN = "BN21";
"MIA1_CS_L0":   PN = "AV20"  !CDS_PN = "AV20";
"MIA1_CS_L1":   PN = "AW21"  !CDS_PN = "AW21";
"MIA1_RSP_L":   PN = "BP21"  !CDS_PN = "BP21";
"MIA_CA0":   PN = "AW19"  !CDS_PN = "AW19";
"MIA_CA1":   PN = "AY20"  !CDS_PN = "AY20";
"MIA_CA2":   PN = "AY21"  !CDS_PN = "AY21";
"MIA_CA3":   PN = "BA21"  !CDS_PN = "BA21";
"MIA_CA4":   PN = "BA19"  !CDS_PN = "BA19";
"MIA_CA5":   PN = "BB20"  !CDS_PN = "BB20";
"MIA_CA6":   PN = "BB21"  !CDS_PN = "BB21";
"MIA_CHECK0":   PN = "AJ19"  !CDS_PN = "AJ19";
"MIA_CHECK1":   PN = "AK21"  !CDS_PN = "AK21";
"MIA_CHECK2":   PN = "AK20"  !CDS_PN = "AK20";
"MIA_CHECK3":   PN = "AL21"  !CDS_PN = "AL21";
"MIA_CHECK4":   PN = "AN19"  !CDS_PN = "AN19";
"MIA_CHECK5":   PN = "AP21"  !CDS_PN = "AP21";
"MIA_CHECK6":   PN = "AP20"  !CDS_PN = "AP20";
"MIA_CHECK7":   PN = "AR21"  !CDS_PN = "AR21";
"MIA_DATA0":   PN = "E19"  !CDS_PN = "E19";
"MIA_DATA1":   PN = "F21"  !CDS_PN = "F21";
"MIA_DATA2":   PN = "F20"  !CDS_PN = "F20";
"MIA_DATA3":   PN = "G21"  !CDS_PN = "G21";
"MIA_DATA4":   PN = "J19"  !CDS_PN = "J19";
"MIA_DATA5":   PN = "K21"  !CDS_PN = "K21";
"MIA_DATA6":   PN = "K20"  !CDS_PN = "K20";
"MIA_DATA7":   PN = "L21"  !CDS_PN = "L21";
"MIA_DATA8":   PN = "L19"  !CDS_PN = "L19";
"MIA_DATA9":   PN = "M21"  !CDS_PN = "M21";
"MIA_DATA10":   PN = "M20"  !CDS_PN = "M20";
"MIA_DATA11":   PN = "N21"  !CDS_PN = "N21";
"MIA_DATA12":   PN = "R19"  !CDS_PN = "R19";
"MIA_DATA13":   PN = "T21"  !CDS_PN = "T21";
"MIA_DATA14":   PN = "T20"  !CDS_PN = "T20";
"MIA_DATA15":   PN = "U21"  !CDS_PN = "U21";
"MIA_DATA16":   PN = "U19"  !CDS_PN = "U19";
"MIA_DATA17":   PN = "V21"  !CDS_PN = "V21";
"MIA_DATA18":   PN = "V20"  !CDS_PN = "V20";
"MIA_DATA19":   PN = "W21"  !CDS_PN = "W21";
"MIA_DATA20":   PN = "AA19"  !CDS_PN = "AA19";
"MIA_DATA21":   PN = "AB21"  !CDS_PN = "AB21";
"MIA_DATA22":   PN = "AB20"  !CDS_PN = "AB20";
"MIA_DATA23":   PN = "AC21"  !CDS_PN = "AC21";
"MIA_DATA24":   PN = "AC19"  !CDS_PN = "AC19";
"MIA_DATA25":   PN = "AD21"  !CDS_PN = "AD21";
"MIA_DATA26":   PN = "AD20"  !CDS_PN = "AD20";
"MIA_DATA27":   PN = "AE21"  !CDS_PN = "AE21";
"MIA_DATA28":   PN = "AG19"  !CDS_PN = "AG19";
"MIA_DATA29":   PN = "AH21"  !CDS_PN = "AH21";
"MIA_DATA30":   PN = "AH20"  !CDS_PN = "AH20";
"MIA_DATA31":   PN = "AJ21"  !CDS_PN = "AJ21";
"MIA_DQS_H0":   PN = "G19"  !CDS_PN = "G19";
"MIA_DQS_H1":   PN = "N19"  !CDS_PN = "N19";
"MIA_DQS_H2":   PN = "W19"  !CDS_PN = "W19";
"MIA_DQS_H3":   PN = "AE19"  !CDS_PN = "AE19";
"MIA_DQS_H4":   PN = "AL19"  !CDS_PN = "AL19";
"MIA_DQS_H5":   PN = "J21"  !CDS_PN = "J21";
"MIA_DQS_H6":   PN = "R21"  !CDS_PN = "R21";
"MIA_DQS_H7":   PN = "AA21"  !CDS_PN = "AA21";
"MIA_DQS_H8":   PN = "AG21"  !CDS_PN = "AG21";
"MIA_DQS_H9":   PN = "AN21"  !CDS_PN = "AN21";
"MIA_DQS_L0":   PN = "H20"  !CDS_PN = "H20";
"MIA_DQS_L1":   PN = "P20"  !CDS_PN = "P20";
"MIA_DQS_L2":   PN = "Y20"  !CDS_PN = "Y20";
"MIA_DQS_L3":   PN = "AF20"  !CDS_PN = "AF20";
"MIA_DQS_L4":   PN = "AM20"  !CDS_PN = "AM20";
"MIA_DQS_L5":   PN = "H21"  !CDS_PN = "H21";
"MIA_DQS_L6":   PN = "P21"  !CDS_PN = "P21";
"MIA_DQS_L7":   PN = "Y21"  !CDS_PN = "Y21";
"MIA_DQS_L8":   PN = "AF21"  !CDS_PN = "AF21";
"MIA_DQS_L9":   PN = "AM21"  !CDS_PN = "AM21";
"MIA_PAR":   PN = "BC21"  !CDS_PN = "BC21";
"MIB0_CS_L0":   PN = "BM21"  !CDS_PN = "BM21";
"MIB0_CS_L1":   PN = "BN19"  !CDS_PN = "BN19";
"MIB0_RSP_L":   PN = "BP20"  !CDS_PN = "BP20";
"MIB1_CS_L0":   PN = "BL19"  !CDS_PN = "BL19";
"MIB1_CS_L1":   PN = "BM20"  !CDS_PN = "BM20";
"MIB1_RSP_L":   PN = "BR19"  !CDS_PN = "BR19";
"MIB_CA0":   PN = "BG21"  !CDS_PN = "BG21";
"MIB_CA1":   PN = "BH21"  !CDS_PN = "BH21";
"MIB_CA2":   PN = "BH20"  !CDS_PN = "BH20";
"MIB_CA3":   PN = "BJ19"  !CDS_PN = "BJ19";
"MIB_CA4":   PN = "BJ21"  !CDS_PN = "BJ21";
"MIB_CA5":   PN = "BK21"  !CDS_PN = "BK21";
"MIB_CA6":   PN = "BK20"  !CDS_PN = "BK20";
"MIB_CHECK0":   PN = "BY20"  !CDS_PN = "BY20";
"MIB_CHECK1":   PN = "CA21"  !CDS_PN = "CA21";
"MIB_CHECK2":   PN = "CA19"  !CDS_PN = "CA19";
"MIB_CHECK3":   PN = "CB21"  !CDS_PN = "CB21";
"MIB_CHECK4":   PN = "BT20"  !CDS_PN = "BT20";
"MIB_CHECK5":   PN = "BU21"  !CDS_PN = "BU21";
"MIB_CHECK6":   PN = "BU19"  !CDS_PN = "BU19";
"MIB_CHECK7":   PN = "BV21"  !CDS_PN = "BV21";
"MIB_DATA0":   PN = "CB20"  !CDS_PN = "CB20";
"MIB_DATA1":   PN = "CC21"  !CDS_PN = "CC21";
"MIB_DATA2":   PN = "CC19"  !CDS_PN = "CC19";
"MIB_DATA3":   PN = "CD21"  !CDS_PN = "CD21";
"MIB_DATA4":   PN = "CF20"  !CDS_PN = "CF20";
"MIB_DATA5":   PN = "CG21"  !CDS_PN = "CG21";
"MIB_DATA6":   PN = "CG19"  !CDS_PN = "CG19";
"MIB_DATA7":   PN = "CH21"  !CDS_PN = "CH21";
"MIB_DATA8":   PN = "CH20"  !CDS_PN = "CH20";
"MIB_DATA9":   PN = "CJ21"  !CDS_PN = "CJ21";
"MIB_DATA10":   PN = "CJ19"  !CDS_PN = "CJ19";
"MIB_DATA11":   PN = "CK21"  !CDS_PN = "CK21";
"MIB_DATA12":   PN = "CM20"  !CDS_PN = "CM20";
"MIB_DATA13":   PN = "CN21"  !CDS_PN = "CN21";
"MIB_DATA14":   PN = "CN19"  !CDS_PN = "CN19";
"MIB_DATA15":   PN = "CP21"  !CDS_PN = "CP21";
"MIB_DATA16":   PN = "CP20"  !CDS_PN = "CP20";
"MIB_DATA17":   PN = "CR21"  !CDS_PN = "CR21";
"MIB_DATA18":   PN = "CR19"  !CDS_PN = "CR19";
"MIB_DATA19":   PN = "CT21"  !CDS_PN = "CT21";
"MIB_DATA20":   PN = "CV20"  !CDS_PN = "CV20";
"MIB_DATA21":   PN = "CW21"  !CDS_PN = "CW21";
"MIB_DATA22":   PN = "CW19"  !CDS_PN = "CW19";
"MIB_DATA23":   PN = "CY21"  !CDS_PN = "CY21";
"MIB_DATA24":   PN = "CY20"  !CDS_PN = "CY20";
"MIB_DATA25":   PN = "DA21"  !CDS_PN = "DA21";
"MIB_DATA26":   PN = "DA19"  !CDS_PN = "DA19";
"MIB_DATA27":   PN = "DB21"  !CDS_PN = "DB21";
"MIB_DATA28":   PN = "DD20"  !CDS_PN = "DD20";
"MIB_DATA29":   PN = "DE21"  !CDS_PN = "DE21";
"MIB_DATA30":   PN = "DE19"  !CDS_PN = "DE19";
"MIB_DATA31":   PN = "DF21"  !CDS_PN = "DF21";
"MIB_DQS_H0":   PN = "CD20"  !CDS_PN = "CD20";
"MIB_DQS_H1":   PN = "CK20"  !CDS_PN = "CK20";
"MIB_DQS_H2":   PN = "CT20"  !CDS_PN = "CT20";
"MIB_DQS_H3":   PN = "DB20"  !CDS_PN = "DB20";
"MIB_DQS_H4":   PN = "BY21"  !CDS_PN = "BY21";
"MIB_DQS_H5":   PN = "CF21"  !CDS_PN = "CF21";
"MIB_DQS_H6":   PN = "CM21"  !CDS_PN = "CM21";
"MIB_DQS_H7":   PN = "CV21"  !CDS_PN = "CV21";
"MIB_DQS_H8":   PN = "DD21"  !CDS_PN = "DD21";
"MIB_DQS_H9":   PN = "BV20"  !CDS_PN = "BV20";
"MIB_DQS_L0":   PN = "CE19"  !CDS_PN = "CE19";
"MIB_DQS_L1":   PN = "CL19"  !CDS_PN = "CL19";
"MIB_DQS_L2":   PN = "CU19"  !CDS_PN = "CU19";
"MIB_DQS_L3":   PN = "DC19"  !CDS_PN = "DC19";
"MIB_DQS_L4":   PN = "BW21"  !CDS_PN = "BW21";
"MIB_DQS_L5":   PN = "CE21"  !CDS_PN = "CE21";
"MIB_DQS_L6":   PN = "CL21"  !CDS_PN = "CL21";
"MIB_DQS_L7":   PN = "CU21"  !CDS_PN = "CU21";
"MIB_DQS_L8":   PN = "DC21"  !CDS_PN = "DC21";
"MIB_DQS_L9":   PN = "BW19"  !CDS_PN = "BW19";
"MIB_PAR":   PN = "BL21"  !CDS_PN = "BL21";
"TEST39I":   PN = "BF21"  !CDS_PN = "BF21";
BODY = "Q_RES","I314": #LOCATION = "R383" !CDS_LOCATION = "R383" &SEC = "1" #&CDS_SEC = "1";
"A":   PN = "1"  !CDS_PN = "1";
"B":   PN = "2"  !CDS_PN = "2";
DRAWING = "@t6g_mb_lib.t6g(sch_1):page19";
BODY = "GENOA_SP5","I159": #LOCATION = "U25" !CDS_LOCATION = "U25" &SEC = "10" #&CDS_SEC = "10";
"MJ0_CLK_H":   PN = "BC16"  !CDS_PN = "BC16";
"MJ0_CLK_L":   PN = "BD16"  !CDS_PN = "BD16";
"MJ1_CLK_H":   PN = "BF16"  !CDS_PN = "BF16";
"MJ1_CLK_L":   PN = "BG16"  !CDS_PN = "BG16";
"MJ_ALERT_L":   PN = "AT18"  !CDS_PN = "AT18";
"MJ_RESET_L":   PN = "AU17"  !CDS_PN = "AU17";
"MJA0_CS_L0":   PN = "AU16"  !CDS_PN = "AU16";
"MJA0_CS_L1":   PN = "AV18"  !CDS_PN = "AV18";
"MJA0_RSP_L":   PN = "BN17"  !CDS_PN = "BN17";
"MJA1_CS_L0":   PN = "AV16"  !CDS_PN = "AV16";
"MJA1_CS_L1":   PN = "AW17"  !CDS_PN = "AW17";
"MJA1_RSP_L":   PN = "BP18"  !CDS_PN = "BP18";
"MJA_CA0":   PN = "AW16"  !CDS_PN = "AW16";
"MJA_CA1":   PN = "AY16"  !CDS_PN = "AY16";
"MJA_CA2":   PN = "AY18"  !CDS_PN = "AY18";
"MJA_CA3":   PN = "BA17"  !CDS_PN = "BA17";
"MJA_CA4":   PN = "BA16"  !CDS_PN = "BA16";
"MJA_CA5":   PN = "BB16"  !CDS_PN = "BB16";
"MJA_CA6":   PN = "BB18"  !CDS_PN = "BB18";
"MJA_CHECK0":   PN = "AJ16"  !CDS_PN = "AJ16";
"MJA_CHECK1":   PN = "AK18"  !CDS_PN = "AK18";
"MJA_CHECK2":   PN = "AK16"  !CDS_PN = "AK16";
"MJA_CHECK3":   PN = "AL17"  !CDS_PN = "AL17";
"MJA_CHECK4":   PN = "AN16"  !CDS_PN = "AN16";
"MJA_CHECK5":   PN = "AP18"  !CDS_PN = "AP18";
"MJA_CHECK6":   PN = "AP16"  !CDS_PN = "AP16";
"MJA_CHECK7":   PN = "AR17"  !CDS_PN = "AR17";
"MJA_DATA0":   PN = "E16"  !CDS_PN = "E16";
"MJA_DATA1":   PN = "F18"  !CDS_PN = "F18";
"MJA_DATA2":   PN = "F16"  !CDS_PN = "F16";
"MJA_DATA3":   PN = "G17"  !CDS_PN = "G17";
"MJA_DATA4":   PN = "J16"  !CDS_PN = "J16";
"MJA_DATA5":   PN = "K18"  !CDS_PN = "K18";
"MJA_DATA6":   PN = "K16"  !CDS_PN = "K16";
"MJA_DATA7":   PN = "L17"  !CDS_PN = "L17";
"MJA_DATA8":   PN = "L16"  !CDS_PN = "L16";
"MJA_DATA9":   PN = "M18"  !CDS_PN = "M18";
"MJA_DATA10":   PN = "M16"  !CDS_PN = "M16";
"MJA_DATA11":   PN = "N17"  !CDS_PN = "N17";
"MJA_DATA12":   PN = "R16"  !CDS_PN = "R16";
"MJA_DATA13":   PN = "T18"  !CDS_PN = "T18";
"MJA_DATA14":   PN = "T16"  !CDS_PN = "T16";
"MJA_DATA15":   PN = "U17"  !CDS_PN = "U17";
"MJA_DATA16":   PN = "U16"  !CDS_PN = "U16";
"MJA_DATA17":   PN = "V18"  !CDS_PN = "V18";
"MJA_DATA18":   PN = "V16"  !CDS_PN = "V16";
"MJA_DATA19":   PN = "W17"  !CDS_PN = "W17";
"MJA_DATA20":   PN = "AA16"  !CDS_PN = "AA16";
"MJA_DATA21":   PN = "AB18"  !CDS_PN = "AB18";
"MJA_DATA22":   PN = "AB16"  !CDS_PN = "AB16";
"MJA_DATA23":   PN = "AC17"  !CDS_PN = "AC17";
"MJA_DATA24":   PN = "AC16"  !CDS_PN = "AC16";
"MJA_DATA25":   PN = "AD18"  !CDS_PN = "AD18";
"MJA_DATA26":   PN = "AD16"  !CDS_PN = "AD16";
"MJA_DATA27":   PN = "AE17"  !CDS_PN = "AE17";
"MJA_DATA28":   PN = "AG16"  !CDS_PN = "AG16";
"MJA_DATA29":   PN = "AH18"  !CDS_PN = "AH18";
"MJA_DATA30":   PN = "AH16"  !CDS_PN = "AH16";
"MJA_DATA31":   PN = "AJ17"  !CDS_PN = "AJ17";
"MJA_DQS_H0":   PN = "G16"  !CDS_PN = "G16";
"MJA_DQS_H1":   PN = "N16"  !CDS_PN = "N16";
"MJA_DQS_H2":   PN = "W16"  !CDS_PN = "W16";
"MJA_DQS_H3":   PN = "AE16"  !CDS_PN = "AE16";
"MJA_DQS_H4":   PN = "AL16"  !CDS_PN = "AL16";
"MJA_DQS_H5":   PN = "J17"  !CDS_PN = "J17";
"MJA_DQS_H6":   PN = "R17"  !CDS_PN = "R17";
"MJA_DQS_H7":   PN = "AA17"  !CDS_PN = "AA17";
"MJA_DQS_H8":   PN = "AG17"  !CDS_PN = "AG17";
"MJA_DQS_H9":   PN = "AN17"  !CDS_PN = "AN17";
"MJA_DQS_L0":   PN = "H16"  !CDS_PN = "H16";
"MJA_DQS_L1":   PN = "P16"  !CDS_PN = "P16";
"MJA_DQS_L2":   PN = "Y16"  !CDS_PN = "Y16";
"MJA_DQS_L3":   PN = "AF16"  !CDS_PN = "AF16";
"MJA_DQS_L4":   PN = "AM16"  !CDS_PN = "AM16";
"MJA_DQS_L5":   PN = "H18"  !CDS_PN = "H18";
"MJA_DQS_L6":   PN = "P18"  !CDS_PN = "P18";
"MJA_DQS_L7":   PN = "Y18"  !CDS_PN = "Y18";
"MJA_DQS_L8":   PN = "AF18"  !CDS_PN = "AF18";
"MJA_DQS_L9":   PN = "AM18"  !CDS_PN = "AM18";
"MJA_PAR":   PN = "BC17"  !CDS_PN = "BC17";
"MJB0_CS_L0":   PN = "BM18"  !CDS_PN = "BM18";
"MJB0_CS_L1":   PN = "BN16"  !CDS_PN = "BN16";
"MJB0_RSP_L":   PN = "BP16"  !CDS_PN = "BP16";
"MJB1_CS_L0":   PN = "BL16"  !CDS_PN = "BL16";
"MJB1_CS_L1":   PN = "BM16"  !CDS_PN = "BM16";
"MJB1_RSP_L":   PN = "BR16"  !CDS_PN = "BR16";
"MJB_CA0":   PN = "BG17"  !CDS_PN = "BG17";
"MJB_CA1":   PN = "BH18"  !CDS_PN = "BH18";
"MJB_CA2":   PN = "BH16"  !CDS_PN = "BH16";
"MJB_CA3":   PN = "BJ16"  !CDS_PN = "BJ16";
"MJB_CA4":   PN = "BJ17"  !CDS_PN = "BJ17";
"MJB_CA5":   PN = "BK18"  !CDS_PN = "BK18";
"MJB_CA6":   PN = "BK16"  !CDS_PN = "BK16";
"MJB_CHECK0":   PN = "BY16"  !CDS_PN = "BY16";
"MJB_CHECK1":   PN = "CA17"  !CDS_PN = "CA17";
"MJB_CHECK2":   PN = "CA16"  !CDS_PN = "CA16";
"MJB_CHECK3":   PN = "CB18"  !CDS_PN = "CB18";
"MJB_CHECK4":   PN = "BT16"  !CDS_PN = "BT16";
"MJB_CHECK5":   PN = "BU17"  !CDS_PN = "BU17";
"MJB_CHECK6":   PN = "BU16"  !CDS_PN = "BU16";
"MJB_CHECK7":   PN = "BV18"  !CDS_PN = "BV18";
"MJB_DATA0":   PN = "CB16"  !CDS_PN = "CB16";
"MJB_DATA1":   PN = "CC17"  !CDS_PN = "CC17";
"MJB_DATA2":   PN = "CC16"  !CDS_PN = "CC16";
"MJB_DATA3":   PN = "CD18"  !CDS_PN = "CD18";
"MJB_DATA4":   PN = "CF16"  !CDS_PN = "CF16";
"MJB_DATA5":   PN = "CG17"  !CDS_PN = "CG17";
"MJB_DATA6":   PN = "CG16"  !CDS_PN = "CG16";
"MJB_DATA7":   PN = "CH18"  !CDS_PN = "CH18";
"MJB_DATA8":   PN = "CH16"  !CDS_PN = "CH16";
"MJB_DATA9":   PN = "CJ17"  !CDS_PN = "CJ17";
"MJB_DATA10":   PN = "CJ16"  !CDS_PN = "CJ16";
"MJB_DATA11":   PN = "CK18"  !CDS_PN = "CK18";
"MJB_DATA12":   PN = "CM16"  !CDS_PN = "CM16";
"MJB_DATA13":   PN = "CN17"  !CDS_PN = "CN17";
"MJB_DATA14":   PN = "CN16"  !CDS_PN = "CN16";
"MJB_DATA15":   PN = "CP18"  !CDS_PN = "CP18";
"MJB_DATA16":   PN = "CP16"  !CDS_PN = "CP16";
"MJB_DATA17":   PN = "CR17"  !CDS_PN = "CR17";
"MJB_DATA18":   PN = "CR16"  !CDS_PN = "CR16";
"MJB_DATA19":   PN = "CT18"  !CDS_PN = "CT18";
"MJB_DATA20":   PN = "CV16"  !CDS_PN = "CV16";
"MJB_DATA21":   PN = "CW17"  !CDS_PN = "CW17";
"MJB_DATA22":   PN = "CW16"  !CDS_PN = "CW16";
"MJB_DATA23":   PN = "CY18"  !CDS_PN = "CY18";
"MJB_DATA24":   PN = "CY16"  !CDS_PN = "CY16";
"MJB_DATA25":   PN = "DA17"  !CDS_PN = "DA17";
"MJB_DATA26":   PN = "DA16"  !CDS_PN = "DA16";
"MJB_DATA27":   PN = "DB18"  !CDS_PN = "DB18";
"MJB_DATA28":   PN = "DD16"  !CDS_PN = "DD16";
"MJB_DATA29":   PN = "DE17"  !CDS_PN = "DE17";
"MJB_DATA30":   PN = "DE16"  !CDS_PN = "DE16";
"MJB_DATA31":   PN = "DF16"  !CDS_PN = "DF16";
"MJB_DQS_H0":   PN = "CD16"  !CDS_PN = "CD16";
"MJB_DQS_H1":   PN = "CK16"  !CDS_PN = "CK16";
"MJB_DQS_H2":   PN = "CT16"  !CDS_PN = "CT16";
"MJB_DQS_H3":   PN = "DB16"  !CDS_PN = "DB16";
"MJB_DQS_H4":   PN = "BY18"  !CDS_PN = "BY18";
"MJB_DQS_H5":   PN = "CF18"  !CDS_PN = "CF18";
"MJB_DQS_H6":   PN = "CM18"  !CDS_PN = "CM18";
"MJB_DQS_H7":   PN = "CV18"  !CDS_PN = "CV18";
"MJB_DQS_H8":   PN = "DD18"  !CDS_PN = "DD18";
"MJB_DQS_H9":   PN = "BV16"  !CDS_PN = "BV16";
"MJB_DQS_L0":   PN = "CE16"  !CDS_PN = "CE16";
"MJB_DQS_L1":   PN = "CL16"  !CDS_PN = "CL16";
"MJB_DQS_L2":   PN = "CU16"  !CDS_PN = "CU16";
"MJB_DQS_L3":   PN = "DC16"  !CDS_PN = "DC16";
"MJB_DQS_L4":   PN = "BW17"  !CDS_PN = "BW17";
"MJB_DQS_L5":   PN = "CE17"  !CDS_PN = "CE17";
"MJB_DQS_L6":   PN = "CL17"  !CDS_PN = "CL17";
"MJB_DQS_L7":   PN = "CU17"  !CDS_PN = "CU17";
"MJB_DQS_L8":   PN = "DC17"  !CDS_PN = "DC17";
"MJB_DQS_L9":   PN = "BW16"  !CDS_PN = "BW16";
"MJB_PAR":   PN = "BL17"  !CDS_PN = "BL17";
"TEST39J":   PN = "BF18"  !CDS_PN = "BF18";
BODY = "Q_RES","I314": #LOCATION = "R384" !CDS_LOCATION = "R384" &SEC = "1" #&CDS_SEC = "1";
"A":   PN = "1"  !CDS_PN = "1";
"B":   PN = "2"  !CDS_PN = "2";
DRAWING = "@t6g_mb_lib.t6g(sch_1):page20";
BODY = "GENOA_SP5","I159": #LOCATION = "U25" !CDS_LOCATION = "U25" &SEC = "36" #&CDS_SEC = "36";
"MK0_CLK_H":   PN = "BC5"  !CDS_PN = "BC5";
"MK0_CLK_L":   PN = "BD6"  !CDS_PN = "BD6";
"MK1_CLK_H":   PN = "BF6"  !CDS_PN = "BF6";
"MK1_CLK_L":   PN = "BG5"  !CDS_PN = "BG5";
"MK_ALERT_L":   PN = "AT7"  !CDS_PN = "AT7";
"MK_RESET_L":   PN = "AU7"  !CDS_PN = "AU7";
"MKA0_CS_L0":   PN = "AU5"  !CDS_PN = "AU5";
"MKA0_CS_L1":   PN = "AV7"  !CDS_PN = "AV7";
"MKA0_RSP_L":   PN = "BN7"  !CDS_PN = "BN7";
"MKA1_CS_L0":   PN = "AV6"  !CDS_PN = "AV6";
"MKA1_CS_L1":   PN = "AW7"  !CDS_PN = "AW7";
"MKA1_RSP_L":   PN = "BP7"  !CDS_PN = "BP7";
"MKA_CA0":   PN = "AW5"  !CDS_PN = "AW5";
"MKA_CA1":   PN = "AY6"  !CDS_PN = "AY6";
"MKA_CA2":   PN = "AY7"  !CDS_PN = "AY7";
"MKA_CA3":   PN = "BA7"  !CDS_PN = "BA7";
"MKA_CA4":   PN = "BA5"  !CDS_PN = "BA5";
"MKA_CA5":   PN = "BB6"  !CDS_PN = "BB6";
"MKA_CA6":   PN = "BB7"  !CDS_PN = "BB7";
"MKA_CHECK0":   PN = "AJ5"  !CDS_PN = "AJ5";
"MKA_CHECK1":   PN = "AK7"  !CDS_PN = "AK7";
"MKA_CHECK2":   PN = "AK6"  !CDS_PN = "AK6";
"MKA_CHECK3":   PN = "AL7"  !CDS_PN = "AL7";
"MKA_CHECK4":   PN = "AN5"  !CDS_PN = "AN5";
"MKA_CHECK5":   PN = "AP7"  !CDS_PN = "AP7";
"MKA_CHECK6":   PN = "AP6"  !CDS_PN = "AP6";
"MKA_CHECK7":   PN = "AR7"  !CDS_PN = "AR7";
"MKA_DATA0":   PN = "E5"  !CDS_PN = "E5";
"MKA_DATA1":   PN = "F7"  !CDS_PN = "F7";
"MKA_DATA2":   PN = "F6"  !CDS_PN = "F6";
"MKA_DATA3":   PN = "G7"  !CDS_PN = "G7";
"MKA_DATA4":   PN = "J5"  !CDS_PN = "J5";
"MKA_DATA5":   PN = "K7"  !CDS_PN = "K7";
"MKA_DATA6":   PN = "K6"  !CDS_PN = "K6";
"MKA_DATA7":   PN = "L7"  !CDS_PN = "L7";
"MKA_DATA8":   PN = "L5"  !CDS_PN = "L5";
"MKA_DATA9":   PN = "M7"  !CDS_PN = "M7";
"MKA_DATA10":   PN = "M6"  !CDS_PN = "M6";
"MKA_DATA11":   PN = "N7"  !CDS_PN = "N7";
"MKA_DATA12":   PN = "R5"  !CDS_PN = "R5";
"MKA_DATA13":   PN = "T7"  !CDS_PN = "T7";
"MKA_DATA14":   PN = "T6"  !CDS_PN = "T6";
"MKA_DATA15":   PN = "U7"  !CDS_PN = "U7";
"MKA_DATA16":   PN = "U5"  !CDS_PN = "U5";
"MKA_DATA17":   PN = "V7"  !CDS_PN = "V7";
"MKA_DATA18":   PN = "V6"  !CDS_PN = "V6";
"MKA_DATA19":   PN = "W7"  !CDS_PN = "W7";
"MKA_DATA20":   PN = "AA5"  !CDS_PN = "AA5";
"MKA_DATA21":   PN = "AB7"  !CDS_PN = "AB7";
"MKA_DATA22":   PN = "AB6"  !CDS_PN = "AB6";
"MKA_DATA23":   PN = "AC7"  !CDS_PN = "AC7";
"MKA_DATA24":   PN = "AC5"  !CDS_PN = "AC5";
"MKA_DATA25":   PN = "AD7"  !CDS_PN = "AD7";
"MKA_DATA26":   PN = "AD6"  !CDS_PN = "AD6";
"MKA_DATA27":   PN = "AE7"  !CDS_PN = "AE7";
"MKA_DATA28":   PN = "AG5"  !CDS_PN = "AG5";
"MKA_DATA29":   PN = "AH7"  !CDS_PN = "AH7";
"MKA_DATA30":   PN = "AH6"  !CDS_PN = "AH6";
"MKA_DATA31":   PN = "AJ7"  !CDS_PN = "AJ7";
"MKA_DQS_H0":   PN = "G5"  !CDS_PN = "G5";
"MKA_DQS_H1":   PN = "N5"  !CDS_PN = "N5";
"MKA_DQS_H2":   PN = "W5"  !CDS_PN = "W5";
"MKA_DQS_H3":   PN = "AE5"  !CDS_PN = "AE5";
"MKA_DQS_H4":   PN = "AL5"  !CDS_PN = "AL5";
"MKA_DQS_H5":   PN = "J7"  !CDS_PN = "J7";
"MKA_DQS_H6":   PN = "R7"  !CDS_PN = "R7";
"MKA_DQS_H7":   PN = "AA7"  !CDS_PN = "AA7";
"MKA_DQS_H8":   PN = "AG7"  !CDS_PN = "AG7";
"MKA_DQS_H9":   PN = "AN7"  !CDS_PN = "AN7";
"MKA_DQS_L0":   PN = "H6"  !CDS_PN = "H6";
"MKA_DQS_L1":   PN = "P6"  !CDS_PN = "P6";
"MKA_DQS_L2":   PN = "Y6"  !CDS_PN = "Y6";
"MKA_DQS_L3":   PN = "AF6"  !CDS_PN = "AF6";
"MKA_DQS_L4":   PN = "AM6"  !CDS_PN = "AM6";
"MKA_DQS_L5":   PN = "H7"  !CDS_PN = "H7";
"MKA_DQS_L6":   PN = "P7"  !CDS_PN = "P7";
"MKA_DQS_L7":   PN = "Y7"  !CDS_PN = "Y7";
"MKA_DQS_L8":   PN = "AF7"  !CDS_PN = "AF7";
"MKA_DQS_L9":   PN = "AM7"  !CDS_PN = "AM7";
"MKA_PAR":   PN = "BC7"  !CDS_PN = "BC7";
"MKB0_CS_L0":   PN = "BM7"  !CDS_PN = "BM7";
"MKB0_CS_L1":   PN = "BN5"  !CDS_PN = "BN5";
"MKB0_RSP_L":   PN = "BP6"  !CDS_PN = "BP6";
"MKB1_CS_L0":   PN = "BL5"  !CDS_PN = "BL5";
"MKB1_CS_L1":   PN = "BM6"  !CDS_PN = "BM6";
"MKB1_RSP_L":   PN = "BR5"  !CDS_PN = "BR5";
"MKB_CA0":   PN = "BG7"  !CDS_PN = "BG7";
"MKB_CA1":   PN = "BH7"  !CDS_PN = "BH7";
"MKB_CA2":   PN = "BH6"  !CDS_PN = "BH6";
"MKB_CA3":   PN = "BJ5"  !CDS_PN = "BJ5";
"MKB_CA4":   PN = "BJ7"  !CDS_PN = "BJ7";
"MKB_CA5":   PN = "BK7"  !CDS_PN = "BK7";
"MKB_CA6":   PN = "BK6"  !CDS_PN = "BK6";
"MKB_CHECK0":   PN = "BY6"  !CDS_PN = "BY6";
"MKB_CHECK1":   PN = "CA7"  !CDS_PN = "CA7";
"MKB_CHECK2":   PN = "CA5"  !CDS_PN = "CA5";
"MKB_CHECK3":   PN = "CB7"  !CDS_PN = "CB7";
"MKB_CHECK4":   PN = "BT6"  !CDS_PN = "BT6";
"MKB_CHECK5":   PN = "BU7"  !CDS_PN = "BU7";
"MKB_CHECK6":   PN = "BU5"  !CDS_PN = "BU5";
"MKB_CHECK7":   PN = "BV7"  !CDS_PN = "BV7";
"MKB_DATA0":   PN = "CB6"  !CDS_PN = "CB6";
"MKB_DATA1":   PN = "CC7"  !CDS_PN = "CC7";
"MKB_DATA2":   PN = "CC5"  !CDS_PN = "CC5";
"MKB_DATA3":   PN = "CD7"  !CDS_PN = "CD7";
"MKB_DATA4":   PN = "CF6"  !CDS_PN = "CF6";
"MKB_DATA5":   PN = "CG7"  !CDS_PN = "CG7";
"MKB_DATA6":   PN = "CG5"  !CDS_PN = "CG5";
"MKB_DATA7":   PN = "CH7"  !CDS_PN = "CH7";
"MKB_DATA8":   PN = "CH6"  !CDS_PN = "CH6";
"MKB_DATA9":   PN = "CJ7"  !CDS_PN = "CJ7";
"MKB_DATA10":   PN = "CJ5"  !CDS_PN = "CJ5";
"MKB_DATA11":   PN = "CK7"  !CDS_PN = "CK7";
"MKB_DATA12":   PN = "CM6"  !CDS_PN = "CM6";
"MKB_DATA13":   PN = "CN7"  !CDS_PN = "CN7";
"MKB_DATA14":   PN = "CN5"  !CDS_PN = "CN5";
"MKB_DATA15":   PN = "CP7"  !CDS_PN = "CP7";
"MKB_DATA16":   PN = "CP6"  !CDS_PN = "CP6";
"MKB_DATA17":   PN = "CR7"  !CDS_PN = "CR7";
"MKB_DATA18":   PN = "CR5"  !CDS_PN = "CR5";
"MKB_DATA19":   PN = "CT7"  !CDS_PN = "CT7";
"MKB_DATA20":   PN = "CV6"  !CDS_PN = "CV6";
"MKB_DATA21":   PN = "CW7"  !CDS_PN = "CW7";
"MKB_DATA22":   PN = "CW5"  !CDS_PN = "CW5";
"MKB_DATA23":   PN = "CY7"  !CDS_PN = "CY7";
"MKB_DATA24":   PN = "CY6"  !CDS_PN = "CY6";
"MKB_DATA25":   PN = "DA7"  !CDS_PN = "DA7";
"MKB_DATA26":   PN = "DA5"  !CDS_PN = "DA5";
"MKB_DATA27":   PN = "DB7"  !CDS_PN = "DB7";
"MKB_DATA28":   PN = "DD6"  !CDS_PN = "DD6";
"MKB_DATA29":   PN = "DE7"  !CDS_PN = "DE7";
"MKB_DATA30":   PN = "DE5"  !CDS_PN = "DE5";
"MKB_DATA31":   PN = "DF7"  !CDS_PN = "DF7";
"MKB_DQS_H0":   PN = "CD6"  !CDS_PN = "CD6";
"MKB_DQS_H1":   PN = "CK6"  !CDS_PN = "CK6";
"MKB_DQS_H2":   PN = "CT6"  !CDS_PN = "CT6";
"MKB_DQS_H3":   PN = "DB6"  !CDS_PN = "DB6";
"MKB_DQS_H4":   PN = "BY7"  !CDS_PN = "BY7";
"MKB_DQS_H5":   PN = "CF7"  !CDS_PN = "CF7";
"MKB_DQS_H6":   PN = "CM7"  !CDS_PN = "CM7";
"MKB_DQS_H7":   PN = "CV7"  !CDS_PN = "CV7";
"MKB_DQS_H8":   PN = "DD7"  !CDS_PN = "DD7";
"MKB_DQS_H9":   PN = "BV6"  !CDS_PN = "BV6";
"MKB_DQS_L0":   PN = "CE5"  !CDS_PN = "CE5";
"MKB_DQS_L1":   PN = "CL5"  !CDS_PN = "CL5";
"MKB_DQS_L2":   PN = "CU5"  !CDS_PN = "CU5";
"MKB_DQS_L3":   PN = "DC5"  !CDS_PN = "DC5";
"MKB_DQS_L4":   PN = "BW7"  !CDS_PN = "BW7";
"MKB_DQS_L5":   PN = "CE7"  !CDS_PN = "CE7";
"MKB_DQS_L6":   PN = "CL7"  !CDS_PN = "CL7";
"MKB_DQS_L7":   PN = "CU7"  !CDS_PN = "CU7";
"MKB_DQS_L8":   PN = "DC7"  !CDS_PN = "DC7";
"MKB_DQS_L9":   PN = "BW5"  !CDS_PN = "BW5";
"MKB_PAR":   PN = "BL7"  !CDS_PN = "BL7";
"TEST39K":   PN = "BF7"  !CDS_PN = "BF7";
BODY = "Q_RES","I314": #LOCATION = "R385" !CDS_LOCATION = "R385" &SEC = "1" #&CDS_SEC = "1";
"A":   PN = "1"  !CDS_PN = "1";
"B":   PN = "2"  !CDS_PN = "2";
DRAWING = "@t6g_mb_lib.t6g(sch_1):page21";
BODY = "GENOA_SP5","I159": #LOCATION = "U25" !CDS_LOCATION = "U25" &SEC = "35" #&CDS_SEC = "35";
"ML0_CLK_H":   PN = "BC9"  !CDS_PN = "BC9";
"ML0_CLK_L":   PN = "BD9"  !CDS_PN = "BD9";
"ML1_CLK_H":   PN = "BF9"  !CDS_PN = "BF9";
"ML1_CLK_L":   PN = "BG9"  !CDS_PN = "BG9";
"ML_ALERT_L":   PN = "AT11"  !CDS_PN = "AT11";
"ML_RESET_L":   PN = "AU10"  !CDS_PN = "AU10";
"MLA0_CS_L0":   PN = "AU9"  !CDS_PN = "AU9";
"MLA0_CS_L1":   PN = "AV11"  !CDS_PN = "AV11";
"MLA0_RSP_L":   PN = "BN10"  !CDS_PN = "BN10";
"MLA1_CS_L0":   PN = "AV9"  !CDS_PN = "AV9";
"MLA1_CS_L1":   PN = "AW10"  !CDS_PN = "AW10";
"MLA1_RSP_L":   PN = "BP11"  !CDS_PN = "BP11";
"MLA_CA0":   PN = "AW9"  !CDS_PN = "AW9";
"MLA_CA1":   PN = "AY9"  !CDS_PN = "AY9";
"MLA_CA2":   PN = "AY11"  !CDS_PN = "AY11";
"MLA_CA3":   PN = "BA10"  !CDS_PN = "BA10";
"MLA_CA4":   PN = "BA9"  !CDS_PN = "BA9";
"MLA_CA5":   PN = "BB9"  !CDS_PN = "BB9";
"MLA_CA6":   PN = "BB11"  !CDS_PN = "BB11";
"MLA_CHECK0":   PN = "AJ9"  !CDS_PN = "AJ9";
"MLA_CHECK1":   PN = "AK11"  !CDS_PN = "AK11";
"MLA_CHECK2":   PN = "AK9"  !CDS_PN = "AK9";
"MLA_CHECK3":   PN = "AL10"  !CDS_PN = "AL10";
"MLA_CHECK4":   PN = "AN9"  !CDS_PN = "AN9";
"MLA_CHECK5":   PN = "AP11"  !CDS_PN = "AP11";
"MLA_CHECK6":   PN = "AP9"  !CDS_PN = "AP9";
"MLA_CHECK7":   PN = "AR10"  !CDS_PN = "AR10";
"MLA_DATA0":   PN = "E9"  !CDS_PN = "E9";
"MLA_DATA1":   PN = "F11"  !CDS_PN = "F11";
"MLA_DATA2":   PN = "F9"  !CDS_PN = "F9";
"MLA_DATA3":   PN = "G10"  !CDS_PN = "G10";
"MLA_DATA4":   PN = "J9"  !CDS_PN = "J9";
"MLA_DATA5":   PN = "K11"  !CDS_PN = "K11";
"MLA_DATA6":   PN = "K9"  !CDS_PN = "K9";
"MLA_DATA7":   PN = "L10"  !CDS_PN = "L10";
"MLA_DATA8":   PN = "L9"  !CDS_PN = "L9";
"MLA_DATA9":   PN = "M11"  !CDS_PN = "M11";
"MLA_DATA10":   PN = "M9"  !CDS_PN = "M9";
"MLA_DATA11":   PN = "N10"  !CDS_PN = "N10";
"MLA_DATA12":   PN = "R9"  !CDS_PN = "R9";
"MLA_DATA13":   PN = "T11"  !CDS_PN = "T11";
"MLA_DATA14":   PN = "T9"  !CDS_PN = "T9";
"MLA_DATA15":   PN = "U10"  !CDS_PN = "U10";
"MLA_DATA16":   PN = "U9"  !CDS_PN = "U9";
"MLA_DATA17":   PN = "V11"  !CDS_PN = "V11";
"MLA_DATA18":   PN = "V9"  !CDS_PN = "V9";
"MLA_DATA19":   PN = "W10"  !CDS_PN = "W10";
"MLA_DATA20":   PN = "AA9"  !CDS_PN = "AA9";
"MLA_DATA21":   PN = "AB11"  !CDS_PN = "AB11";
"MLA_DATA22":   PN = "AB9"  !CDS_PN = "AB9";
"MLA_DATA23":   PN = "AC10"  !CDS_PN = "AC10";
"MLA_DATA24":   PN = "AC9"  !CDS_PN = "AC9";
"MLA_DATA25":   PN = "AD11"  !CDS_PN = "AD11";
"MLA_DATA26":   PN = "AD9"  !CDS_PN = "AD9";
"MLA_DATA27":   PN = "AE10"  !CDS_PN = "AE10";
"MLA_DATA28":   PN = "AG9"  !CDS_PN = "AG9";
"MLA_DATA29":   PN = "AH11"  !CDS_PN = "AH11";
"MLA_DATA30":   PN = "AH9"  !CDS_PN = "AH9";
"MLA_DATA31":   PN = "AJ10"  !CDS_PN = "AJ10";
"MLA_DQS_H0":   PN = "G9"  !CDS_PN = "G9";
"MLA_DQS_H1":   PN = "N9"  !CDS_PN = "N9";
"MLA_DQS_H2":   PN = "W9"  !CDS_PN = "W9";
"MLA_DQS_H3":   PN = "AE9"  !CDS_PN = "AE9";
"MLA_DQS_H4":   PN = "AL9"  !CDS_PN = "AL9";
"MLA_DQS_H5":   PN = "J10"  !CDS_PN = "J10";
"MLA_DQS_H6":   PN = "R10"  !CDS_PN = "R10";
"MLA_DQS_H7":   PN = "AA10"  !CDS_PN = "AA10";
"MLA_DQS_H8":   PN = "AG10"  !CDS_PN = "AG10";
"MLA_DQS_H9":   PN = "AN10"  !CDS_PN = "AN10";
"MLA_DQS_L0":   PN = "H9"  !CDS_PN = "H9";
"MLA_DQS_L1":   PN = "P9"  !CDS_PN = "P9";
"MLA_DQS_L2":   PN = "Y9"  !CDS_PN = "Y9";
"MLA_DQS_L3":   PN = "AF9"  !CDS_PN = "AF9";
"MLA_DQS_L4":   PN = "AM9"  !CDS_PN = "AM9";
"MLA_DQS_L5":   PN = "H11"  !CDS_PN = "H11";
"MLA_DQS_L6":   PN = "P11"  !CDS_PN = "P11";
"MLA_DQS_L7":   PN = "Y11"  !CDS_PN = "Y11";
"MLA_DQS_L8":   PN = "AF11"  !CDS_PN = "AF11";
"MLA_DQS_L9":   PN = "AM11"  !CDS_PN = "AM11";
"MLA_PAR":   PN = "BC10"  !CDS_PN = "BC10";
"MLB0_CS_L0":   PN = "BM11"  !CDS_PN = "BM11";
"MLB0_CS_L1":   PN = "BN9"  !CDS_PN = "BN9";
"MLB0_RSP_L":   PN = "BP9"  !CDS_PN = "BP9";
"MLB1_CS_L0":   PN = "BL9"  !CDS_PN = "BL9";
"MLB1_CS_L1":   PN = "BM9"  !CDS_PN = "BM9";
"MLB1_RSP_L":   PN = "BR9"  !CDS_PN = "BR9";
"MLB_CA0":   PN = "BG10"  !CDS_PN = "BG10";
"MLB_CA1":   PN = "BH11"  !CDS_PN = "BH11";
"MLB_CA2":   PN = "BH9"  !CDS_PN = "BH9";
"MLB_CA3":   PN = "BJ9"  !CDS_PN = "BJ9";
"MLB_CA4":   PN = "BJ10"  !CDS_PN = "BJ10";
"MLB_CA5":   PN = "BK11"  !CDS_PN = "BK11";
"MLB_CA6":   PN = "BK9"  !CDS_PN = "BK9";
"MLB_CHECK0":   PN = "BY9"  !CDS_PN = "BY9";
"MLB_CHECK1":   PN = "CA10"  !CDS_PN = "CA10";
"MLB_CHECK2":   PN = "CA9"  !CDS_PN = "CA9";
"MLB_CHECK3":   PN = "CB11"  !CDS_PN = "CB11";
"MLB_CHECK4":   PN = "BT9"  !CDS_PN = "BT9";
"MLB_CHECK5":   PN = "BU10"  !CDS_PN = "BU10";
"MLB_CHECK6":   PN = "BU9"  !CDS_PN = "BU9";
"MLB_CHECK7":   PN = "BV11"  !CDS_PN = "BV11";
"MLB_DATA0":   PN = "CB9"  !CDS_PN = "CB9";
"MLB_DATA1":   PN = "CC10"  !CDS_PN = "CC10";
"MLB_DATA2":   PN = "CC9"  !CDS_PN = "CC9";
"MLB_DATA3":   PN = "CD11"  !CDS_PN = "CD11";
"MLB_DATA4":   PN = "CF9"  !CDS_PN = "CF9";
"MLB_DATA5":   PN = "CG10"  !CDS_PN = "CG10";
"MLB_DATA6":   PN = "CG9"  !CDS_PN = "CG9";
"MLB_DATA7":   PN = "CH11"  !CDS_PN = "CH11";
"MLB_DATA8":   PN = "CH9"  !CDS_PN = "CH9";
"MLB_DATA9":   PN = "CJ10"  !CDS_PN = "CJ10";
"MLB_DATA10":   PN = "CJ9"  !CDS_PN = "CJ9";
"MLB_DATA11":   PN = "CK11"  !CDS_PN = "CK11";
"MLB_DATA12":   PN = "CM9"  !CDS_PN = "CM9";
"MLB_DATA13":   PN = "CN10"  !CDS_PN = "CN10";
"MLB_DATA14":   PN = "CN9"  !CDS_PN = "CN9";
"MLB_DATA15":   PN = "CP11"  !CDS_PN = "CP11";
"MLB_DATA16":   PN = "CP9"  !CDS_PN = "CP9";
"MLB_DATA17":   PN = "CR10"  !CDS_PN = "CR10";
"MLB_DATA18":   PN = "CR9"  !CDS_PN = "CR9";
"MLB_DATA19":   PN = "CT11"  !CDS_PN = "CT11";
"MLB_DATA20":   PN = "CV9"  !CDS_PN = "CV9";
"MLB_DATA21":   PN = "CW10"  !CDS_PN = "CW10";
"MLB_DATA22":   PN = "CW9"  !CDS_PN = "CW9";
"MLB_DATA23":   PN = "CY11"  !CDS_PN = "CY11";
"MLB_DATA24":   PN = "CY9"  !CDS_PN = "CY9";
"MLB_DATA25":   PN = "DA10"  !CDS_PN = "DA10";
"MLB_DATA26":   PN = "DA9"  !CDS_PN = "DA9";
"MLB_DATA27":   PN = "DB11"  !CDS_PN = "DB11";
"MLB_DATA28":   PN = "DD9"  !CDS_PN = "DD9";
"MLB_DATA29":   PN = "DE10"  !CDS_PN = "DE10";
"MLB_DATA30":   PN = "DE9"  !CDS_PN = "DE9";
"MLB_DATA31":   PN = "DF9"  !CDS_PN = "DF9";
"MLB_DQS_H0":   PN = "CD9"  !CDS_PN = "CD9";
"MLB_DQS_H1":   PN = "CK9"  !CDS_PN = "CK9";
"MLB_DQS_H2":   PN = "CT9"  !CDS_PN = "CT9";
"MLB_DQS_H3":   PN = "DB9"  !CDS_PN = "DB9";
"MLB_DQS_H4":   PN = "BY11"  !CDS_PN = "BY11";
"MLB_DQS_H5":   PN = "CF11"  !CDS_PN = "CF11";
"MLB_DQS_H6":   PN = "CM11"  !CDS_PN = "CM11";
"MLB_DQS_H7":   PN = "CV11"  !CDS_PN = "CV11";
"MLB_DQS_H8":   PN = "DD11"  !CDS_PN = "DD11";
"MLB_DQS_H9":   PN = "BV9"  !CDS_PN = "BV9";
"MLB_DQS_L0":   PN = "CE9"  !CDS_PN = "CE9";
"MLB_DQS_L1":   PN = "CL9"  !CDS_PN = "CL9";
"MLB_DQS_L2":   PN = "CU9"  !CDS_PN = "CU9";
"MLB_DQS_L3":   PN = "DC9"  !CDS_PN = "DC9";
"MLB_DQS_L4":   PN = "BW10"  !CDS_PN = "BW10";
"MLB_DQS_L5":   PN = "CE10"  !CDS_PN = "CE10";
"MLB_DQS_L6":   PN = "CL10"  !CDS_PN = "CL10";
"MLB_DQS_L7":   PN = "CU10"  !CDS_PN = "CU10";
"MLB_DQS_L8":   PN = "DC10"  !CDS_PN = "DC10";
"MLB_DQS_L9":   PN = "BW9"  !CDS_PN = "BW9";
"MLB_PAR":   PN = "BL10"  !CDS_PN = "BL10";
"TEST39L":   PN = "BF11"  !CDS_PN = "BF11";
BODY = "Q_RES","I314": #LOCATION = "R386" !CDS_LOCATION = "R386" &SEC = "1" #&CDS_SEC = "1";
"A":   PN = "1"  !CDS_PN = "1";
"B":   PN = "2"  !CDS_PN = "2";
DRAWING = "@t6g_mb_lib.t6g(sch_1):page22";
BODY = "GENOA_SP5","I207": #LOCATION = "U25" !CDS_LOCATION = "U25" &SEC = "11" #&CDS_SEC = "11";
"G0_RXN0":   PN = "M40"  !CDS_PN = "M40";
"G0_RXN1":   PN = "K40"  !CDS_PN = "K40";
"G0_RXN2":   PN = "H40"  !CDS_PN = "H40";
"G0_RXN3":   PN = "L43"  !CDS_PN = "L43";
"G0_RXN4":   PN = "G43"  !CDS_PN = "G43";
"G0_RXN5":   PN = "J43"  !CDS_PN = "J43";
"G0_RXN6":   PN = "L46"  !CDS_PN = "L46";
"G0_RXN7":   PN = "G46"  !CDS_PN = "G46";
"G0_RXN8":   PN = "J46"  !CDS_PN = "J46";
"G0_RXN9":   PN = "L49"  !CDS_PN = "L49";
"G0_RXN10":   PN = "G49"  !CDS_PN = "G49";
"G0_RXN11":   PN = "J49"  !CDS_PN = "J49";
"G0_RXN12":   PN = "L52"  !CDS_PN = "L52";
"G0_RXN13":   PN = "G52"  !CDS_PN = "G52";
"G0_RXN14":   PN = "J52"  !CDS_PN = "J52";
"G0_RXN15":   PN = "N52"  !CDS_PN = "N52";
"G0_RXP0":   PN = "M41"  !CDS_PN = "M41";
"G0_RXP1":   PN = "K41"  !CDS_PN = "K41";
"G0_RXP2":   PN = "H41"  !CDS_PN = "H41";
"G0_RXP3":   PN = "L44"  !CDS_PN = "L44";
"G0_RXP4":   PN = "G44"  !CDS_PN = "G44";
"G0_RXP5":   PN = "J44"  !CDS_PN = "J44";
"G0_RXP6":   PN = "L47"  !CDS_PN = "L47";
"G0_RXP7":   PN = "G47"  !CDS_PN = "G47";
"G0_RXP8":   PN = "J47"  !CDS_PN = "J47";
"G0_RXP9":   PN = "L50"  !CDS_PN = "L50";
"G0_RXP10":   PN = "G50"  !CDS_PN = "G50";
"G0_RXP11":   PN = "J50"  !CDS_PN = "J50";
"G0_RXP12":   PN = "L53"  !CDS_PN = "L53";
"G0_RXP13":   PN = "G53"  !CDS_PN = "G53";
"G0_RXP14":   PN = "J53"  !CDS_PN = "J53";
"G0_RXP15":   PN = "N53"  !CDS_PN = "N53";
"G0_TXN0":   PN = "AF41"  !CDS_PN = "AF41";
"G0_TXN1":   PN = "AD41"  !CDS_PN = "AD41";
"G0_TXN2":   PN = "AB41"  !CDS_PN = "AB41";
"G0_TXN3":   PN = "AG44"  !CDS_PN = "AG44";
"G0_TXN4":   PN = "AA44"  !CDS_PN = "AA44";
"G0_TXN5":   PN = "AC44"  !CDS_PN = "AC44";
"G0_TXN6":   PN = "AE44"  !CDS_PN = "AE44";
"G0_TXN7":   PN = "AG47"  !CDS_PN = "AG47";
"G0_TXN8":   PN = "AC47"  !CDS_PN = "AC47";
"G0_TXN9":   PN = "AE47"  !CDS_PN = "AE47";
"G0_TXN10":   PN = "AG50"  !CDS_PN = "AG50";
"G0_TXN11":   PN = "AC50"  !CDS_PN = "AC50";
"G0_TXN12":   PN = "AE50"  !CDS_PN = "AE50";
"G0_TXN13":   PN = "AG53"  !CDS_PN = "AG53";
"G0_TXN14":   PN = "AC53"  !CDS_PN = "AC53";
"G0_TXN15":   PN = "AE53"  !CDS_PN = "AE53";
"G0_TXP0":   PN = "AF40"  !CDS_PN = "AF40";
"G0_TXP1":   PN = "AD40"  !CDS_PN = "AD40";
"G0_TXP2":   PN = "AB40"  !CDS_PN = "AB40";
"G0_TXP3":   PN = "AG43"  !CDS_PN = "AG43";
"G0_TXP4":   PN = "AA43"  !CDS_PN = "AA43";
"G0_TXP5":   PN = "AC43"  !CDS_PN = "AC43";
"G0_TXP6":   PN = "AE43"  !CDS_PN = "AE43";
"G0_TXP7":   PN = "AG46"  !CDS_PN = "AG46";
"G0_TXP8":   PN = "AC46"  !CDS_PN = "AC46";
"G0_TXP9":   PN = "AE46"  !CDS_PN = "AE46";
"G0_TXP10":   PN = "AG49"  !CDS_PN = "AG49";
"G0_TXP11":   PN = "AC49"  !CDS_PN = "AC49";
"G0_TXP12":   PN = "AE49"  !CDS_PN = "AE49";
"G0_TXP13":   PN = "AG52"  !CDS_PN = "AG52";
"G0_TXP14":   PN = "AC52"  !CDS_PN = "AC52";
"G0_TXP15":   PN = "AE52"  !CDS_PN = "AE52";
BODY = "GENOA_SP5","I208": #LOCATION = "U25" !CDS_LOCATION = "U25" &SEC = "12" #&CDS_SEC = "12";
"G1_RXN0":   PN = "V40"  !CDS_PN = "V40";
"G1_RXN1":   PN = "T40"  !CDS_PN = "T40";
"G1_RXN2":   PN = "P40"  !CDS_PN = "P40";
"G1_RXN3":   PN = "U43"  !CDS_PN = "U43";
"G1_RXN4":   PN = "N43"  !CDS_PN = "N43";
"G1_RXN5":   PN = "R43"  !CDS_PN = "R43";
"G1_RXN6":   PN = "U46"  !CDS_PN = "U46";
"G1_RXN7":   PN = "N46"  !CDS_PN = "N46";
"G1_RXN8":   PN = "R46"  !CDS_PN = "R46";
"G1_RXN9":   PN = "W49"  !CDS_PN = "W49";
"G1_RXN10":   PN = "N49"  !CDS_PN = "N49";
"G1_RXN11":   PN = "R49"  !CDS_PN = "R49";
"G1_RXN12":   PN = "U49"  !CDS_PN = "U49";
"G1_RXN13":   PN = "W52"  !CDS_PN = "W52";
"G1_RXN14":   PN = "R52"  !CDS_PN = "R52";
"G1_RXN15":   PN = "U52"  !CDS_PN = "U52";
"G1_RXP0":   PN = "V41"  !CDS_PN = "V41";
"G1_RXP1":   PN = "T41"  !CDS_PN = "T41";
"G1_RXP2":   PN = "P41"  !CDS_PN = "P41";
"G1_RXP3":   PN = "U44"  !CDS_PN = "U44";
"G1_RXP4":   PN = "N44"  !CDS_PN = "N44";
"G1_RXP5":   PN = "R44"  !CDS_PN = "R44";
"G1_RXP6":   PN = "U47"  !CDS_PN = "U47";
"G1_RXP7":   PN = "N47"  !CDS_PN = "N47";
"G1_RXP8":   PN = "R47"  !CDS_PN = "R47";
"G1_RXP9":   PN = "W50"  !CDS_PN = "W50";
"G1_RXP10":   PN = "N50"  !CDS_PN = "N50";
"G1_RXP11":   PN = "R50"  !CDS_PN = "R50";
"G1_RXP12":   PN = "U50"  !CDS_PN = "U50";
"G1_RXP13":   PN = "W53"  !CDS_PN = "W53";
"G1_RXP14":   PN = "R53"  !CDS_PN = "R53";
"G1_RXP15":   PN = "U53"  !CDS_PN = "U53";
"G1_TXN0":   PN = "AP41"  !CDS_PN = "AP41";
"G1_TXN1":   PN = "AM41"  !CDS_PN = "AM41";
"G1_TXN2":   PN = "AH41"  !CDS_PN = "AH41";
"G1_TXN3":   PN = "AK41"  !CDS_PN = "AK41";
"G1_TXN4":   PN = "AN44"  !CDS_PN = "AN44";
"G1_TXN5":   PN = "AJ44"  !CDS_PN = "AJ44";
"G1_TXN6":   PN = "AL44"  !CDS_PN = "AL44";
"G1_TXN7":   PN = "AN47"  !CDS_PN = "AN47";
"G1_TXN8":   PN = "AJ47"  !CDS_PN = "AJ47";
"G1_TXN9":   PN = "AL47"  !CDS_PN = "AL47";
"G1_TXN10":   PN = "AN50"  !CDS_PN = "AN50";
"G1_TXN11":   PN = "AJ50"  !CDS_PN = "AJ50";
"G1_TXN12":   PN = "AL50"  !CDS_PN = "AL50";
"G1_TXN13":   PN = "AN53"  !CDS_PN = "AN53";
"G1_TXN14":   PN = "AJ53"  !CDS_PN = "AJ53";
"G1_TXN15":   PN = "AL53"  !CDS_PN = "AL53";
"G1_TXP0":   PN = "AP40"  !CDS_PN = "AP40";
"G1_TXP1":   PN = "AM40"  !CDS_PN = "AM40";
"G1_TXP2":   PN = "AH40"  !CDS_PN = "AH40";
"G1_TXP3":   PN = "AK40"  !CDS_PN = "AK40";
"G1_TXP4":   PN = "AN43"  !CDS_PN = "AN43";
"G1_TXP5":   PN = "AJ43"  !CDS_PN = "AJ43";
"G1_TXP6":   PN = "AL43"  !CDS_PN = "AL43";
"G1_TXP7":   PN = "AN46"  !CDS_PN = "AN46";
"G1_TXP8":   PN = "AJ46"  !CDS_PN = "AJ46";
"G1_TXP9":   PN = "AL46"  !CDS_PN = "AL46";
"G1_TXP10":   PN = "AN49"  !CDS_PN = "AN49";
"G1_TXP11":   PN = "AJ49"  !CDS_PN = "AJ49";
"G1_TXP12":   PN = "AL49"  !CDS_PN = "AL49";
"G1_TXP13":   PN = "AN52"  !CDS_PN = "AN52";
"G1_TXP14":   PN = "AJ52"  !CDS_PN = "AJ52";
"G1_TXP15":   PN = "AL52"  !CDS_PN = "AL52";
DRAWING = "@t6g_mb_lib.t6g(sch_1):page23";
BODY = "GENOA_SP5","I215": #LOCATION = "U25" !CDS_LOCATION = "U25" &SEC = "13" #&CDS_SEC = "13";
"G2_RXN0":   PN = "AE23"  !CDS_PN = "AE23";
"G2_RXN1":   PN = "AC23"  !CDS_PN = "AC23";
"G2_RXN2":   PN = "AG23"  !CDS_PN = "AG23";
"G2_RXN3":   PN = "AE26"  !CDS_PN = "AE26";
"G2_RXN4":   PN = "AC26"  !CDS_PN = "AC26";
"G2_RXN5":   PN = "AG26"  !CDS_PN = "AG26";
"G2_RXN6":   PN = "AE29"  !CDS_PN = "AE29";
"G2_RXN7":   PN = "AC29"  !CDS_PN = "AC29";
"G2_RXN8":   PN = "AG29"  !CDS_PN = "AG29";
"G2_RXN9":   PN = "AE32"  !CDS_PN = "AE32";
"G2_RXN10":   PN = "AC32"  !CDS_PN = "AC32";
"G2_RXN11":   PN = "AA32"  !CDS_PN = "AA32";
"G2_RXN12":   PN = "AG32"  !CDS_PN = "AG32";
"G2_RXN13":   PN = "AB35"  !CDS_PN = "AB35";
"G2_RXN14":   PN = "AD35"  !CDS_PN = "AD35";
"G2_RXN15":   PN = "AF35"  !CDS_PN = "AF35";
"G2_RXP0":   PN = "AE24"  !CDS_PN = "AE24";
"G2_RXP1":   PN = "AC24"  !CDS_PN = "AC24";
"G2_RXP2":   PN = "AG24"  !CDS_PN = "AG24";
"G2_RXP3":   PN = "AE27"  !CDS_PN = "AE27";
"G2_RXP4":   PN = "AC27"  !CDS_PN = "AC27";
"G2_RXP5":   PN = "AG27"  !CDS_PN = "AG27";
"G2_RXP6":   PN = "AE30"  !CDS_PN = "AE30";
"G2_RXP7":   PN = "AC30"  !CDS_PN = "AC30";
"G2_RXP8":   PN = "AG30"  !CDS_PN = "AG30";
"G2_RXP9":   PN = "AE33"  !CDS_PN = "AE33";
"G2_RXP10":   PN = "AC33"  !CDS_PN = "AC33";
"G2_RXP11":   PN = "AA33"  !CDS_PN = "AA33";
"G2_RXP12":   PN = "AG33"  !CDS_PN = "AG33";
"G2_RXP13":   PN = "AB36"  !CDS_PN = "AB36";
"G2_RXP14":   PN = "AD36"  !CDS_PN = "AD36";
"G2_RXP15":   PN = "AF36"  !CDS_PN = "AF36";
"G2_TXN0":   PN = "N24"  !CDS_PN = "N24";
"G2_TXN1":   PN = "J24"  !CDS_PN = "J24";
"G2_TXN2":   PN = "G24"  !CDS_PN = "G24";
"G2_TXN3":   PN = "L24"  !CDS_PN = "L24";
"G2_TXN4":   PN = "J27"  !CDS_PN = "J27";
"G2_TXN5":   PN = "G27"  !CDS_PN = "G27";
"G2_TXN6":   PN = "L27"  !CDS_PN = "L27";
"G2_TXN7":   PN = "J30"  !CDS_PN = "J30";
"G2_TXN8":   PN = "G30"  !CDS_PN = "G30";
"G2_TXN9":   PN = "L30"  !CDS_PN = "L30";
"G2_TXN10":   PN = "J33"  !CDS_PN = "J33";
"G2_TXN11":   PN = "G33"  !CDS_PN = "G33";
"G2_TXN12":   PN = "L33"  !CDS_PN = "L33";
"G2_TXN13":   PN = "H36"  !CDS_PN = "H36";
"G2_TXN14":   PN = "K36"  !CDS_PN = "K36";
"G2_TXN15":   PN = "M36"  !CDS_PN = "M36";
"G2_TXP0":   PN = "N23"  !CDS_PN = "N23";
"G2_TXP1":   PN = "J23"  !CDS_PN = "J23";
"G2_TXP2":   PN = "G23"  !CDS_PN = "G23";
"G2_TXP3":   PN = "L23"  !CDS_PN = "L23";
"G2_TXP4":   PN = "J26"  !CDS_PN = "J26";
"G2_TXP5":   PN = "G26"  !CDS_PN = "G26";
"G2_TXP6":   PN = "L26"  !CDS_PN = "L26";
"G2_TXP7":   PN = "J29"  !CDS_PN = "J29";
"G2_TXP8":   PN = "G29"  !CDS_PN = "G29";
"G2_TXP9":   PN = "L29"  !CDS_PN = "L29";
"G2_TXP10":   PN = "J32"  !CDS_PN = "J32";
"G2_TXP11":   PN = "G32"  !CDS_PN = "G32";
"G2_TXP12":   PN = "L32"  !CDS_PN = "L32";
"G2_TXP13":   PN = "H35"  !CDS_PN = "H35";
"G2_TXP14":   PN = "K35"  !CDS_PN = "K35";
"G2_TXP15":   PN = "M35"  !CDS_PN = "M35";
BODY = "GENOA_SP5","I216": #LOCATION = "U25" !CDS_LOCATION = "U25" &SEC = "14" #&CDS_SEC = "14";
"G3_RXN0||SATA20_RXN":   PN = "AL23"  !CDS_PN = "AL23";
"G3_RXN1||SATA21_RXN":   PN = "AJ23"  !CDS_PN = "AJ23";
"G3_RXN2||SATA22_RXN":   PN = "AN23"  !CDS_PN = "AN23";
"G3_RXN3||SATA23_RXN":   PN = "AL26"  !CDS_PN = "AL26";
"G3_RXN4||SATA24_RXN":   PN = "AJ26"  !CDS_PN = "AJ26";
"G3_RXN5||SATA25_RXN":   PN = "AN26"  !CDS_PN = "AN26";
"G3_RXN6||SATA26_RXN":   PN = "AL29"  !CDS_PN = "AL29";
"G3_RXN7||SATA27_RXN":   PN = "AJ29"  !CDS_PN = "AJ29";
"G3_RXN8||SATA30_RXN":   PN = "AN29"  !CDS_PN = "AN29";
"G3_RXN9||SATA31_RXN":   PN = "AL32"  !CDS_PN = "AL32";
"G3_RXN10||SATA32_RXN":   PN = "AJ32"  !CDS_PN = "AJ32";
"G3_RXN11||SATA33_RXN":   PN = "AN32"  !CDS_PN = "AN32";
"G3_RXN12||SATA34_RXN":   PN = "AK35"  !CDS_PN = "AK35";
"G3_RXN13||SATA35_RXN":   PN = "AH35"  !CDS_PN = "AH35";
"G3_RXN14||SATA36_RXN":   PN = "AM35"  !CDS_PN = "AM35";
"G3_RXN15||SATA37_RXN":   PN = "AP35"  !CDS_PN = "AP35";
"G3_RXP0||SATA20_RXP":   PN = "AL24"  !CDS_PN = "AL24";
"G3_RXP1||SATA21_RXP":   PN = "AJ24"  !CDS_PN = "AJ24";
"G3_RXP2||SATA22_RXP":   PN = "AN24"  !CDS_PN = "AN24";
"G3_RXP3||SATA23_RXP":   PN = "AL27"  !CDS_PN = "AL27";
"G3_RXP4||SATA24_RXP":   PN = "AJ27"  !CDS_PN = "AJ27";
"G3_RXP5||SATA25_RXP":   PN = "AN27"  !CDS_PN = "AN27";
"G3_RXP6||SATA26_RXP":   PN = "AL30"  !CDS_PN = "AL30";
"G3_RXP7||SATA27_RXP":   PN = "AJ30"  !CDS_PN = "AJ30";
"G3_RXP8||SATA30_RXP":   PN = "AN30"  !CDS_PN = "AN30";
"G3_RXP9||SATA31_RXP":   PN = "AL33"  !CDS_PN = "AL33";
"G3_RXP10||SATA32_RXP":   PN = "AJ33"  !CDS_PN = "AJ33";
"G3_RXP11||SATA33_RXP":   PN = "AN33"  !CDS_PN = "AN33";
"G3_RXP12||SATA34_RXP":   PN = "AK36"  !CDS_PN = "AK36";
"G3_RXP13||SATA35_RXP":   PN = "AH36"  !CDS_PN = "AH36";
"G3_RXP14||SATA36_RXP":   PN = "AM36"  !CDS_PN = "AM36";
"G3_RXP15||SATA37_RXP":   PN = "AP36"  !CDS_PN = "AP36";
"G3_TXN0||SATA20_TXN":   PN = "U24"  !CDS_PN = "U24";
"G3_TXN1||SATA21_TXN":   PN = "R24"  !CDS_PN = "R24";
"G3_TXN2||SATA22_TXN":   PN = "W24"  !CDS_PN = "W24";
"G3_TXN3||SATA23_TXN":   PN = "U27"  !CDS_PN = "U27";
"G3_TXN4||SATA24_TXN":   PN = "R27"  !CDS_PN = "R27";
"G3_TXN5||SATA25_TXN":   PN = "N27"  !CDS_PN = "N27";
"G3_TXN6||SATA26_TXN":   PN = "W27"  !CDS_PN = "W27";
"G3_TXN7||SATA27_TXN":   PN = "R30"  !CDS_PN = "R30";
"G3_TXN8||SATA30_TXN":   PN = "N30"  !CDS_PN = "N30";
"G3_TXN9||SATA31_TXN":   PN = "U30"  !CDS_PN = "U30";
"G3_TXN10||SATA32_TXN":   PN = "R33"  !CDS_PN = "R33";
"G3_TXN11||SATA33_TXN":   PN = "N33"  !CDS_PN = "N33";
"G3_TXN12||SATA34_TXN":   PN = "U33"  !CDS_PN = "U33";
"G3_TXN13||SATA35_TXN":   PN = "P36"  !CDS_PN = "P36";
"G3_TXN14||SATA36_TXN":   PN = "T36"  !CDS_PN = "T36";
"G3_TXN15||SATA37_TXN":   PN = "V36"  !CDS_PN = "V36";
"G3_TXP0||SATA20_TXP":   PN = "U23"  !CDS_PN = "U23";
"G3_TXP1||SATA21_TXP":   PN = "R23"  !CDS_PN = "R23";
"G3_TXP2||SATA22_TXP":   PN = "W23"  !CDS_PN = "W23";
"G3_TXP3||SATA23_TXP":   PN = "U26"  !CDS_PN = "U26";
"G3_TXP4||SATA24_TXP":   PN = "R26"  !CDS_PN = "R26";
"G3_TXP5||SATA25_TXP":   PN = "N26"  !CDS_PN = "N26";
"G3_TXP6||SATA26_TXP":   PN = "W26"  !CDS_PN = "W26";
"G3_TXP7||SATA27_TXP":   PN = "R29"  !CDS_PN = "R29";
"G3_TXP8||SATA30_TXP":   PN = "N29"  !CDS_PN = "N29";
"G3_TXP9||SATA31_TXP":   PN = "U29"  !CDS_PN = "U29";
"G3_TXP10||SATA32_TXP":   PN = "R32"  !CDS_PN = "R32";
"G3_TXP11||SATA33_TXP":   PN = "N32"  !CDS_PN = "N32";
"G3_TXP12||SATA34_TXP":   PN = "U32"  !CDS_PN = "U32";
"G3_TXP13||SATA35_TXP":   PN = "P35"  !CDS_PN = "P35";
"G3_TXP14||SATA36_TXP":   PN = "T35"  !CDS_PN = "T35";
"G3_TXP15||SATA37_TXP":   PN = "V35"  !CDS_PN = "V35";
DRAWING = "@t6g_mb_lib.t6g(sch_1):page24";
BODY = "GENOA_SP5","I148": #LOCATION = "U25" !CDS_LOCATION = "U25" &SEC = "15" #&CDS_SEC = "15";
"P0_RXN0||SATA00_RXN":   PN = "BW53"  !CDS_PN = "BW53";
"P0_RXN1||SATA01_RXN":   PN = "CA53"  !CDS_PN = "CA53";
"P0_RXN2||SATA02_RXN":   PN = "BU53"  !CDS_PN = "BU53";
"P0_RXN3||SATA03_RXN":   PN = "BW50"  !CDS_PN = "BW50";
"P0_RXN4||SATA04_RXN":   PN = "CA50"  !CDS_PN = "CA50";
"P0_RXN5||SATA05_RXN":   PN = "BU50"  !CDS_PN = "BU50";
"P0_RXN6||SATA06_RXN":   PN = "BW47"  !CDS_PN = "BW47";
"P0_RXN7||SATA07_RXN":   PN = "CA47"  !CDS_PN = "CA47";
"P0_RXN8||SATA10_RXN":   PN = "BU47"  !CDS_PN = "BU47";
"P0_RXN9||SATA11_RXN":   PN = "BW44"  !CDS_PN = "BW44";
"P0_RXN10||SATA12_RXN":   PN = "CA44"  !CDS_PN = "CA44";
"P0_RXN11||SATA13_RXN":   PN = "BU44"  !CDS_PN = "BU44";
"P0_RXN12||SATA14_RXN":   PN = "BY41"  !CDS_PN = "BY41";
"P0_RXN13||SATA15_RXN":   PN = "CB41"  !CDS_PN = "CB41";
"P0_RXN14||SATA16_RXN":   PN = "BV41"  !CDS_PN = "BV41";
"P0_RXN15||SATA17_RXN":   PN = "BT41"  !CDS_PN = "BT41";
"P0_RXP0||SATA00_RXP":   PN = "BW52"  !CDS_PN = "BW52";
"P0_RXP1||SATA01_RXP":   PN = "CA52"  !CDS_PN = "CA52";
"P0_RXP2||SATA02_RXP":   PN = "BU52"  !CDS_PN = "BU52";
"P0_RXP3||SATA03_RXP":   PN = "BW49"  !CDS_PN = "BW49";
"P0_RXP4||SATA04_RXP":   PN = "CA49"  !CDS_PN = "CA49";
"P0_RXP5||SATA05_RXP":   PN = "BU49"  !CDS_PN = "BU49";
"P0_RXP6||SATA06_RXP":   PN = "BW46"  !CDS_PN = "BW46";
"P0_RXP7||SATA07_RXP":   PN = "CA46"  !CDS_PN = "CA46";
"P0_RXP8||SATA10_RXP":   PN = "BU46"  !CDS_PN = "BU46";
"P0_RXP9||SATA11_RXP":   PN = "BW43"  !CDS_PN = "BW43";
"P0_RXP10||SATA12_RXP":   PN = "CA43"  !CDS_PN = "CA43";
"P0_RXP11||SATA13_RXP":   PN = "BU43"  !CDS_PN = "BU43";
"P0_RXP12||SATA14_RXP":   PN = "BY40"  !CDS_PN = "BY40";
"P0_RXP13||SATA15_RXP":   PN = "CB40"  !CDS_PN = "CB40";
"P0_RXP14||SATA16_RXP":   PN = "BV40"  !CDS_PN = "BV40";
"P0_RXP15||SATA17_RXP":   PN = "BT40"  !CDS_PN = "BT40";
"P0_TXN0||SATA00_TXN":   PN = "CN52"  !CDS_PN = "CN52";
"P0_TXN1||SATA01_TXN":   PN = "CR52"  !CDS_PN = "CR52";
"P0_TXN2||SATA02_TXN":   PN = "CL52"  !CDS_PN = "CL52";
"P0_TXN3||SATA03_TXN":   PN = "CN49"  !CDS_PN = "CN49";
"P0_TXN4||SATA04_TXN":   PN = "CR49"  !CDS_PN = "CR49";
"P0_TXN5||SATA05_TXN":   PN = "CU49"  !CDS_PN = "CU49";
"P0_TXN6||SATA06_TXN":   PN = "CL49"  !CDS_PN = "CL49";
"P0_TXN7||SATA07_TXN":   PN = "CR46"  !CDS_PN = "CR46";
"P0_TXN8||SATA10_TXN":   PN = "CU46"  !CDS_PN = "CU46";
"P0_TXN9||SATA11_TXN":   PN = "CN46"  !CDS_PN = "CN46";
"P0_TXN10||SATA12_TXN":   PN = "CR43"  !CDS_PN = "CR43";
"P0_TXN11||SATA13_TXN":   PN = "CU43"  !CDS_PN = "CU43";
"P0_TXN12||SATA14_TXN":   PN = "CN43"  !CDS_PN = "CN43";
"P0_TXN13||SATA15_TXN":   PN = "CT40"  !CDS_PN = "CT40";
"P0_TXN14||SATA16_TXN":   PN = "CP40"  !CDS_PN = "CP40";
"P0_TXN15||SATA17_TXN":   PN = "CM40"  !CDS_PN = "CM40";
"P0_TXP0||SATA00_TXP":   PN = "CN53"  !CDS_PN = "CN53";
"P0_TXP1||SATA01_TXP":   PN = "CR53"  !CDS_PN = "CR53";
"P0_TXP2||SATA02_TXP":   PN = "CL53"  !CDS_PN = "CL53";
"P0_TXP3||SATA03_TXP":   PN = "CN50"  !CDS_PN = "CN50";
"P0_TXP4||SATA04_TXP":   PN = "CR50"  !CDS_PN = "CR50";
"P0_TXP5||SATA05_TXP":   PN = "CU50"  !CDS_PN = "CU50";
"P0_TXP6||SATA06_TXP":   PN = "CL50"  !CDS_PN = "CL50";
"P0_TXP7||SATA07_TXP":   PN = "CR47"  !CDS_PN = "CR47";
"P0_TXP8||SATA10_TXP":   PN = "CU47"  !CDS_PN = "CU47";
"P0_TXP9||SATA11_TXP":   PN = "CN47"  !CDS_PN = "CN47";
"P0_TXP10||SATA12_TXP":   PN = "CR44"  !CDS_PN = "CR44";
"P0_TXP11||SATA13_TXP":   PN = "CU44"  !CDS_PN = "CU44";
"P0_TXP12||SATA14_TXP":   PN = "CN44"  !CDS_PN = "CN44";
"P0_TXP13||SATA15_TXP":   PN = "CT41"  !CDS_PN = "CT41";
"P0_TXP14||SATA16_TXP":   PN = "CP41"  !CDS_PN = "CP41";
"P0_TXP15||SATA17_TXP":   PN = "CM41"  !CDS_PN = "CM41";
BODY = "GENOA_SP5","I149": #LOCATION = "U25" !CDS_LOCATION = "U25" &SEC = "16" #&CDS_SEC = "16";
"P1_RXN0":   PN = "CE53"  !CDS_PN = "CE53";
"P1_RXN1":   PN = "CG53"  !CDS_PN = "CG53";
"P1_RXN2":   PN = "CC53"  !CDS_PN = "CC53";
"P1_RXN3":   PN = "CE50"  !CDS_PN = "CE50";
"P1_RXN4":   PN = "CG50"  !CDS_PN = "CG50";
"P1_RXN5":   PN = "CC50"  !CDS_PN = "CC50";
"P1_RXN6":   PN = "CE47"  !CDS_PN = "CE47";
"P1_RXN7":   PN = "CG47"  !CDS_PN = "CG47";
"P1_RXN8":   PN = "CC47"  !CDS_PN = "CC47";
"P1_RXN9":   PN = "CE44"  !CDS_PN = "CE44";
"P1_RXN10":   PN = "CG44"  !CDS_PN = "CG44";
"P1_RXN11":   PN = "CJ44"  !CDS_PN = "CJ44";
"P1_RXN12":   PN = "CC44"  !CDS_PN = "CC44";
"P1_RXN13":   PN = "CH41"  !CDS_PN = "CH41";
"P1_RXN14":   PN = "CF41"  !CDS_PN = "CF41";
"P1_RXN15":   PN = "CD41"  !CDS_PN = "CD41";
"P1_RXP0":   PN = "CE52"  !CDS_PN = "CE52";
"P1_RXP1":   PN = "CG52"  !CDS_PN = "CG52";
"P1_RXP2":   PN = "CC52"  !CDS_PN = "CC52";
"P1_RXP3":   PN = "CE49"  !CDS_PN = "CE49";
"P1_RXP4":   PN = "CG49"  !CDS_PN = "CG49";
"P1_RXP5":   PN = "CC49"  !CDS_PN = "CC49";
"P1_RXP6":   PN = "CE46"  !CDS_PN = "CE46";
"P1_RXP7":   PN = "CG46"  !CDS_PN = "CG46";
"P1_RXP8":   PN = "CC46"  !CDS_PN = "CC46";
"P1_RXP9":   PN = "CE43"  !CDS_PN = "CE43";
"P1_RXP10":   PN = "CG43"  !CDS_PN = "CG43";
"P1_RXP11":   PN = "CJ43"  !CDS_PN = "CJ43";
"P1_RXP12":   PN = "CC43"  !CDS_PN = "CC43";
"P1_RXP13":   PN = "CH40"  !CDS_PN = "CH40";
"P1_RXP14":   PN = "CF40"  !CDS_PN = "CF40";
"P1_RXP15":   PN = "CD40"  !CDS_PN = "CD40";
"P1_TXN0":   PN = "CU52"  !CDS_PN = "CU52";
"P1_TXN1":   PN = "DA52"  !CDS_PN = "DA52";
"P1_TXN2":   PN = "DC52"  !CDS_PN = "DC52";
"P1_TXN3":   PN = "CW52"  !CDS_PN = "CW52";
"P1_TXN4":   PN = "DA49"  !CDS_PN = "DA49";
"P1_TXN5":   PN = "DC49"  !CDS_PN = "DC49";
"P1_TXN6":   PN = "CW49"  !CDS_PN = "CW49";
"P1_TXN7":   PN = "DA46"  !CDS_PN = "DA46";
"P1_TXN8":   PN = "DC46"  !CDS_PN = "DC46";
"P1_TXN9":   PN = "CW46"  !CDS_PN = "CW46";
"P1_TXN10":   PN = "DA43"  !CDS_PN = "DA43";
"P1_TXN11":   PN = "DC43"  !CDS_PN = "DC43";
"P1_TXN12":   PN = "CW43"  !CDS_PN = "CW43";
"P1_TXN13":   PN = "DB40"  !CDS_PN = "DB40";
"P1_TXN14":   PN = "CY40"  !CDS_PN = "CY40";
"P1_TXN15":   PN = "CV40"  !CDS_PN = "CV40";
"P1_TXP0":   PN = "CU53"  !CDS_PN = "CU53";
"P1_TXP1":   PN = "DA53"  !CDS_PN = "DA53";
"P1_TXP2":   PN = "DC53"  !CDS_PN = "DC53";
"P1_TXP3":   PN = "CW53"  !CDS_PN = "CW53";
"P1_TXP4":   PN = "DA50"  !CDS_PN = "DA50";
"P1_TXP5":   PN = "DC50"  !CDS_PN = "DC50";
"P1_TXP6":   PN = "CW50"  !CDS_PN = "CW50";
"P1_TXP7":   PN = "DA47"  !CDS_PN = "DA47";
"P1_TXP8":   PN = "DC47"  !CDS_PN = "DC47";
"P1_TXP9":   PN = "CW47"  !CDS_PN = "CW47";
"P1_TXP10":   PN = "DA44"  !CDS_PN = "DA44";
"P1_TXP11":   PN = "DC44"  !CDS_PN = "DC44";
"P1_TXP12":   PN = "CW44"  !CDS_PN = "CW44";
"P1_TXP13":   PN = "DB41"  !CDS_PN = "DB41";
"P1_TXP14":   PN = "CY41"  !CDS_PN = "CY41";
"P1_TXP15":   PN = "CV41"  !CDS_PN = "CV41";
DRAWING = "@t6g_mb_lib.t6g(sch_1):page25";
BODY = "GENOA_SP5","I147": #LOCATION = "U25" !CDS_LOCATION = "U25" &SEC = "17" #&CDS_SEC = "17";
"P2_RXN0":   PN = "CM36"  !CDS_PN = "CM36";
"P2_RXN1":   PN = "CP36"  !CDS_PN = "CP36";
"P2_RXN2":   PN = "CT36"  !CDS_PN = "CT36";
"P2_RXN3":   PN = "CN33"  !CDS_PN = "CN33";
"P2_RXN4":   PN = "CU33"  !CDS_PN = "CU33";
"P2_RXN5":   PN = "CR33"  !CDS_PN = "CR33";
"P2_RXN6":   PN = "CN30"  !CDS_PN = "CN30";
"P2_RXN7":   PN = "CU30"  !CDS_PN = "CU30";
"P2_RXN8":   PN = "CR30"  !CDS_PN = "CR30";
"P2_RXN9":   PN = "CL27"  !CDS_PN = "CL27";
"P2_RXN10":   PN = "CU27"  !CDS_PN = "CU27";
"P2_RXN11":   PN = "CR27"  !CDS_PN = "CR27";
"P2_RXN12":   PN = "CN27"  !CDS_PN = "CN27";
"P2_RXN13":   PN = "CL24"  !CDS_PN = "CL24";
"P2_RXN14":   PN = "CR24"  !CDS_PN = "CR24";
"P2_RXN15":   PN = "CN24"  !CDS_PN = "CN24";
"P2_RXP0":   PN = "CM35"  !CDS_PN = "CM35";
"P2_RXP1":   PN = "CP35"  !CDS_PN = "CP35";
"P2_RXP2":   PN = "CT35"  !CDS_PN = "CT35";
"P2_RXP3":   PN = "CN32"  !CDS_PN = "CN32";
"P2_RXP4":   PN = "CU32"  !CDS_PN = "CU32";
"P2_RXP5":   PN = "CR32"  !CDS_PN = "CR32";
"P2_RXP6":   PN = "CN29"  !CDS_PN = "CN29";
"P2_RXP7":   PN = "CU29"  !CDS_PN = "CU29";
"P2_RXP8":   PN = "CR29"  !CDS_PN = "CR29";
"P2_RXP9":   PN = "CL26"  !CDS_PN = "CL26";
"P2_RXP10":   PN = "CU26"  !CDS_PN = "CU26";
"P2_RXP11":   PN = "CR26"  !CDS_PN = "CR26";
"P2_RXP12":   PN = "CN26"  !CDS_PN = "CN26";
"P2_RXP13":   PN = "CL23"  !CDS_PN = "CL23";
"P2_RXP14":   PN = "CR23"  !CDS_PN = "CR23";
"P2_RXP15":   PN = "CN23"  !CDS_PN = "CN23";
"P2_TXN0":   PN = "BT35"  !CDS_PN = "BT35";
"P2_TXN1":   PN = "BV35"  !CDS_PN = "BV35";
"P2_TXN2":   PN = "CB35"  !CDS_PN = "CB35";
"P2_TXN3":   PN = "BY35"  !CDS_PN = "BY35";
"P2_TXN4":   PN = "BU32"  !CDS_PN = "BU32";
"P2_TXN5":   PN = "CA32"  !CDS_PN = "CA32";
"P2_TXN6":   PN = "BW32"  !CDS_PN = "BW32";
"P2_TXN7":   PN = "BU29"  !CDS_PN = "BU29";
"P2_TXN8":   PN = "CA29"  !CDS_PN = "CA29";
"P2_TXN9":   PN = "BW29"  !CDS_PN = "BW29";
"P2_TXN10":   PN = "BU26"  !CDS_PN = "BU26";
"P2_TXN11":   PN = "CA26"  !CDS_PN = "CA26";
"P2_TXN12":   PN = "BW26"  !CDS_PN = "BW26";
"P2_TXN13":   PN = "BU23"  !CDS_PN = "BU23";
"P2_TXN14":   PN = "CA23"  !CDS_PN = "CA23";
"P2_TXN15":   PN = "BW23"  !CDS_PN = "BW23";
"P2_TXP0":   PN = "BT36"  !CDS_PN = "BT36";
"P2_TXP1":   PN = "BV36"  !CDS_PN = "BV36";
"P2_TXP2":   PN = "CB36"  !CDS_PN = "CB36";
"P2_TXP3":   PN = "BY36"  !CDS_PN = "BY36";
"P2_TXP4":   PN = "BU33"  !CDS_PN = "BU33";
"P2_TXP5":   PN = "CA33"  !CDS_PN = "CA33";
"P2_TXP6":   PN = "BW33"  !CDS_PN = "BW33";
"P2_TXP7":   PN = "BU30"  !CDS_PN = "BU30";
"P2_TXP8":   PN = "CA30"  !CDS_PN = "CA30";
"P2_TXP9":   PN = "BW30"  !CDS_PN = "BW30";
"P2_TXP10":   PN = "BU27"  !CDS_PN = "BU27";
"P2_TXP11":   PN = "CA27"  !CDS_PN = "CA27";
"P2_TXP12":   PN = "BW27"  !CDS_PN = "BW27";
"P2_TXP13":   PN = "BU24"  !CDS_PN = "BU24";
"P2_TXP14":   PN = "CA24"  !CDS_PN = "CA24";
"P2_TXP15":   PN = "BW24"  !CDS_PN = "BW24";
BODY = "GENOA_SP5","I148": #LOCATION = "U25" !CDS_LOCATION = "U25" &SEC = "18" #&CDS_SEC = "18";
"P3_RXN0":   PN = "CV36"  !CDS_PN = "CV36";
"P3_RXN1":   PN = "CY36"  !CDS_PN = "CY36";
"P3_RXN2":   PN = "DB36"  !CDS_PN = "DB36";
"P3_RXN3":   PN = "CW33"  !CDS_PN = "CW33";
"P3_RXN4":   PN = "DC33"  !CDS_PN = "DC33";
"P3_RXN5":   PN = "DA33"  !CDS_PN = "DA33";
"P3_RXN6":   PN = "CW30"  !CDS_PN = "CW30";
"P3_RXN7":   PN = "DC30"  !CDS_PN = "DC30";
"P3_RXN8":   PN = "DA30"  !CDS_PN = "DA30";
"P3_RXN9":   PN = "CW27"  !CDS_PN = "CW27";
"P3_RXN10":   PN = "DC27"  !CDS_PN = "DC27";
"P3_RXN11":   PN = "DA27"  !CDS_PN = "DA27";
"P3_RXN12":   PN = "CW24"  !CDS_PN = "CW24";
"P3_RXN13":   PN = "DC24"  !CDS_PN = "DC24";
"P3_RXN14":   PN = "DA24"  !CDS_PN = "DA24";
"P3_RXN15":   PN = "CU24"  !CDS_PN = "CU24";
"P3_RXP0":   PN = "CV35"  !CDS_PN = "CV35";
"P3_RXP1":   PN = "CY35"  !CDS_PN = "CY35";
"P3_RXP2":   PN = "DB35"  !CDS_PN = "DB35";
"P3_RXP3":   PN = "CW32"  !CDS_PN = "CW32";
"P3_RXP4":   PN = "DC32"  !CDS_PN = "DC32";
"P3_RXP5":   PN = "DA32"  !CDS_PN = "DA32";
"P3_RXP6":   PN = "CW29"  !CDS_PN = "CW29";
"P3_RXP7":   PN = "DC29"  !CDS_PN = "DC29";
"P3_RXP8":   PN = "DA29"  !CDS_PN = "DA29";
"P3_RXP9":   PN = "CW26"  !CDS_PN = "CW26";
"P3_RXP10":   PN = "DC26"  !CDS_PN = "DC26";
"P3_RXP11":   PN = "DA26"  !CDS_PN = "DA26";
"P3_RXP12":   PN = "CW23"  !CDS_PN = "CW23";
"P3_RXP13":   PN = "DC23"  !CDS_PN = "DC23";
"P3_RXP14":   PN = "DA23"  !CDS_PN = "DA23";
"P3_RXP15":   PN = "CU23"  !CDS_PN = "CU23";
"P3_TXN0":   PN = "CD35"  !CDS_PN = "CD35";
"P3_TXN1":   PN = "CF35"  !CDS_PN = "CF35";
"P3_TXN2":   PN = "CH35"  !CDS_PN = "CH35";
"P3_TXN3":   PN = "CC32"  !CDS_PN = "CC32";
"P3_TXN4":   PN = "CJ32"  !CDS_PN = "CJ32";
"P3_TXN5":   PN = "CG32"  !CDS_PN = "CG32";
"P3_TXN6":   PN = "CE32"  !CDS_PN = "CE32";
"P3_TXN7":   PN = "CC29"  !CDS_PN = "CC29";
"P3_TXN8":   PN = "CG29"  !CDS_PN = "CG29";
"P3_TXN9":   PN = "CE29"  !CDS_PN = "CE29";
"P3_TXN10":   PN = "CC26"  !CDS_PN = "CC26";
"P3_TXN11":   PN = "CG26"  !CDS_PN = "CG26";
"P3_TXN12":   PN = "CE26"  !CDS_PN = "CE26";
"P3_TXN13":   PN = "CC23"  !CDS_PN = "CC23";
"P3_TXN14":   PN = "CG23"  !CDS_PN = "CG23";
"P3_TXN15":   PN = "CE23"  !CDS_PN = "CE23";
"P3_TXP0":   PN = "CD36"  !CDS_PN = "CD36";
"P3_TXP1":   PN = "CF36"  !CDS_PN = "CF36";
"P3_TXP2":   PN = "CH36"  !CDS_PN = "CH36";
"P3_TXP3":   PN = "CC33"  !CDS_PN = "CC33";
"P3_TXP4":   PN = "CJ33"  !CDS_PN = "CJ33";
"P3_TXP5":   PN = "CG33"  !CDS_PN = "CG33";
"P3_TXP6":   PN = "CE33"  !CDS_PN = "CE33";
"P3_TXP7":   PN = "CC30"  !CDS_PN = "CC30";
"P3_TXP8":   PN = "CG30"  !CDS_PN = "CG30";
"P3_TXP9":   PN = "CE30"  !CDS_PN = "CE30";
"P3_TXP10":   PN = "CC27"  !CDS_PN = "CC27";
"P3_TXP11":   PN = "CG27"  !CDS_PN = "CG27";
"P3_TXP12":   PN = "CE27"  !CDS_PN = "CE27";
"P3_TXP13":   PN = "CC24"  !CDS_PN = "CC24";
"P3_TXP14":   PN = "CG24"  !CDS_PN = "CG24";
"P3_TXP15":   PN = "CE24"  !CDS_PN = "CE24";
DRAWING = "@t6g_mb_lib.t6g(sch_1):page26";
BODY = "GENOA_SP5","I59": #LOCATION = "U25" !CDS_LOCATION = "U25" &SEC = "19" #&CDS_SEC = "19";
"P4_RXN0":   PN = "DG53"  !CDS_PN = "DG53";
"P4_RXN1":   PN = "DG50"  !CDS_PN = "DG50";
"P4_RXN2":   PN = "DG47"  !CDS_PN = "DG47";
"P4_RXN3":   PN = "DG44"  !CDS_PN = "DG44";
"P4_RXP0":   PN = "DG54"  !CDS_PN = "DG54";
"P4_RXP1":   PN = "DG51"  !CDS_PN = "DG51";
"P4_RXP2":   PN = "DG48"  !CDS_PN = "DG48";
"P4_RXP3":   PN = "DG45"  !CDS_PN = "DG45";
"P4_TXN0":   PN = "DE52"  !CDS_PN = "DE52";
"P4_TXN1":   PN = "DE49"  !CDS_PN = "DE49";
"P4_TXN2":   PN = "DE46"  !CDS_PN = "DE46";
"P4_TXN3":   PN = "DE43"  !CDS_PN = "DE43";
"P4_TXP0":   PN = "DE53"  !CDS_PN = "DE53";
"P4_TXP1":   PN = "DE50"  !CDS_PN = "DE50";
"P4_TXP2":   PN = "DE47"  !CDS_PN = "DE47";
"P4_TXP3":   PN = "DE44"  !CDS_PN = "DE44";
"P5_RXN2":   PN = "E44"  !CDS_PN = "E44";
"P5_RXN3":   PN = "E41"  !CDS_PN = "E41";
"P5_RXP2":   PN = "E43"  !CDS_PN = "E43";
"P5_RXP3":   PN = "E40"  !CDS_PN = "E40";
"P5_TXN2":   PN = "C45"  !CDS_PN = "C45";
"P5_TXN3":   PN = "C42"  !CDS_PN = "C42";
"P5_TXP2":   PN = "C44"  !CDS_PN = "C44";
"P5_TXP3":   PN = "C41"  !CDS_PN = "C41";
"WAFL_RXN0||P5_RXN0":   PN = "E50"  !CDS_PN = "E50";
"WAFL_RXN1||P5_RXN1":   PN = "E47"  !CDS_PN = "E47";
"WAFL_RXP0||P5_RXP0":   PN = "E49"  !CDS_PN = "E49";
"WAFL_RXP1||P5_RXP1":   PN = "E46"  !CDS_PN = "E46";
"WAFL_TXN0||P5_TXN0":   PN = "C51"  !CDS_PN = "C51";
"WAFL_TXN1||P5_TXN1":   PN = "C48"  !CDS_PN = "C48";
"WAFL_TXP0||P5_TXP0":   PN = "C50"  !CDS_PN = "C50";
"WAFL_TXP1||P5_TXP1":   PN = "C47"  !CDS_PN = "C47";
BODY = "Q_CAP_DIFFBUS","I156": #LOCATION = "C2077" !CDS_LOCATION = "C2077" &SEC = "1" #&CDS_SEC = "1";
"1":   PN = "1"  !CDS_PN = "1";
"2":   PN = "2"  !CDS_PN = "2";
BODY = "Q_CAP_DIFFBUS","I157": #LOCATION = "C2078" !CDS_LOCATION = "C2078" &SEC = "1" #&CDS_SEC = "1";
"1":   PN = "1"  !CDS_PN = "1";
"2":   PN = "2"  !CDS_PN = "2";
DRAWING = "@t6g_mb_lib.t6g(sch_1):page27";
BODY = "Q_RES","I170": #LOCATION = "R404" !CDS_LOCATION = "R404" &SEC = "1" #&CDS_SEC = "1";
"A":   PN = "1"  !CDS_PN = "1";
"B":   PN = "2"  !CDS_PN = "2";
BODY = "GENOA_SP5","I227": #LOCATION = "U25" !CDS_LOCATION = "U25" &SEC = "20" #&CDS_SEC = "20";
"ALERT_L":   PN = "A68"  !CDS_PN = "A68";
"AZ_BITCLK":   PN = "C32"  !CDS_PN = "C32";
"AZ_RST_L||SW_MDATA1":   PN = "A34"  !CDS_PN = "A34";
"AZ_SDIN0||SW_MDATA3":   PN = "C33"  !CDS_PN = "C33";
"AZ_SDIN1||SW_MCLK":   PN = "D33"  !CDS_PN = "D33";
"AZ_SDIN2||SW_MDATA0":   PN = "A33"  !CDS_PN = "A33";
"AZ_SDOUT||SW_MDATA2":   PN = "A32"  !CDS_PN = "A32";
"AZ_SYNC":   PN = "D32"  !CDS_PN = "D32";
"BP0":   PN = "C63"  !CDS_PN = "C63";
"BP1":   PN = "C62"  !CDS_PN = "C62";
"BP2":   PN = "A63"  !CDS_PN = "A63";
"BP3":   PN = "A62"  !CDS_PN = "A62";
"CORETYPE0":   PN = "C70"  !CDS_PN = "C70";
"CORETYPE1":   PN = "B69"  !CDS_PN = "B69";
"CORETYPE2":   PN = "D68"  !CDS_PN = "D68";
"CPU_PRESENT_L":   PN = "B66"  !CDS_PN = "B66";
"DBREQ_L":   PN = "C16"  !CDS_PN = "C16";
"PCC0_L":   PN = "C22"  !CDS_PN = "C22";
"PCC1_L":   PN = "DG72"  !CDS_PN = "DG72";
"PROCHOT_L":   PN = "A69"  !CDS_PN = "A69";
"RTC_LDO_SELECT":   PN = "DH8"  !CDS_PN = "DH8";
"SA0":   PN = "DJ55"  !CDS_PN = "DJ55";
"SA1":   PN = "DJ56"  !CDS_PN = "DJ56";
"SIC":   PN = "DJ71"  !CDS_PN = "DJ71";
"SID":   PN = "DH71"  !CDS_PN = "DH71";
"SP5R1":   PN = "C19"  !CDS_PN = "C19";
"SP5R2":   PN = "C68"  !CDS_PN = "C68";
"SP5R3":   PN = "DH73"  !CDS_PN = "DH73";
"SP5R4":   PN = "DH10"  !CDS_PN = "DH10";
"SVC0":   PN = "A23"  !CDS_PN = "A23";
"SVC1":   PN = "DJ72"  !CDS_PN = "DJ72";
"SVD0":   PN = "A22"  !CDS_PN = "A22";
"SVD1":   PN = "DH72"  !CDS_PN = "DH72";
"SVT0":   PN = "B21"  !CDS_PN = "B21";
"SVT1":   PN = "DG73"  !CDS_PN = "DG73";
"TCK":   PN = "B17"  !CDS_PN = "B17";
"TDI":   PN = "C17"  !CDS_PN = "C17";
"TDO":   PN = "C18"  !CDS_PN = "C18";
"TEST4_CCD0":   PN = "AA50"  !CDS_PN = "AA50";
"TEST4_CCD1":   PN = "CJ28"  !CDS_PN = "CJ28";
"TEST4_CCD2":   PN = "CJ48"  !CDS_PN = "CJ48";
"TEST4_CCD3":   PN = "AA30"  !CDS_PN = "AA30";
"TEST4_CCD4":   PN = "AA52"  !CDS_PN = "AA52";
"TEST4_CCD5":   PN = "CJ26"  !CDS_PN = "CJ26";
"TEST4_CCD6":   PN = "CJ50"  !CDS_PN = "CJ50";
"TEST4_CCD7":   PN = "AA27"  !CDS_PN = "AA27";
"TEST4_CCD8":   PN = "AA48"  !CDS_PN = "AA48";
"TEST4_CCD9":   PN = "CK30"  !CDS_PN = "CK30";
"TEST4_CCD10":   PN = "CJ47"  !CDS_PN = "CJ47";
"TEST4_CCD11":   PN = "AA28"  !CDS_PN = "AA28";
"TEST4_IOD":   PN = "AA25"  !CDS_PN = "AA25";
"TEST5_CCD0":   PN = "AA51"  !CDS_PN = "AA51";
"TEST5_CCD1":   PN = "CJ27"  !CDS_PN = "CJ27";
"TEST5_CCD2":   PN = "CJ49"  !CDS_PN = "CJ49";
"TEST5_CCD3":   PN = "Y30"  !CDS_PN = "Y30";
"TEST5_CCD4":   PN = "AA53"  !CDS_PN = "AA53";
"TEST5_CCD5":   PN = "CJ25"  !CDS_PN = "CJ25";
"TEST5_CCD6":   PN = "CJ51"  !CDS_PN = "CJ51";
"TEST5_CCD7":   PN = "AA26"  !CDS_PN = "AA26";
"TEST5_CCD8":   PN = "Y47"  !CDS_PN = "Y47";
"TEST5_CCD9":   PN = "CK29"  !CDS_PN = "CK29";
"TEST5_CCD10":   PN = "CK47"  !CDS_PN = "CK47";
"TEST5_CCD11":   PN = "Y29"  !CDS_PN = "Y29";
"TEST5_IOD":   PN = "AA24"  !CDS_PN = "AA24";
"TEST6_CCD0":   PN = "AA46"  !CDS_PN = "AA46";
"TEST6_CCD1":   PN = "CJ30"  !CDS_PN = "CJ30";
"TEST6_CCD2":   PN = "CJ46"  !CDS_PN = "CJ46";
"TEST6_CCD3":   PN = "Y46"  !CDS_PN = "Y46";
"TEST6_IOD":   PN = "AA49"  !CDS_PN = "AA49";
"TEST6_X3D0":   PN = "AA47"  !CDS_PN = "AA47";
"TEST6_X3D1":   PN = "CJ29"  !CDS_PN = "CJ29";
"TEST6_X3D2":   PN = "AA29"  !CDS_PN = "AA29";
"TEST6_X3D3":   PN = "CJ52"  !CDS_PN = "CJ52";
"TEST6_X3D4":   PN = "AA23"  !CDS_PN = "AA23";
"TEST6_X3D5":   PN = "CJ53"  !CDS_PN = "CJ53";
"TEST41_IOD":   PN = "W31"  !CDS_PN = "W31";
"TEST47_CCD0":   PN = "B60"  !CDS_PN = "B60";
"TEST47_CCD1":   PN = "CJ24"  !CDS_PN = "CJ24";
"TEST47_CCD2":   PN = "CK46"  !CDS_PN = "CK46";
"TEST47_CCD3":   PN = "E32"  !CDS_PN = "E32";
"TEST47_IOD0":   PN = "B58"  !CDS_PN = "B58";
"TEST47_IOD1":   PN = "D7"  !CDS_PN = "D7";
"TEST50_IOD":   PN = "B61"  !CDS_PN = "B61";
"THERMTRIP_L":   PN = "DJ9"  !CDS_PN = "DJ9";
"TMS":   PN = "A16"  !CDS_PN = "A16";
"TRST_L":   PN = "A17"  !CDS_PN = "A17";
"UART0_CTS_L||UART2_TXD||AGPIO135":   PN = "DJ33"  !CDS_PN = "DJ33";
"UART0_INTR||AGPIO139":   PN = "DG34"  !CDS_PN = "DG34";
"UART0_RTS_L||UART2_RXD||AGPIO137":   PN = "DF34"  !CDS_PN = "DF34";
"UART0_RXD||AGPIO136":   PN = "DG35"  !CDS_PN = "DG35";
"UART0_TXD||AGPIO138":   PN = "DJ34"  !CDS_PN = "DJ34";
"UART1_RXD||AGPIO141":   PN = "DH33"  !CDS_PN = "DH33";
"UART1_TXD||AGPIO142":   PN = "DJ32"  !CDS_PN = "DJ32";
"VDD_11_S3_SENSE":   PN = "DH3"  !CDS_PN = "DH3";
"VDD_18_S5_SENSE":   PN = "C74"  !CDS_PN = "C74";
"VDD_33_S5_SENSE":   PN = "BP53"  !CDS_PN = "BP53";
"VDDCR_CPU0_SENSE":   PN = "C2"  !CDS_PN = "C2";
"VDDCR_CPU1_SENSE":   PN = "DG3"  !CDS_PN = "DG3";
"VDDCR_SOC_SENSE":   PN = "B3"  !CDS_PN = "B3";
"VDDIO_SENSE":   PN = "BR53"  !CDS_PN = "BR53";
"VSS_SENSE_A":   PN = "C3"  !CDS_PN = "C3";
"VSS_SENSE_B":   PN = "BR54"  !CDS_PN = "BR54";
"VSS_SENSE_C":   PN = "DJ3"  !CDS_PN = "DJ3";
"VSS_SENSE_D":   PN = "B73"  !CDS_PN = "B73";
"XTRIG_L4":   PN = "C66"  !CDS_PN = "C66";
"XTRIG_L5":   PN = "C65"  !CDS_PN = "C65";
"XTRIG_L6":   PN = "A66"  !CDS_PN = "A66";
"XTRIG_L7":   PN = "A65"  !CDS_PN = "A65";
BODY = "Q_RES","I279": #LOCATION = "R405" !CDS_LOCATION = "R405" &SEC = "1" #&CDS_SEC = "1";
"A":   PN = "1"  !CDS_PN = "1";
"B":   PN = "2"  !CDS_PN = "2";
BODY = "Q_RES","I288": #LOCATION = "R2318" !CDS_LOCATION = "R2318" &SEC = "1" #&CDS_SEC = "1";
"A":   PN = "1"  !CDS_PN = "1";
"B":   PN = "2"  !CDS_PN = "2";
BODY = "Q_RES","I294": #LOCATION = "R403" !CDS_LOCATION = "R403" &SEC = "1" #&CDS_SEC = "1";
"A":   PN = "1"  !CDS_PN = "1";
"B":   PN = "2"  !CDS_PN = "2";
BODY = "Q_CAP","I295": #LOCATION = "C212" !CDS_LOCATION = "C212" &SEC = "1" #&CDS_SEC = "1";
"A":   PN = "1"  !CDS_PN = "1";
"B":   PN = "2"  !CDS_PN = "2";
BODY = "Q_RES","I296": #LOCATION = "R402" !CDS_LOCATION = "R402" &SEC = "1" #&CDS_SEC = "1";
"A":   PN = "1"  !CDS_PN = "1";
"B":   PN = "2"  !CDS_PN = "2";
BODY = "Q_CAP","I297": #LOCATION = "C211" !CDS_LOCATION = "C211" &SEC = "1" #&CDS_SEC = "1";
"A":   PN = "1"  !CDS_PN = "1";
"B":   PN = "2"  !CDS_PN = "2";
BODY = "Q_RES","I300": #LOCATION = "R401" !CDS_LOCATION = "R401" &SEC = "1" #&CDS_SEC = "1";
"A":   PN = "1"  !CDS_PN = "1";
"B":   PN = "2"  !CDS_PN = "2";
BODY = "Q_RES","I301": #LOCATION = "R400" !CDS_LOCATION = "R400" &SEC = "1" #&CDS_SEC = "1";
"A":   PN = "1"  !CDS_PN = "1";
"B":   PN = "2"  !CDS_PN = "2";
BODY = "Q_CAP","I302": #LOCATION = "C210" !CDS_LOCATION = "C210" &SEC = "1" #&CDS_SEC = "1";
"A":   PN = "1"  !CDS_PN = "1";
"B":   PN = "2"  !CDS_PN = "2";
BODY = "Q_CAP","I303": #LOCATION = "C209" !CDS_LOCATION = "C209" &SEC = "1" #&CDS_SEC = "1";
"A":   PN = "1"  !CDS_PN = "1";
"B":   PN = "2"  !CDS_PN = "2";
BODY = "Q_RES","I304": #LOCATION = "R399" !CDS_LOCATION = "R399" &SEC = "1" #&CDS_SEC = "1";
"A":   PN = "1"  !CDS_PN = "1";
"B":   PN = "2"  !CDS_PN = "2";
BODY = "Q_RES","I305": #LOCATION = "R398" !CDS_LOCATION = "R398" &SEC = "1" #&CDS_SEC = "1";
"A":   PN = "1"  !CDS_PN = "1";
"B":   PN = "2"  !CDS_PN = "2";
BODY = "Q_CAP","I306": #LOCATION = "C208" !CDS_LOCATION = "C208" &SEC = "1" #&CDS_SEC = "1";
"A":   PN = "1"  !CDS_PN = "1";
"B":   PN = "2"  !CDS_PN = "2";
BODY = "Q_CAP","I307": #LOCATION = "C207" !CDS_LOCATION = "C207" &SEC = "1" #&CDS_SEC = "1";
"A":   PN = "1"  !CDS_PN = "1";
"B":   PN = "2"  !CDS_PN = "2";
BODY = "Q_RES","I318": #LOCATION = "PR59" !CDS_LOCATION = "PR59" &SEC = "1" #&CDS_SEC = "1";
"A":   PN = "1"  !CDS_PN = "1";
"B":   PN = "2"  !CDS_PN = "2";
BODY = "Q_RES","I319": #LOCATION = "PR60" !CDS_LOCATION = "PR60" &SEC = "1" #&CDS_SEC = "1";
"A":   PN = "1"  !CDS_PN = "1";
"B":   PN = "2"  !CDS_PN = "2";
BODY = "Q_RES","I322": #LOCATION = "PR303" !CDS_LOCATION = "PR303" &SEC = "1" #&CDS_SEC = "1";
"A":   PN = "1"  !CDS_PN = "1";
"B":   PN = "2"  !CDS_PN = "2";
BODY = "Q_RES","I323": #LOCATION = "PR302" !CDS_LOCATION = "PR302" &SEC = "1" #&CDS_SEC = "1";
"A":   PN = "1"  !CDS_PN = "1";
"B":   PN = "2"  !CDS_PN = "2";
BODY = "Q_RES","I334": #LOCATION = "R483" !CDS_LOCATION = "R483" &SEC = "1" #&CDS_SEC = "1";
"A":   PN = "1"  !CDS_PN = "1";
"B":   PN = "2"  !CDS_PN = "2";
BODY = "Q_RES","I335": #LOCATION = "R481" !CDS_LOCATION = "R481" &SEC = "1" #&CDS_SEC = "1";
"A":   PN = "1"  !CDS_PN = "1";
"B":   PN = "2"  !CDS_PN = "2";
BODY = "Q_RES","I336": #LOCATION = "R484" !CDS_LOCATION = "R484" &SEC = "1" #&CDS_SEC = "1";
"A":   PN = "1"  !CDS_PN = "1";
"B":   PN = "2"  !CDS_PN = "2";
BODY = "Q_RES","I337": #LOCATION = "R485" !CDS_LOCATION = "R485" &SEC = "1" #&CDS_SEC = "1";
"A":   PN = "1"  !CDS_PN = "1";
"B":   PN = "2"  !CDS_PN = "2";
BODY = "Q_RES","I346": #LOCATION = "R156" !CDS_LOCATION = "R156" &SEC = "1" #&CDS_SEC = "1";
"A":   PN = "1"  !CDS_PN = "1";
"B":   PN = "2"  !CDS_PN = "2";
BODY = "Q_RES","I347": #LOCATION = "R157" !CDS_LOCATION = "R157" &SEC = "1" #&CDS_SEC = "1";
"A":   PN = "1"  !CDS_PN = "1";
"B":   PN = "2"  !CDS_PN = "2";
BODY = "Q_RES","I348": #LOCATION = "R357" !CDS_LOCATION = "R357" &SEC = "1" #&CDS_SEC = "1";
"A":   PN = "1"  !CDS_PN = "1";
"B":   PN = "2"  !CDS_PN = "2";
BODY = "Q_RES","I349": #LOCATION = "R356" !CDS_LOCATION = "R356" &SEC = "1" #&CDS_SEC = "1";
"A":   PN = "1"  !CDS_PN = "1";
"B":   PN = "2"  !CDS_PN = "2";
BODY = "Q_RES","I353": #LOCATION = "R1204" !CDS_LOCATION = "R1204" &SEC = "1" #&CDS_SEC = "1";
"A":   PN = "1"  !CDS_PN = "1";
"B":   PN = "2"  !CDS_PN = "2";
BODY = "TP","I355": #LOCATION = "TP9" !CDS_LOCATION = "TP9" &SEC = "1" #&CDS_SEC = "1";
"TP":   PN = "1"  !CDS_PN = "1";
BODY = "TP","I356": #LOCATION = "TP8" !CDS_LOCATION = "TP8" &SEC = "1" #&CDS_SEC = "1";
"TP":   PN = "1"  !CDS_PN = "1";
BODY = "TP","I357": #LOCATION = "TP7" !CDS_LOCATION = "TP7" &SEC = "1" #&CDS_SEC = "1";
"TP":   PN = "1"  !CDS_PN = "1";
BODY = "TP","I358": #LOCATION = "TP6" !CDS_LOCATION = "TP6" &SEC = "1" #&CDS_SEC = "1";
"TP":   PN = "1"  !CDS_PN = "1";
BODY = "TP","I359": #LOCATION = "TP5" !CDS_LOCATION = "TP5" &SEC = "1" #&CDS_SEC = "1";
"TP":   PN = "1"  !CDS_PN = "1";
BODY = "TP","I360": #LOCATION = "TP4" !CDS_LOCATION = "TP4" &SEC = "1" #&CDS_SEC = "1";
"TP":   PN = "1"  !CDS_PN = "1";
BODY = "TP","I361": #LOCATION = "TP3" !CDS_LOCATION = "TP3" &SEC = "1" #&CDS_SEC = "1";
"TP":   PN = "1"  !CDS_PN = "1";
BODY = "TP","I362": #LOCATION = "TP2" !CDS_LOCATION = "TP2" &SEC = "1" #&CDS_SEC = "1";
"TP":   PN = "1"  !CDS_PN = "1";
BODY = "Q_RES","I377": #LOCATION = "R412" !CDS_LOCATION = "R412" &SEC = "1" #&CDS_SEC = "1";
"A":   PN = "1"  !CDS_PN = "1";
"B":   PN = "2"  !CDS_PN = "2";
BODY = "Q_RES","I378": #LOCATION = "R418" !CDS_LOCATION = "R418" &SEC = "1" #&CDS_SEC = "1";
"A":   PN = "1"  !CDS_PN = "1";
"B":   PN = "2"  !CDS_PN = "2";
BODY = "Q_RES","I379": #LOCATION = "R417" !CDS_LOCATION = "R417" &SEC = "1" #&CDS_SEC = "1";
"A":   PN = "1"  !CDS_PN = "1";
"B":   PN = "2"  !CDS_PN = "2";
BODY = "Q_RES","I380": #LOCATION = "R408" !CDS_LOCATION = "R408" &SEC = "1" #&CDS_SEC = "1";
"A":   PN = "1"  !CDS_PN = "1";
"B":   PN = "2"  !CDS_PN = "2";
BODY = "Q_RES","I381": #LOCATION = "R409" !CDS_LOCATION = "R409" &SEC = "1" #&CDS_SEC = "1";
"A":   PN = "1"  !CDS_PN = "1";
"B":   PN = "2"  !CDS_PN = "2";
BODY = "Q_RES","I382": #LOCATION = "R410" !CDS_LOCATION = "R410" &SEC = "1" #&CDS_SEC = "1";
"A":   PN = "1"  !CDS_PN = "1";
"B":   PN = "2"  !CDS_PN = "2";
BODY = "Q_RES","I383": #LOCATION = "R411" !CDS_LOCATION = "R411" &SEC = "1" #&CDS_SEC = "1";
"A":   PN = "1"  !CDS_PN = "1";
"B":   PN = "2"  !CDS_PN = "2";
BODY = "Q_RES","I384": #LOCATION = "R413" !CDS_LOCATION = "R413" &SEC = "1" #&CDS_SEC = "1";
"A":   PN = "1"  !CDS_PN = "1";
"B":   PN = "2"  !CDS_PN = "2";
BODY = "Q_RES","I385": #LOCATION = "R414" !CDS_LOCATION = "R414" &SEC = "1" #&CDS_SEC = "1";
"A":   PN = "1"  !CDS_PN = "1";
"B":   PN = "2"  !CDS_PN = "2";
BODY = "Q_RES","I386": #LOCATION = "R415" !CDS_LOCATION = "R415" &SEC = "1" #&CDS_SEC = "1";
"A":   PN = "1"  !CDS_PN = "1";
"B":   PN = "2"  !CDS_PN = "2";
BODY = "Q_RES","I387": #LOCATION = "R416" !CDS_LOCATION = "R416" &SEC = "1" #&CDS_SEC = "1";
"A":   PN = "1"  !CDS_PN = "1";
"B":   PN = "2"  !CDS_PN = "2";
BODY = "Q_RES","I388": #LOCATION = "R387" !CDS_LOCATION = "R387" &SEC = "1" #&CDS_SEC = "1";
"A":   PN = "1"  !CDS_PN = "1";
"B":   PN = "2"  !CDS_PN = "2";
BODY = "Q_RES","I389": #LOCATION = "R388" !CDS_LOCATION = "R388" &SEC = "1" #&CDS_SEC = "1";
"A":   PN = "1"  !CDS_PN = "1";
"B":   PN = "2"  !CDS_PN = "2";
BODY = "Q_RES","I390": #LOCATION = "R390" !CDS_LOCATION = "R390" &SEC = "1" #&CDS_SEC = "1";
"A":   PN = "1"  !CDS_PN = "1";
"B":   PN = "2"  !CDS_PN = "2";
BODY = "Q_RES","I391": #LOCATION = "R389" !CDS_LOCATION = "R389" &SEC = "1" #&CDS_SEC = "1";
"A":   PN = "1"  !CDS_PN = "1";
"B":   PN = "2"  !CDS_PN = "2";
BODY = "Q_RES","I392": #LOCATION = "R391" !CDS_LOCATION = "R391" &SEC = "1" #&CDS_SEC = "1";
"A":   PN = "1"  !CDS_PN = "1";
"B":   PN = "2"  !CDS_PN = "2";
BODY = "Q_RES","I393": #LOCATION = "R396" !CDS_LOCATION = "R396" &SEC = "1" #&CDS_SEC = "1";
"A":   PN = "1"  !CDS_PN = "1";
"B":   PN = "2"  !CDS_PN = "2";
BODY = "Q_RES","I394": #LOCATION = "R397" !CDS_LOCATION = "R397" &SEC = "1" #&CDS_SEC = "1";
"A":   PN = "1"  !CDS_PN = "1";
"B":   PN = "2"  !CDS_PN = "2";
BODY = "Q_RES","I395": #LOCATION = "R392" !CDS_LOCATION = "R392" &SEC = "1" #&CDS_SEC = "1";
"A":   PN = "1"  !CDS_PN = "1";
"B":   PN = "2"  !CDS_PN = "2";
BODY = "Q_RES","I396": #LOCATION = "R393" !CDS_LOCATION = "R393" &SEC = "1" #&CDS_SEC = "1";
"A":   PN = "1"  !CDS_PN = "1";
"B":   PN = "2"  !CDS_PN = "2";
BODY = "Q_RES","I397": #LOCATION = "R394" !CDS_LOCATION = "R394" &SEC = "1" #&CDS_SEC = "1";
"A":   PN = "1"  !CDS_PN = "1";
"B":   PN = "2"  !CDS_PN = "2";
BODY = "Q_RES","I399": #LOCATION = "R489" !CDS_LOCATION = "R489" &SEC = "1" #&CDS_SEC = "1";
"A":   PN = "1"  !CDS_PN = "1";
"B":   PN = "2"  !CDS_PN = "2";
BODY = "Q_RES","I401": #LOCATION = "R247" !CDS_LOCATION = "R247" &SEC = "1" #&CDS_SEC = "1";
"A":   PN = "1"  !CDS_PN = "1";
"B":   PN = "2"  !CDS_PN = "2";
BODY = "TP","I403": #LOCATION = "TP10" !CDS_LOCATION = "TP10" &SEC = "1" #&CDS_SEC = "1";
"TP":   PN = "1"  !CDS_PN = "1";
BODY = "TP","I404": #LOCATION = "TP1" !CDS_LOCATION = "TP1" &SEC = "1" #&CDS_SEC = "1";
"TP":   PN = "1"  !CDS_PN = "1";
BODY = "CONN10_HBC1051L300D8H","I423": #LOCATION = "J212" !CDS_LOCATION = "J212" #SEC = "1" !CDS_SEC = "1";
"1":   PN = "1"  !CDS_PN = "1";
"2":   PN = "2"  !CDS_PN = "2";
"3":   PN = "3"  !CDS_PN = "3";
"4":   PN = "4"  !CDS_PN = "4";
"5":   PN = "5"  !CDS_PN = "5";
"6":   PN = "6"  !CDS_PN = "6";
"7":   PN = "7"  !CDS_PN = "7";
"8":   PN = "8"  !CDS_PN = "8";
"9":   PN = "9"  !CDS_PN = "9";
"10":   PN = "10"  !CDS_PN = "10";
BODY = "SCONN8_G802M0083150RD3HR","I424": #LOCATION = "J48" !CDS_LOCATION = "J48" #SEC = "1" !CDS_SEC = "1";
"1":   PN = "1"  !CDS_PN = "1";
"2":   PN = "2"  !CDS_PN = "2";
"3":   PN = "3"  !CDS_PN = "3";
"4":   PN = "4"  !CDS_PN = "4";
"5":   PN = "5"  !CDS_PN = "5";
"6":   PN = "6"  !CDS_PN = "6";
"7":   PN = "7"  !CDS_PN = "7";
"8":   PN = "8"  !CDS_PN = "8";
BODY = "SCONN8_G802M0083150RD3HR","I425": #LOCATION = "J5" !CDS_LOCATION = "J5" #SEC = "1" !CDS_SEC = "1";
"1":   PN = "1"  !CDS_PN = "1";
"2":   PN = "2"  !CDS_PN = "2";
"3":   PN = "3"  !CDS_PN = "3";
"4":   PN = "4"  !CDS_PN = "4";
"5":   PN = "5"  !CDS_PN = "5";
"6":   PN = "6"  !CDS_PN = "6";
"7":   PN = "7"  !CDS_PN = "7";
"8":   PN = "8"  !CDS_PN = "8";
BODY = "Q_RES","I427": #LOCATION = "R5055" !CDS_LOCATION = "R5055" &SEC = "1" #&CDS_SEC = "1";
"A":   PN = "1"  !CDS_PN = "1";
"B":   PN = "2"  !CDS_PN = "2";
BODY = "Q_RES","I428": #LOCATION = "R5056" !CDS_LOCATION = "R5056" &SEC = "1" #&CDS_SEC = "1";
"A":   PN = "1"  !CDS_PN = "1";
"B":   PN = "2"  !CDS_PN = "2";
BODY = "Q_RES","I429": #LOCATION = "R1533" !CDS_LOCATION = "R1533" &SEC = "1" #&CDS_SEC = "1";
"A":   PN = "1"  !CDS_PN = "1";
"B":   PN = "2"  !CDS_PN = "2";
DRAWING = "@t6g_mb_lib.t6g(sch_1):page29";
BODY = "Q_RES","I282": #LOCATION = "R457" !CDS_LOCATION = "R457" &SEC = "1" #&CDS_SEC = "1";
"A":   PN = "1"  !CDS_PN = "1";
"B":   PN = "2"  !CDS_PN = "2";
BODY = "Q_RES","I284": #LOCATION = "R455" !CDS_LOCATION = "R455" &SEC = "1" #&CDS_SEC = "1";
"A":   PN = "1"  !CDS_PN = "1";
"B":   PN = "2"  !CDS_PN = "2";
BODY = "GENOA_SP5","I287": #LOCATION = "U25" !CDS_LOCATION = "U25" &SEC = "22" #&CDS_SEC = "22";
"AGPIO76||SPI_TPM_CS_L":   PN = "DJ25"  !CDS_PN = "DJ25";
"ESPI0_ALERT_L||AGPIO108":   PN = "DJ22"  !CDS_PN = "DJ22";
"ESPI0_DAT0||SPI0_DAT0||AGPIO120":   PN = "DF28"  !CDS_PN = "DF28";
"ESPI0_DAT1||SPI0_DAT1||AGPIO121":   PN = "DG22"  !CDS_PN = "DG22";
"ESPI0_DAT2||SPI0_DAT2||AGPIO122":   PN = "DJ28"  !CDS_PN = "DJ28";
"ESPI0_DAT3||SPI0_DAT3||AGPIO123":   PN = "DG29"  !CDS_PN = "DG29";
"ESPI1_ALERT_L||AGPIO110":   PN = "DF24"  !CDS_PN = "DF24";
"ESPI1_DAT0||SPI1_DAT0||AGPIO131":   PN = "DH24"  !CDS_PN = "DH24";
"ESPI1_DAT1||SPI1_DAT1||AGPIO132":   PN = "DE24"  !CDS_PN = "DE24";
"ESPI1_DAT2||SPI1_DAT2||AGPIO133":   PN = "DF25"  !CDS_PN = "DF25";
"ESPI1_DAT3||SPI1_DAT3||AGPIO134":   PN = "DG25"  !CDS_PN = "DG25";
"ESPI_CLK0||SPI_CLK0||AGPIO117":   PN = "DJ27"  !CDS_PN = "DJ27";
"ESPI_CLK1||SPI_CLK1||AGPIO75":   PN = "DG23"  !CDS_PN = "DG23";
"ESPI_CLK2||AGPIO74":   PN = "DF27"  !CDS_PN = "DF27";
"ESPI_CS0_L||AGPIO124":   PN = "DG28"  !CDS_PN = "DG28";
"ESPI_CS1_L||AGPIO125":   PN = "DJ23"  !CDS_PN = "DJ23";
"ESPI_RSTIN_L||KBRST_L||AGPIO129":   PN = "DJ26"  !CDS_PN = "DJ26";
"ESPI_RSTOUT_L||AGPIO23":   PN = "DE27"  !CDS_PN = "DE27";
"SPI_CS0_L||AGPIO118":   PN = "DF30"  !CDS_PN = "DF30";
"SPI_CS1_L||AGPIO119":   PN = "DG26"  !CDS_PN = "DG26";
"SPI_CS2_L||AGPIO126":   PN = "DH27"  !CDS_PN = "DH27";
"USB00_DN":   PN = "A25"  !CDS_PN = "A25";
"USB00_DP":   PN = "A26"  !CDS_PN = "A26";
"USB00_OC_L||AGPIO264":   PN = "E23"  !CDS_PN = "E23";
"USB00_RXN":   PN = "E26"  !CDS_PN = "E26";
"USB00_RXP":   PN = "E27"  !CDS_PN = "E27";
"USB00_TXN":   PN = "C26"  !CDS_PN = "C26";
"USB00_TXP":   PN = "C25"  !CDS_PN = "C25";
"USB01_DN":   PN = "A29"  !CDS_PN = "A29";
"USB01_DP":   PN = "A28"  !CDS_PN = "A28";
"USB01_OC_L||AGPIO265":   PN = "E24"  !CDS_PN = "E24";
"USB01_RXN":   PN = "C28"  !CDS_PN = "C28";
"USB01_RXP":   PN = "C29"  !CDS_PN = "C29";
"USB01_TXN":   PN = "E29"  !CDS_PN = "E29";
"USB01_TXP":   PN = "E30"  !CDS_PN = "E30";
"USB10_DN":   PN = "DH67"  !CDS_PN = "DH67";
"USB10_DP":   PN = "DJ67"  !CDS_PN = "DJ67";
"USB10_OC_L||AGPIO16":   PN = "DG40"  !CDS_PN = "DG40";
"USB10_RXN":   PN = "DH65"  !CDS_PN = "DH65";
"USB10_RXP":   PN = "DJ65"  !CDS_PN = "DJ65";
"USB10_TXN":   PN = "DJ69"  !CDS_PN = "DJ69";
"USB10_TXP":   PN = "DH69"  !CDS_PN = "DH69";
"USB11_DN":   PN = "DJ60"  !CDS_PN = "DJ60";
"USB11_DP":   PN = "DH60"  !CDS_PN = "DH60";
"USB11_OC_L||AGPIO17":   PN = "DH40"  !CDS_PN = "DH40";
"USB11_RXN":   PN = "DH62"  !CDS_PN = "DH62";
"USB11_RXP":   PN = "DJ62"  !CDS_PN = "DJ62";
"USB11_TXN":   PN = "DH58"  !CDS_PN = "DH58";
"USB11_TXP":   PN = "DG58"  !CDS_PN = "DG58";
BODY = "Q_RES","I327": #LOCATION = "R470" !CDS_LOCATION = "R470" &SEC = "1" #&CDS_SEC = "1";
"A":   PN = "1"  !CDS_PN = "1";
"B":   PN = "2"  !CDS_PN = "2";
BODY = "Q_RES","I328": #LOCATION = "R469" !CDS_LOCATION = "R469" &SEC = "1" #&CDS_SEC = "1";
"A":   PN = "1"  !CDS_PN = "1";
"B":   PN = "2"  !CDS_PN = "2";
BODY = "Q_RES","I329": #LOCATION = "R468" !CDS_LOCATION = "R468" &SEC = "1" #&CDS_SEC = "1";
"A":   PN = "1"  !CDS_PN = "1";
"B":   PN = "2"  !CDS_PN = "2";
BODY = "Q_RES","I330": #LOCATION = "R471" !CDS_LOCATION = "R471" &SEC = "1" #&CDS_SEC = "1";
"A":   PN = "1"  !CDS_PN = "1";
"B":   PN = "2"  !CDS_PN = "2";
BODY = "Q_RES","I332": #LOCATION = "R474" !CDS_LOCATION = "R474" &SEC = "1" #&CDS_SEC = "1";
"A":   PN = "1"  !CDS_PN = "1";
"B":   PN = "2"  !CDS_PN = "2";
BODY = "SN74LVC1G07DBVR","I373": #LOCATION = "U3" !CDS_LOCATION = "U3" &SEC = "1" #&CDS_SEC = "1";
"A":   PN = "2"  !CDS_PN = "2";
"GND":   PN = "3"  !CDS_PN = "3";
"NC":   PN = "1"  !CDS_PN = "1";
"VCC":   PN = "5"  !CDS_PN = "5";
"Y":   PN = "4"  !CDS_PN = "4";
BODY = "Q_RES","I377": #LOCATION = "R589" !CDS_LOCATION = "R589" &SEC = "1" #&CDS_SEC = "1";
"A":   PN = "1"  !CDS_PN = "1";
"B":   PN = "2"  !CDS_PN = "2";
BODY = "Q_CAP","I379": #LOCATION = "C30" !CDS_LOCATION = "C30" &SEC = "1" #&CDS_SEC = "1";
"A":   PN = "1"  !CDS_PN = "1";
"B":   PN = "2"  !CDS_PN = "2";
BODY = "Q_RES","I383": #LOCATION = "R454" !CDS_LOCATION = "R454" &SEC = "1" #&CDS_SEC = "1";
"A":   PN = "1"  !CDS_PN = "1";
"B":   PN = "2"  !CDS_PN = "2";
BODY = "Q_RES","I396": #LOCATION = "R1503" !CDS_LOCATION = "R1503" &SEC = "1" #&CDS_SEC = "1";
"A":   PN = "1"  !CDS_PN = "1";
"B":   PN = "2"  !CDS_PN = "2";
BODY = "Q_RES","I397": #LOCATION = "R1504" !CDS_LOCATION = "R1504" &SEC = "1" #&CDS_SEC = "1";
"A":   PN = "1"  !CDS_PN = "1";
"B":   PN = "2"  !CDS_PN = "2";
BODY = "Q_RES","I398": #LOCATION = "R1505" !CDS_LOCATION = "R1505" &SEC = "1" #&CDS_SEC = "1";
"A":   PN = "1"  !CDS_PN = "1";
"B":   PN = "2"  !CDS_PN = "2";
BODY = "Q_RES","I399": #LOCATION = "R1506" !CDS_LOCATION = "R1506" &SEC = "1" #&CDS_SEC = "1";
"A":   PN = "1"  !CDS_PN = "1";
"B":   PN = "2"  !CDS_PN = "2";
BODY = "Q_RES","I405": #LOCATION = "R458" !CDS_LOCATION = "R458" &SEC = "1" #&CDS_SEC = "1";
"A":   PN = "1"  !CDS_PN = "1";
"B":   PN = "2"  !CDS_PN = "2";
BODY = "Q_RES","I407": #LOCATION = "R459" !CDS_LOCATION = "R459" &SEC = "1" #&CDS_SEC = "1";
"A":   PN = "1"  !CDS_PN = "1";
"B":   PN = "2"  !CDS_PN = "2";
BODY = "Q_RES","I408": #LOCATION = "R460" !CDS_LOCATION = "R460" &SEC = "1" #&CDS_SEC = "1";
"A":   PN = "1"  !CDS_PN = "1";
"B":   PN = "2"  !CDS_PN = "2";
BODY = "Q_RES","I409": #LOCATION = "R461" !CDS_LOCATION = "R461" &SEC = "1" #&CDS_SEC = "1";
"A":   PN = "1"  !CDS_PN = "1";
"B":   PN = "2"  !CDS_PN = "2";
BODY = "Q_RES","I410": #LOCATION = "R464" !CDS_LOCATION = "R464" &SEC = "1" #&CDS_SEC = "1";
"A":   PN = "1"  !CDS_PN = "1";
"B":   PN = "2"  !CDS_PN = "2";
BODY = "Q_RES","I411": #LOCATION = "R465" !CDS_LOCATION = "R465" &SEC = "1" #&CDS_SEC = "1";
"A":   PN = "1"  !CDS_PN = "1";
"B":   PN = "2"  !CDS_PN = "2";
BODY = "Q_RES","I412": #LOCATION = "R466" !CDS_LOCATION = "R466" &SEC = "1" #&CDS_SEC = "1";
"A":   PN = "1"  !CDS_PN = "1";
"B":   PN = "2"  !CDS_PN = "2";
BODY = "Q_RES","I413": #LOCATION = "R467" !CDS_LOCATION = "R467" &SEC = "1" #&CDS_SEC = "1";
"A":   PN = "1"  !CDS_PN = "1";
"B":   PN = "2"  !CDS_PN = "2";
BODY = "Q_RES","I414": #LOCATION = "R475" !CDS_LOCATION = "R475" &SEC = "1" #&CDS_SEC = "1";
"A":   PN = "1"  !CDS_PN = "1";
"B":   PN = "2"  !CDS_PN = "2";
BODY = "Q_RES","I425": #LOCATION = "R462" !CDS_LOCATION = "R462" &SEC = "1" #&CDS_SEC = "1";
"A":   PN = "1"  !CDS_PN = "1";
"B":   PN = "2"  !CDS_PN = "2";
BODY = "Q_RES","I426": #LOCATION = "R1592" !CDS_LOCATION = "R1592" &SEC = "1" #&CDS_SEC = "1";
"A":   PN = "1"  !CDS_PN = "1";
"B":   PN = "2"  !CDS_PN = "2";
BODY = "Q_RES","I427": #LOCATION = "R1593" !CDS_LOCATION = "R1593" &SEC = "1" #&CDS_SEC = "1";
"A":   PN = "1"  !CDS_PN = "1";
"B":   PN = "2"  !CDS_PN = "2";
BODY = "Q_RES","I428": #LOCATION = "R472" !CDS_LOCATION = "R472" &SEC = "1" #&CDS_SEC = "1";
"A":   PN = "1"  !CDS_PN = "1";
"B":   PN = "2"  !CDS_PN = "2";
BODY = "Q_RES","I430": #LOCATION = "R473" !CDS_LOCATION = "R473" &SEC = "1" #&CDS_SEC = "1";
"A":   PN = "1"  !CDS_PN = "1";
"B":   PN = "2"  !CDS_PN = "2";
DRAWING = "@t6g_mb_lib.t6g(sch_1):page30";
BODY = "GENOA_SP5","I28": #LOCATION = "U25" !CDS_LOCATION = "U25" &SEC = "27" #&CDS_SEC = "27";
"VDD_11_S3_BJ18":   PN = "BJ18"  !CDS_PN = "BJ18";
"VDD_11_S3_BJ23":   PN = "BJ23"  !CDS_PN = "BJ23";
"VDD_11_S3_BJ25":   PN = "BJ25"  !CDS_PN = "BJ25";
"VDD_11_S3_BJ27":   PN = "BJ27"  !CDS_PN = "BJ27";
"VDD_11_S3_BK22":   PN = "BK22"  !CDS_PN = "BK22";
"VDD_11_S3_BK24":   PN = "BK24"  !CDS_PN = "BK24";
"VDD_11_S3_BK26":   PN = "BK26"  !CDS_PN = "BK26";
"VDD_11_S3_BK28":   PN = "BK28"  !CDS_PN = "BK28";
"VDD_11_S3_BK49":   PN = "BK49"  !CDS_PN = "BK49";
"VDD_11_S3_BL23":   PN = "BL23"  !CDS_PN = "BL23";
"VDD_11_S3_BL25":   PN = "BL25"  !CDS_PN = "BL25";
"VDD_11_S3_BL27":   PN = "BL27"  !CDS_PN = "BL27";
"VDD_11_S3_BL48":   PN = "BL48"  !CDS_PN = "BL48";
"VDD_11_S3_BM12":   PN = "BM12"  !CDS_PN = "BM12";
"VDD_11_S3_BM19":   PN = "BM19"  !CDS_PN = "BM19";
"VDD_11_S3_BM22":   PN = "BM22"  !CDS_PN = "BM22";
"VDD_11_S3_BM24":   PN = "BM24"  !CDS_PN = "BM24";
"VDD_11_S3_BM26":   PN = "BM26"  !CDS_PN = "BM26";
"VDD_11_S3_BM28":   PN = "BM28"  !CDS_PN = "BM28";
"VDD_11_S3_BM30":   PN = "BM30"  !CDS_PN = "BM30";
"VDD_11_S3_BM32":   PN = "BM32"  !CDS_PN = "BM32";
"VDD_11_S3_BM34":   PN = "BM34"  !CDS_PN = "BM34";
"VDD_11_S3_BM36":   PN = "BM36"  !CDS_PN = "BM36";
"VDD_11_S3_BM39":   PN = "BM39"  !CDS_PN = "BM39";
"VDD_11_S3_BM41":   PN = "BM41"  !CDS_PN = "BM41";
"VDD_11_S3_BM43":   PN = "BM43"  !CDS_PN = "BM43";
"VDD_11_S3_BM45":   PN = "BM45"  !CDS_PN = "BM45";
"VDD_11_S3_BM47":   PN = "BM47"  !CDS_PN = "BM47";
"VDD_11_S3_BM49":   PN = "BM49"  !CDS_PN = "BM49";
"VDD_11_S3_BN25":   PN = "BN25"  !CDS_PN = "BN25";
"VDD_11_S3_BN29":   PN = "BN29"  !CDS_PN = "BN29";
"VDD_11_S3_BN33":   PN = "BN33"  !CDS_PN = "BN33";
"VDD_11_S3_BN40":   PN = "BN40"  !CDS_PN = "BN40";
"VDD_11_S3_BN44":   PN = "BN44"  !CDS_PN = "BN44";
"VDD_11_S3_BN48":   PN = "BN48"  !CDS_PN = "BN48";
"VDD_11_S3_BP22":   PN = "BP22"  !CDS_PN = "BP22";
"VDD_11_S3_BR4":   PN = "BR4"  !CDS_PN = "BR4";
"VDD_11_S3_BR11":   PN = "BR11"  !CDS_PN = "BR11";
"VDD_11_S3_BR18":   PN = "BR18"  !CDS_PN = "BR18";
"VDD_11_S3_BV5":   PN = "BV5"  !CDS_PN = "BV5";
"VDD_11_S3_BV12":   PN = "BV12"  !CDS_PN = "BV12";
"VDD_11_S3_BV19":   PN = "BV19"  !CDS_PN = "BV19";
"VDD_11_S3_BV22":   PN = "BV22"  !CDS_PN = "BV22";
"VDD_11_S3_CA4":   PN = "CA4"  !CDS_PN = "CA4";
"VDD_11_S3_CA11":   PN = "CA11"  !CDS_PN = "CA11";
"VDD_11_S3_CA18":   PN = "CA18"  !CDS_PN = "CA18";
"VDD_11_S3_CB22":   PN = "CB22"  !CDS_PN = "CB22";
"VDD_11_S3_CD5":   PN = "CD5"  !CDS_PN = "CD5";
"VDD_11_S3_CD12":   PN = "CD12"  !CDS_PN = "CD12";
"VDD_11_S3_CD19":   PN = "CD19"  !CDS_PN = "CD19";
"VDD_11_S3_CF22":   PN = "CF22"  !CDS_PN = "CF22";
"VDD_11_S3_CG4":   PN = "CG4"  !CDS_PN = "CG4";
"VDD_11_S3_CG11":   PN = "CG11"  !CDS_PN = "CG11";
"VDD_11_S3_CG18":   PN = "CG18"  !CDS_PN = "CG18";
"VDD_11_S3_CJ22":   PN = "CJ22"  !CDS_PN = "CJ22";
"VDD_11_S3_CK5":   PN = "CK5"  !CDS_PN = "CK5";
"VDD_11_S3_CK12":   PN = "CK12"  !CDS_PN = "CK12";
"VDD_11_S3_CK19":   PN = "CK19"  !CDS_PN = "CK19";
"VDD_11_S3_CM22":   PN = "CM22"  !CDS_PN = "CM22";
"VDD_11_S3_CN4":   PN = "CN4"  !CDS_PN = "CN4";
"VDD_11_S3_CN11":   PN = "CN11"  !CDS_PN = "CN11";
"VDD_11_S3_CN18":   PN = "CN18"  !CDS_PN = "CN18";
"VDD_11_S3_CT5":   PN = "CT5"  !CDS_PN = "CT5";
"VDD_11_S3_CT12":   PN = "CT12"  !CDS_PN = "CT12";
"VDD_11_S3_CT19":   PN = "CT19"  !CDS_PN = "CT19";
"VDD_11_S3_CT22":   PN = "CT22"  !CDS_PN = "CT22";
"VDD_11_S3_CW4":   PN = "CW4"  !CDS_PN = "CW4";
"VDD_11_S3_CW11":   PN = "CW11"  !CDS_PN = "CW11";
"VDD_11_S3_CW18":   PN = "CW18"  !CDS_PN = "CW18";
"VDD_11_S3_CY22":   PN = "CY22"  !CDS_PN = "CY22";
"VDD_11_S3_DB5":   PN = "DB5"  !CDS_PN = "DB5";
"VDD_11_S3_DB12":   PN = "DB12"  !CDS_PN = "DB12";
"VDD_11_S3_DB19":   PN = "DB19"  !CDS_PN = "DB19";
"VDD_11_S3_DE4":   PN = "DE4"  !CDS_PN = "DE4";
"VDD_11_S3_DE11":   PN = "DE11"  !CDS_PN = "DE11";
"VDD_11_S3_DE18":   PN = "DE18"  !CDS_PN = "DE18";
"VDD_11_S3_DG5":   PN = "DG5"  !CDS_PN = "DG5";
"VDD_18_S5_AR52":   PN = "AR52"  !CDS_PN = "AR52";
"VDD_18_S5_AR54":   PN = "AR54"  !CDS_PN = "AR54";
"VDD_18_S5_AT51":   PN = "AT51"  !CDS_PN = "AT51";
"VDD_18_S5_AT53":   PN = "AT53"  !CDS_PN = "AT53";
"VDD_18_S5_AU50":   PN = "AU50"  !CDS_PN = "AU50";
"VDD_18_S5_AU52":   PN = "AU52"  !CDS_PN = "AU52";
"VDD_18_S5_AU54":   PN = "AU54"  !CDS_PN = "AU54";
"VDD_18_S5_AV49":   PN = "AV49"  !CDS_PN = "AV49";
"VDD_18_S5_AV51":   PN = "AV51"  !CDS_PN = "AV51";
"VDD_18_S5_AV53":   PN = "AV53"  !CDS_PN = "AV53";
"VDD_18_S5_AW50":   PN = "AW50"  !CDS_PN = "AW50";
"VDD_18_S5_AW52":   PN = "AW52"  !CDS_PN = "AW52";
"VDD_18_S5_AW54":   PN = "AW54"  !CDS_PN = "AW54";
"VDD_18_S5_AY51":   PN = "AY51"  !CDS_PN = "AY51";
"VDD_18_S5_AY53":   PN = "AY53"  !CDS_PN = "AY53";
"VDD_18_S5_BA50":   PN = "BA50"  !CDS_PN = "BA50";
"VDD_18_S5_BA52":   PN = "BA52"  !CDS_PN = "BA52";
"VDD_18_S5_BA54":   PN = "BA54"  !CDS_PN = "BA54";
"VDD_18_S5_BB51":   PN = "BB51"  !CDS_PN = "BB51";
"VDD_18_S5_BB53":   PN = "BB53"  !CDS_PN = "BB53";
"VDD_18_S5_BC52":   PN = "BC52"  !CDS_PN = "BC52";
"VDD_18_S5_BC54":   PN = "BC54"  !CDS_PN = "BC54";
"VDD_33_S5_BN52":   PN = "BN52"  !CDS_PN = "BN52";
"VDD_33_S5_BP51":   PN = "BP51"  !CDS_PN = "BP51";
"VDDBT_RTC_G":   PN = "BN23"  !CDS_PN = "BN23";
"VDDIO_AA54":   PN = "AA54"  !CDS_PN = "AA54";
"VDDIO_AC58":   PN = "AC58"  !CDS_PN = "AC58";
"VDDIO_AC65":   PN = "AC65"  !CDS_PN = "AC65";
"VDDIO_AC72":   PN = "AC72"  !CDS_PN = "AC72";
"VDDIO_AD54":   PN = "AD54"  !CDS_PN = "AD54";
"VDDIO_AF57":   PN = "AF57"  !CDS_PN = "AF57";
"VDDIO_AF64":   PN = "AF64"  !CDS_PN = "AF64";
"VDDIO_AF71":   PN = "AF71"  !CDS_PN = "AF71";
"VDDIO_AH54":   PN = "AH54"  !CDS_PN = "AH54";
"VDDIO_AJ58":   PN = "AJ58"  !CDS_PN = "AJ58";
"VDDIO_AJ65":   PN = "AJ65"  !CDS_PN = "AJ65";
"VDDIO_AJ72":   PN = "AJ72"  !CDS_PN = "AJ72";
"VDDIO_AM54":   PN = "AM54"  !CDS_PN = "AM54";
"VDDIO_AM57":   PN = "AM57"  !CDS_PN = "AM57";
"VDDIO_AM64":   PN = "AM64"  !CDS_PN = "AM64";
"VDDIO_AM71":   PN = "AM71"  !CDS_PN = "AM71";
"VDDIO_AR58":   PN = "AR58"  !CDS_PN = "AR58";
"VDDIO_AR65":   PN = "AR65"  !CDS_PN = "AR65";
"VDDIO_AR72":   PN = "AR72"  !CDS_PN = "AR72";
"VDDIO_AUDIO":   PN = "BH27"  !CDS_PN = "BH27";
"VDDIO_AV57":   PN = "AV57"  !CDS_PN = "AV57";
"VDDIO_AV64":   PN = "AV64"  !CDS_PN = "AV64";
"VDDIO_AV71":   PN = "AV71"  !CDS_PN = "AV71";
"VDDIO_BA58":   PN = "BA58"  !CDS_PN = "BA58";
"VDDIO_BA65":   PN = "BA65"  !CDS_PN = "BA65";
"VDDIO_BA72":   PN = "BA72"  !CDS_PN = "BA72";
"VDDIO_BD50":   PN = "BD50"  !CDS_PN = "BD50";
"VDDIO_BD52":   PN = "BD52"  !CDS_PN = "BD52";
"VDDIO_BD54":   PN = "BD54"  !CDS_PN = "BD54";
"VDDIO_BF51":   PN = "BF51"  !CDS_PN = "BF51";
"VDDIO_BF53":   PN = "BF53"  !CDS_PN = "BF53";
"VDDIO_BF57":   PN = "BF57"  !CDS_PN = "BF57";
"VDDIO_BF64":   PN = "BF64"  !CDS_PN = "BF64";
"VDDIO_BF71":   PN = "BF71"  !CDS_PN = "BF71";
"VDDIO_BG50":   PN = "BG50"  !CDS_PN = "BG50";
"VDDIO_BG52":   PN = "BG52"  !CDS_PN = "BG52";
"VDDIO_BG54":   PN = "BG54"  !CDS_PN = "BG54";
"VDDIO_BH51":   PN = "BH51"  !CDS_PN = "BH51";
"VDDIO_BH53":   PN = "BH53"  !CDS_PN = "BH53";
"VDDIO_BJ50":   PN = "BJ50"  !CDS_PN = "BJ50";
"VDDIO_BJ52":   PN = "BJ52"  !CDS_PN = "BJ52";
"VDDIO_BJ54":   PN = "BJ54"  !CDS_PN = "BJ54";
"VDDIO_BJ58":   PN = "BJ58"  !CDS_PN = "BJ58";
"VDDIO_BJ65":   PN = "BJ65"  !CDS_PN = "BJ65";
"VDDIO_BJ72":   PN = "BJ72"  !CDS_PN = "BJ72";
"VDDIO_BK51":   PN = "BK51"  !CDS_PN = "BK51";
"VDDIO_BK53":   PN = "BK53"  !CDS_PN = "BK53";
"VDDIO_BL50":   PN = "BL50"  !CDS_PN = "BL50";
"VDDIO_BL52":   PN = "BL52"  !CDS_PN = "BL52";
"VDDIO_BL54":   PN = "BL54"  !CDS_PN = "BL54";
"VDDIO_BM51":   PN = "BM51"  !CDS_PN = "BM51";
"VDDIO_BM53":   PN = "BM53"  !CDS_PN = "BM53";
"VDDIO_BM57":   PN = "BM57"  !CDS_PN = "BM57";
"VDDIO_BM64":   PN = "BM64"  !CDS_PN = "BM64";
"VDDIO_BM71":   PN = "BM71"  !CDS_PN = "BM71";
"VDDIO_BN54":   PN = "BN54"  !CDS_PN = "BN54";
"VDDIO_BR58":   PN = "BR58"  !CDS_PN = "BR58";
"VDDIO_BR65":   PN = "BR65"  !CDS_PN = "BR65";
"VDDIO_BR72":   PN = "BR72"  !CDS_PN = "BR72";
"VDDIO_BV54":   PN = "BV54"  !CDS_PN = "BV54";
"VDDIO_BV57":   PN = "BV57"  !CDS_PN = "BV57";
"VDDIO_BV64":   PN = "BV64"  !CDS_PN = "BV64";
"VDDIO_BV71":   PN = "BV71"  !CDS_PN = "BV71";
"VDDIO_CA58":   PN = "CA58"  !CDS_PN = "CA58";
"VDDIO_CA65":   PN = "CA65"  !CDS_PN = "CA65";
"VDDIO_CA72":   PN = "CA72"  !CDS_PN = "CA72";
"VDDIO_CB54":   PN = "CB54"  !CDS_PN = "CB54";
"VDDIO_CD57":   PN = "CD57"  !CDS_PN = "CD57";
"VDDIO_CD64":   PN = "CD64"  !CDS_PN = "CD64";
"VDDIO_CD71":   PN = "CD71"  !CDS_PN = "CD71";
"VDDIO_CF54":   PN = "CF54"  !CDS_PN = "CF54";
"VDDIO_CG58":   PN = "CG58"  !CDS_PN = "CG58";
"VDDIO_CG65":   PN = "CG65"  !CDS_PN = "CG65";
"VDDIO_CG72":   PN = "CG72"  !CDS_PN = "CG72";
"VDDIO_CJ54":   PN = "CJ54"  !CDS_PN = "CJ54";
"VDDIO_CK57":   PN = "CK57"  !CDS_PN = "CK57";
"VDDIO_CK64":   PN = "CK64"  !CDS_PN = "CK64";
"VDDIO_CK71":   PN = "CK71"  !CDS_PN = "CK71";
"VDDIO_CM54":   PN = "CM54"  !CDS_PN = "CM54";
"VDDIO_CN58":   PN = "CN58"  !CDS_PN = "CN58";
"VDDIO_CN65":   PN = "CN65"  !CDS_PN = "CN65";
"VDDIO_CN72":   PN = "CN72"  !CDS_PN = "CN72";
"VDDIO_CT54":   PN = "CT54"  !CDS_PN = "CT54";
"VDDIO_CT57":   PN = "CT57"  !CDS_PN = "CT57";
"VDDIO_CT64":   PN = "CT64"  !CDS_PN = "CT64";
"VDDIO_CT71":   PN = "CT71"  !CDS_PN = "CT71";
"VDDIO_CW58":   PN = "CW58"  !CDS_PN = "CW58";
"VDDIO_CW65":   PN = "CW65"  !CDS_PN = "CW65";
"VDDIO_CW72":   PN = "CW72"  !CDS_PN = "CW72";
"VDDIO_CY54":   PN = "CY54"  !CDS_PN = "CY54";
"VDDIO_DB57":   PN = "DB57"  !CDS_PN = "DB57";
"VDDIO_DB64":   PN = "DB64"  !CDS_PN = "DB64";
"VDDIO_DB71":   PN = "DB71"  !CDS_PN = "DB71";
"VDDIO_DE58":   PN = "DE58"  !CDS_PN = "DE58";
"VDDIO_DE65":   PN = "DE65"  !CDS_PN = "DE65";
"VDDIO_DE72":   PN = "DE72"  !CDS_PN = "DE72";
"VDDIO_DG64":   PN = "DG64"  !CDS_PN = "DG64";
"VDDIO_DG71":   PN = "DG71"  !CDS_PN = "DG71";
"VDDIO_H57":   PN = "H57"  !CDS_PN = "H57";
"VDDIO_H64":   PN = "H64"  !CDS_PN = "H64";
"VDDIO_H71":   PN = "H71"  !CDS_PN = "H71";
"VDDIO_K54":   PN = "K54"  !CDS_PN = "K54";
"VDDIO_L58":   PN = "L58"  !CDS_PN = "L58";
"VDDIO_L65":   PN = "L65"  !CDS_PN = "L65";
"VDDIO_L72":   PN = "L72"  !CDS_PN = "L72";
"VDDIO_P54":   PN = "P54"  !CDS_PN = "P54";
"VDDIO_P57":   PN = "P57"  !CDS_PN = "P57";
"VDDIO_P64":   PN = "P64"  !CDS_PN = "P64";
"VDDIO_P71":   PN = "P71"  !CDS_PN = "P71";
"VDDIO_U58":   PN = "U58"  !CDS_PN = "U58";
"VDDIO_U65":   PN = "U65"  !CDS_PN = "U65";
"VDDIO_U72":   PN = "U72"  !CDS_PN = "U72";
"VDDIO_V54":   PN = "V54"  !CDS_PN = "V54";
"VDDIO_Y57":   PN = "Y57"  !CDS_PN = "Y57";
"VDDIO_Y64":   PN = "Y64"  !CDS_PN = "Y64";
"VDDIO_Y71":   PN = "Y71"  !CDS_PN = "Y71";
BODY = "GENOA_SP5","I29": #LOCATION = "U25" !CDS_LOCATION = "U25" &SEC = "23" #&CDS_SEC = "23";
"RSVD_A31":   PN = "A31"  !CDS_PN = "A31";
"RSVD_A35":   PN = "A35"  !CDS_PN = "A35";
"RSVD_A41":   PN = "A41"  !CDS_PN = "A41";
"RSVD_A42":   PN = "A42"  !CDS_PN = "A42";
"RSVD_A45":   PN = "A45"  !CDS_PN = "A45";
"RSVD_A48":   PN = "A48"  !CDS_PN = "A48";
"RSVD_A50":   PN = "A50"  !CDS_PN = "A50";
"RSVD_A51":   PN = "A51"  !CDS_PN = "A51";
"RSVD_A54":   PN = "A54"  !CDS_PN = "A54";
"RSVD_A55":   PN = "A55"  !CDS_PN = "A55";
"RSVD_A56":   PN = "A56"  !CDS_PN = "A56";
"RSVD_A57":   PN = "A57"  !CDS_PN = "A57";
"RSVD_A59":   PN = "A59"  !CDS_PN = "A59";
"RSVD_A60":   PN = "A60"  !CDS_PN = "A60";
"RSVD_B40":   PN = "B40"  !CDS_PN = "B40";
"RSVD_BD4":   PN = "BD4"  !CDS_PN = "BD4";
"RSVD_BD7":   PN = "BD7"  !CDS_PN = "BD7";
"RSVD_BD11":   PN = "BD11"  !CDS_PN = "BD11";
"RSVD_BD14":   PN = "BD14"  !CDS_PN = "BD14";
"RSVD_BD18":   PN = "BD18"  !CDS_PN = "BD18";
"RSVD_BD21":   PN = "BD21"  !CDS_PN = "BD21";
"RSVD_BD55":   PN = "BD55"  !CDS_PN = "BD55";
"RSVD_BD58":   PN = "BD58"  !CDS_PN = "BD58";
"RSVD_BD62":   PN = "BD62"  !CDS_PN = "BD62";
"RSVD_BD65":   PN = "BD65"  !CDS_PN = "BD65";
"RSVD_BD69":   PN = "BD69"  !CDS_PN = "BD69";
"RSVD_BD72":   PN = "BD72"  !CDS_PN = "BD72";
"RSVD_C31":   PN = "C31"  !CDS_PN = "C31";
"RSVD_C34":   PN = "C34"  !CDS_PN = "C34";
"RSVD_C35":   PN = "C35"  !CDS_PN = "C35";
"RSVD_C53":   PN = "C53"  !CDS_PN = "C53";
"RSVD_C54":   PN = "C54"  !CDS_PN = "C54";
"RSVD_D4":   PN = "D4"  !CDS_PN = "D4";
"RSVD_D8":   PN = "D8"  !CDS_PN = "D8";
"RSVD_D11":   PN = "D11"  !CDS_PN = "D11";
"RSVD_D22":   PN = "D22"  !CDS_PN = "D22";
"RSVD_D34":   PN = "D34"  !CDS_PN = "D34";
"RSVD_D36":   PN = "D36"  !CDS_PN = "D36";
"RSVD_D58":   PN = "D58"  !CDS_PN = "D58";
"RSVD_D62":   PN = "D62"  !CDS_PN = "D62";
"RSVD_D65":   PN = "D65"  !CDS_PN = "D65";
"RSVD_D72":   PN = "D72"  !CDS_PN = "D72";
"RSVD_DG17":   PN = "DG17"  !CDS_PN = "DG17";
"RSVD_DH17":   PN = "DH17"  !CDS_PN = "DH17";
"RSVD_DH21":   PN = "DH21"  !CDS_PN = "DH21";
"RSVD_DJ4":   PN = "DJ4"  !CDS_PN = "DJ4";
"RSVD_E33":   PN = "E33"  !CDS_PN = "E33";
"RSVD_E36":   PN = "E36"  !CDS_PN = "E36";
"TEST4_CCD12":   PN = "C58"  !CDS_PN = "C58";
"TEST4_CCD13":   PN = "DH13"  !CDS_PN = "DH13";
"TEST4_CCD14":   PN = "DF41"  !CDS_PN = "DF41";
"TEST4_CCD15":   PN = "C23"  !CDS_PN = "C23";
"TEST5_CCD12":   PN = "C59"  !CDS_PN = "C59";
"TEST5_CCD13":   PN = "DH14"  !CDS_PN = "DH14";
"TEST5_CCD14":   PN = "DG42"  !CDS_PN = "DG42";
"TEST5_CCD15":   PN = "D23"  !CDS_PN = "D23";
"TEST6_X3D6":   PN = "B36"  !CDS_PN = "B36";
"TEST6_X3D7":   PN = "DJ57"  !CDS_PN = "DJ57";
BODY = "GENOA_SP5","I42": #LOCATION = "U25" !CDS_LOCATION = "U25" &SEC = "24" #&CDS_SEC = "24";
"VDDCR_CPU0_AB23":   PN = "AB23"  !CDS_PN = "AB23";
"VDDCR_CPU0_AB24":   PN = "AB24"  !CDS_PN = "AB24";
"VDDCR_CPU0_AB26":   PN = "AB26"  !CDS_PN = "AB26";
"VDDCR_CPU0_AB27":   PN = "AB27"  !CDS_PN = "AB27";
"VDDCR_CPU0_AB29":   PN = "AB29"  !CDS_PN = "AB29";
"VDDCR_CPU0_AB30":   PN = "AB30"  !CDS_PN = "AB30";
"VDDCR_CPU0_AB32":   PN = "AB32"  !CDS_PN = "AB32";
"VDDCR_CPU0_AB33":   PN = "AB33"  !CDS_PN = "AB33";
"VDDCR_CPU0_AB43":   PN = "AB43"  !CDS_PN = "AB43";
"VDDCR_CPU0_AB44":   PN = "AB44"  !CDS_PN = "AB44";
"VDDCR_CPU0_AB46":   PN = "AB46"  !CDS_PN = "AB46";
"VDDCR_CPU0_AB47":   PN = "AB47"  !CDS_PN = "AB47";
"VDDCR_CPU0_AB49":   PN = "AB49"  !CDS_PN = "AB49";
"VDDCR_CPU0_AB50":   PN = "AB50"  !CDS_PN = "AB50";
"VDDCR_CPU0_AB52":   PN = "AB52"  !CDS_PN = "AB52";
"VDDCR_CPU0_AB53":   PN = "AB53"  !CDS_PN = "AB53";
"VDDCR_CPU0_AC35":   PN = "AC35"  !CDS_PN = "AC35";
"VDDCR_CPU0_AC36":   PN = "AC36"  !CDS_PN = "AC36";
"VDDCR_CPU0_AC40":   PN = "AC40"  !CDS_PN = "AC40";
"VDDCR_CPU0_AC41":   PN = "AC41"  !CDS_PN = "AC41";
"VDDCR_CPU0_AF23":   PN = "AF23"  !CDS_PN = "AF23";
"VDDCR_CPU0_AF24":   PN = "AF24"  !CDS_PN = "AF24";
"VDDCR_CPU0_AF26":   PN = "AF26"  !CDS_PN = "AF26";
"VDDCR_CPU0_AF27":   PN = "AF27"  !CDS_PN = "AF27";
"VDDCR_CPU0_AF29":   PN = "AF29"  !CDS_PN = "AF29";
"VDDCR_CPU0_AF30":   PN = "AF30"  !CDS_PN = "AF30";
"VDDCR_CPU0_AF32":   PN = "AF32"  !CDS_PN = "AF32";
"VDDCR_CPU0_AF33":   PN = "AF33"  !CDS_PN = "AF33";
"VDDCR_CPU0_AF43":   PN = "AF43"  !CDS_PN = "AF43";
"VDDCR_CPU0_AF44":   PN = "AF44"  !CDS_PN = "AF44";
"VDDCR_CPU0_AF46":   PN = "AF46"  !CDS_PN = "AF46";
"VDDCR_CPU0_AF47":   PN = "AF47"  !CDS_PN = "AF47";
"VDDCR_CPU0_AF49":   PN = "AF49"  !CDS_PN = "AF49";
"VDDCR_CPU0_AF50":   PN = "AF50"  !CDS_PN = "AF50";
"VDDCR_CPU0_AF52":   PN = "AF52"  !CDS_PN = "AF52";
"VDDCR_CPU0_AF53":   PN = "AF53"  !CDS_PN = "AF53";
"VDDCR_CPU0_AG35":   PN = "AG35"  !CDS_PN = "AG35";
"VDDCR_CPU0_AG36":   PN = "AG36"  !CDS_PN = "AG36";
"VDDCR_CPU0_AG40":   PN = "AG40"  !CDS_PN = "AG40";
"VDDCR_CPU0_AG41":   PN = "AG41"  !CDS_PN = "AG41";
"VDDCR_CPU0_AK23":   PN = "AK23"  !CDS_PN = "AK23";
"VDDCR_CPU0_AK24":   PN = "AK24"  !CDS_PN = "AK24";
"VDDCR_CPU0_AK26":   PN = "AK26"  !CDS_PN = "AK26";
"VDDCR_CPU0_AK27":   PN = "AK27"  !CDS_PN = "AK27";
"VDDCR_CPU0_AK29":   PN = "AK29"  !CDS_PN = "AK29";
"VDDCR_CPU0_AK30":   PN = "AK30"  !CDS_PN = "AK30";
"VDDCR_CPU0_AK32":   PN = "AK32"  !CDS_PN = "AK32";
"VDDCR_CPU0_AK33":   PN = "AK33"  !CDS_PN = "AK33";
"VDDCR_CPU0_AK43":   PN = "AK43"  !CDS_PN = "AK43";
"VDDCR_CPU0_AK44":   PN = "AK44"  !CDS_PN = "AK44";
"VDDCR_CPU0_AK46":   PN = "AK46"  !CDS_PN = "AK46";
"VDDCR_CPU0_AK47":   PN = "AK47"  !CDS_PN = "AK47";
"VDDCR_CPU0_AK49":   PN = "AK49"  !CDS_PN = "AK49";
"VDDCR_CPU0_AK50":   PN = "AK50"  !CDS_PN = "AK50";
"VDDCR_CPU0_AK52":   PN = "AK52"  !CDS_PN = "AK52";
"VDDCR_CPU0_AK53":   PN = "AK53"  !CDS_PN = "AK53";
"VDDCR_CPU0_AL35":   PN = "AL35"  !CDS_PN = "AL35";
"VDDCR_CPU0_AL36":   PN = "AL36"  !CDS_PN = "AL36";
"VDDCR_CPU0_AL40":   PN = "AL40"  !CDS_PN = "AL40";
"VDDCR_CPU0_AL41":   PN = "AL41"  !CDS_PN = "AL41";
"VDDCR_CPU0_AP23":   PN = "AP23"  !CDS_PN = "AP23";
"VDDCR_CPU0_AP24":   PN = "AP24"  !CDS_PN = "AP24";
"VDDCR_CPU0_AP26":   PN = "AP26"  !CDS_PN = "AP26";
"VDDCR_CPU0_AP27":   PN = "AP27"  !CDS_PN = "AP27";
"VDDCR_CPU0_AP29":   PN = "AP29"  !CDS_PN = "AP29";
"VDDCR_CPU0_AP30":   PN = "AP30"  !CDS_PN = "AP30";
"VDDCR_CPU0_AP32":   PN = "AP32"  !CDS_PN = "AP32";
"VDDCR_CPU0_AP33":   PN = "AP33"  !CDS_PN = "AP33";
"VDDCR_CPU0_AP43":   PN = "AP43"  !CDS_PN = "AP43";
"VDDCR_CPU0_AP44":   PN = "AP44"  !CDS_PN = "AP44";
"VDDCR_CPU0_AP46":   PN = "AP46"  !CDS_PN = "AP46";
"VDDCR_CPU0_AP47":   PN = "AP47"  !CDS_PN = "AP47";
"VDDCR_CPU0_AP49":   PN = "AP49"  !CDS_PN = "AP49";
"VDDCR_CPU0_AP50":   PN = "AP50"  !CDS_PN = "AP50";
"VDDCR_CPU0_AP52":   PN = "AP52"  !CDS_PN = "AP52";
"VDDCR_CPU0_AP53":   PN = "AP53"  !CDS_PN = "AP53";
"VDDCR_CPU0_AR23":   PN = "AR23"  !CDS_PN = "AR23";
"VDDCR_CPU0_AR25":   PN = "AR25"  !CDS_PN = "AR25";
"VDDCR_CPU0_AR27":   PN = "AR27"  !CDS_PN = "AR27";
"VDDCR_CPU0_AR29":   PN = "AR29"  !CDS_PN = "AR29";
"VDDCR_CPU0_AR31":   PN = "AR31"  !CDS_PN = "AR31";
"VDDCR_CPU0_AR33":   PN = "AR33"  !CDS_PN = "AR33";
"VDDCR_CPU0_AR35":   PN = "AR35"  !CDS_PN = "AR35";
"VDDCR_CPU0_AR40":   PN = "AR40"  !CDS_PN = "AR40";
"VDDCR_CPU0_AR42":   PN = "AR42"  !CDS_PN = "AR42";
"VDDCR_CPU0_AR44":   PN = "AR44"  !CDS_PN = "AR44";
"VDDCR_CPU0_AR46":   PN = "AR46"  !CDS_PN = "AR46";
"VDDCR_CPU0_AR48":   PN = "AR48"  !CDS_PN = "AR48";
"VDDCR_CPU0_AR50":   PN = "AR50"  !CDS_PN = "AR50";
"VDDCR_CPU0_AT24":   PN = "AT24"  !CDS_PN = "AT24";
"VDDCR_CPU0_AT26":   PN = "AT26"  !CDS_PN = "AT26";
"VDDCR_CPU0_AT28":   PN = "AT28"  !CDS_PN = "AT28";
"VDDCR_CPU0_AT30":   PN = "AT30"  !CDS_PN = "AT30";
"VDDCR_CPU0_AT32":   PN = "AT32"  !CDS_PN = "AT32";
"VDDCR_CPU0_AT34":   PN = "AT34"  !CDS_PN = "AT34";
"VDDCR_CPU0_AT36":   PN = "AT36"  !CDS_PN = "AT36";
"VDDCR_CPU0_AT39":   PN = "AT39"  !CDS_PN = "AT39";
"VDDCR_CPU0_AT41":   PN = "AT41"  !CDS_PN = "AT41";
"VDDCR_CPU0_AT43":   PN = "AT43"  !CDS_PN = "AT43";
"VDDCR_CPU0_AT45":   PN = "AT45"  !CDS_PN = "AT45";
"VDDCR_CPU0_AT47":   PN = "AT47"  !CDS_PN = "AT47";
"VDDCR_CPU0_AT49":   PN = "AT49"  !CDS_PN = "AT49";
"VDDCR_CPU0_AU25":   PN = "AU25"  !CDS_PN = "AU25";
"VDDCR_CPU0_AU29":   PN = "AU29"  !CDS_PN = "AU29";
"VDDCR_CPU0_AU33":   PN = "AU33"  !CDS_PN = "AU33";
"VDDCR_CPU0_AU42":   PN = "AU42"  !CDS_PN = "AU42";
"VDDCR_CPU0_AU44":   PN = "AU44"  !CDS_PN = "AU44";
"VDDCR_CPU0_AU46":   PN = "AU46"  !CDS_PN = "AU46";
"VDDCR_CPU0_AU48":   PN = "AU48"  !CDS_PN = "AU48";
"VDDCR_CPU0_B19":   PN = "B19"  !CDS_PN = "B19";
"VDDCR_CPU0_B20":   PN = "B20"  !CDS_PN = "B20";
"VDDCR_CPU0_B22":   PN = "B22"  !CDS_PN = "B22";
"VDDCR_CPU0_B23":   PN = "B23"  !CDS_PN = "B23";
"VDDCR_CPU0_B25":   PN = "B25"  !CDS_PN = "B25";
"VDDCR_CPU0_B26":   PN = "B26"  !CDS_PN = "B26";
"VDDCR_CPU0_B28":   PN = "B28"  !CDS_PN = "B28";
"VDDCR_CPU0_B29":   PN = "B29"  !CDS_PN = "B29";
"VDDCR_CPU0_B31":   PN = "B31"  !CDS_PN = "B31";
"VDDCR_CPU0_B32":   PN = "B32"  !CDS_PN = "B32";
"VDDCR_CPU0_B34":   PN = "B34"  !CDS_PN = "B34";
"VDDCR_CPU0_B35":   PN = "B35"  !CDS_PN = "B35";
"VDDCR_CPU0_B41":   PN = "B41"  !CDS_PN = "B41";
"VDDCR_CPU0_B42":   PN = "B42"  !CDS_PN = "B42";
"VDDCR_CPU0_B44":   PN = "B44"  !CDS_PN = "B44";
"VDDCR_CPU0_B45":   PN = "B45"  !CDS_PN = "B45";
"VDDCR_CPU0_B47":   PN = "B47"  !CDS_PN = "B47";
"VDDCR_CPU0_B48":   PN = "B48"  !CDS_PN = "B48";
"VDDCR_CPU0_B50":   PN = "B50"  !CDS_PN = "B50";
"VDDCR_CPU0_B51":   PN = "B51"  !CDS_PN = "B51";
"VDDCR_CPU0_B53":   PN = "B53"  !CDS_PN = "B53";
"VDDCR_CPU0_B54":   PN = "B54"  !CDS_PN = "B54";
"VDDCR_CPU0_B56":   PN = "B56"  !CDS_PN = "B56";
"VDDCR_CPU0_B57":   PN = "B57"  !CDS_PN = "B57";
"VDDCR_CPU0_C20":   PN = "C20"  !CDS_PN = "C20";
"VDDCR_CPU0_D55":   PN = "D55"  !CDS_PN = "D55";
"VDDCR_CPU0_D56":   PN = "D56"  !CDS_PN = "D56";
"VDDCR_CPU0_E22":   PN = "E22"  !CDS_PN = "E22";
"VDDCR_CPU0_E25":   PN = "E25"  !CDS_PN = "E25";
"VDDCR_CPU0_E28":   PN = "E28"  !CDS_PN = "E28";
"VDDCR_CPU0_E31":   PN = "E31"  !CDS_PN = "E31";
"VDDCR_CPU0_E34":   PN = "E34"  !CDS_PN = "E34";
"VDDCR_CPU0_E35":   PN = "E35"  !CDS_PN = "E35";
"VDDCR_CPU0_E42":   PN = "E42"  !CDS_PN = "E42";
"VDDCR_CPU0_E45":   PN = "E45"  !CDS_PN = "E45";
"VDDCR_CPU0_E48":   PN = "E48"  !CDS_PN = "E48";
"VDDCR_CPU0_E51":   PN = "E51"  !CDS_PN = "E51";
"VDDCR_CPU0_E54":   PN = "E54"  !CDS_PN = "E54";
"VDDCR_CPU0_F22":   PN = "F22"  !CDS_PN = "F22";
"VDDCR_CPU0_F25":   PN = "F25"  !CDS_PN = "F25";
"VDDCR_CPU0_F28":   PN = "F28"  !CDS_PN = "F28";
"VDDCR_CPU0_F31":   PN = "F31"  !CDS_PN = "F31";
"VDDCR_CPU0_F34":   PN = "F34"  !CDS_PN = "F34";
"VDDCR_CPU0_F42":   PN = "F42"  !CDS_PN = "F42";
"VDDCR_CPU0_F45":   PN = "F45"  !CDS_PN = "F45";
"VDDCR_CPU0_F48":   PN = "F48"  !CDS_PN = "F48";
"VDDCR_CPU0_F51":   PN = "F51"  !CDS_PN = "F51";
"VDDCR_CPU0_F54":   PN = "F54"  !CDS_PN = "F54";
"VDDCR_CPU0_G35":   PN = "G35"  !CDS_PN = "G35";
"VDDCR_CPU0_G36":   PN = "G36"  !CDS_PN = "G36";
"VDDCR_CPU0_G40":   PN = "G40"  !CDS_PN = "G40";
"VDDCR_CPU0_G41":   PN = "G41"  !CDS_PN = "G41";
"VDDCR_CPU0_H23":   PN = "H23"  !CDS_PN = "H23";
"VDDCR_CPU0_H24":   PN = "H24"  !CDS_PN = "H24";
"VDDCR_CPU0_H26":   PN = "H26"  !CDS_PN = "H26";
"VDDCR_CPU0_H27":   PN = "H27"  !CDS_PN = "H27";
"VDDCR_CPU0_H29":   PN = "H29"  !CDS_PN = "H29";
"VDDCR_CPU0_H30":   PN = "H30"  !CDS_PN = "H30";
"VDDCR_CPU0_H32":   PN = "H32"  !CDS_PN = "H32";
"VDDCR_CPU0_H33":   PN = "H33"  !CDS_PN = "H33";
"VDDCR_CPU0_H43":   PN = "H43"  !CDS_PN = "H43";
"VDDCR_CPU0_H44":   PN = "H44"  !CDS_PN = "H44";
"VDDCR_CPU0_H46":   PN = "H46"  !CDS_PN = "H46";
"VDDCR_CPU0_H47":   PN = "H47"  !CDS_PN = "H47";
"VDDCR_CPU0_H49":   PN = "H49"  !CDS_PN = "H49";
"VDDCR_CPU0_H50":   PN = "H50"  !CDS_PN = "H50";
"VDDCR_CPU0_H52":   PN = "H52"  !CDS_PN = "H52";
"VDDCR_CPU0_H53":   PN = "H53"  !CDS_PN = "H53";
"VDDCR_CPU0_J35":   PN = "J35"  !CDS_PN = "J35";
"VDDCR_CPU0_J36":   PN = "J36"  !CDS_PN = "J36";
"VDDCR_CPU0_J40":   PN = "J40"  !CDS_PN = "J40";
"VDDCR_CPU0_J41":   PN = "J41"  !CDS_PN = "J41";
"VDDCR_CPU0_M23":   PN = "M23"  !CDS_PN = "M23";
"VDDCR_CPU0_M24":   PN = "M24"  !CDS_PN = "M24";
"VDDCR_CPU0_M26":   PN = "M26"  !CDS_PN = "M26";
"VDDCR_CPU0_M27":   PN = "M27"  !CDS_PN = "M27";
"VDDCR_CPU0_M29":   PN = "M29"  !CDS_PN = "M29";
"VDDCR_CPU0_M30":   PN = "M30"  !CDS_PN = "M30";
"VDDCR_CPU0_M32":   PN = "M32"  !CDS_PN = "M32";
"VDDCR_CPU0_M33":   PN = "M33"  !CDS_PN = "M33";
"VDDCR_CPU0_M43":   PN = "M43"  !CDS_PN = "M43";
"VDDCR_CPU0_M44":   PN = "M44"  !CDS_PN = "M44";
"VDDCR_CPU0_M46":   PN = "M46"  !CDS_PN = "M46";
"VDDCR_CPU0_M47":   PN = "M47"  !CDS_PN = "M47";
"VDDCR_CPU0_M49":   PN = "M49"  !CDS_PN = "M49";
"VDDCR_CPU0_M50":   PN = "M50"  !CDS_PN = "M50";
"VDDCR_CPU0_M52":   PN = "M52"  !CDS_PN = "M52";
"VDDCR_CPU0_M53":   PN = "M53"  !CDS_PN = "M53";
"VDDCR_CPU0_N35":   PN = "N35"  !CDS_PN = "N35";
"VDDCR_CPU0_N36":   PN = "N36"  !CDS_PN = "N36";
"VDDCR_CPU0_N40":   PN = "N40"  !CDS_PN = "N40";
"VDDCR_CPU0_N41":   PN = "N41"  !CDS_PN = "N41";
"VDDCR_CPU0_T23":   PN = "T23"  !CDS_PN = "T23";
"VDDCR_CPU0_T24":   PN = "T24"  !CDS_PN = "T24";
"VDDCR_CPU0_T26":   PN = "T26"  !CDS_PN = "T26";
"VDDCR_CPU0_T27":   PN = "T27"  !CDS_PN = "T27";
"VDDCR_CPU0_T29":   PN = "T29"  !CDS_PN = "T29";
"VDDCR_CPU0_T30":   PN = "T30"  !CDS_PN = "T30";
"VDDCR_CPU0_T32":   PN = "T32"  !CDS_PN = "T32";
"VDDCR_CPU0_T33":   PN = "T33"  !CDS_PN = "T33";
"VDDCR_CPU0_T43":   PN = "T43"  !CDS_PN = "T43";
"VDDCR_CPU0_T44":   PN = "T44"  !CDS_PN = "T44";
"VDDCR_CPU0_T46":   PN = "T46"  !CDS_PN = "T46";
"VDDCR_CPU0_T47":   PN = "T47"  !CDS_PN = "T47";
"VDDCR_CPU0_T49":   PN = "T49"  !CDS_PN = "T49";
"VDDCR_CPU0_T50":   PN = "T50"  !CDS_PN = "T50";
"VDDCR_CPU0_T52":   PN = "T52"  !CDS_PN = "T52";
"VDDCR_CPU0_T53":   PN = "T53"  !CDS_PN = "T53";
"VDDCR_CPU0_U35":   PN = "U35"  !CDS_PN = "U35";
"VDDCR_CPU0_U36":   PN = "U36"  !CDS_PN = "U36";
"VDDCR_CPU0_U40":   PN = "U40"  !CDS_PN = "U40";
"VDDCR_CPU0_U41":   PN = "U41"  !CDS_PN = "U41";
"VDDCR_CPU0_W29":   PN = "W29"  !CDS_PN = "W29";
"VDDCR_CPU0_W30":   PN = "W30"  !CDS_PN = "W30";
"VDDCR_CPU0_W32":   PN = "W32"  !CDS_PN = "W32";
"VDDCR_CPU0_W33":   PN = "W33"  !CDS_PN = "W33";
"VDDCR_CPU0_W43":   PN = "W43"  !CDS_PN = "W43";
"VDDCR_CPU0_W44":   PN = "W44"  !CDS_PN = "W44";
"VDDCR_CPU0_W46":   PN = "W46"  !CDS_PN = "W46";
"VDDCR_CPU0_W47":   PN = "W47"  !CDS_PN = "W47";
"VDDCR_CPU0_Y35":   PN = "Y35"  !CDS_PN = "Y35";
"VDDCR_CPU0_Y36":   PN = "Y36"  !CDS_PN = "Y36";
"VDDCR_CPU0_Y40":   PN = "Y40"  !CDS_PN = "Y40";
"VDDCR_CPU0_Y41":   PN = "Y41"  !CDS_PN = "Y41";
BODY = "GENOA_SP5","I45": #LOCATION = "U25" !CDS_LOCATION = "U25" &SEC = "25" #&CDS_SEC = "25";
"VDDCR_CPU1_BN27":   PN = "BN27"  !CDS_PN = "BN27";
"VDDCR_CPU1_BN31":   PN = "BN31"  !CDS_PN = "BN31";
"VDDCR_CPU1_BN35":   PN = "BN35"  !CDS_PN = "BN35";
"VDDCR_CPU1_BN42":   PN = "BN42"  !CDS_PN = "BN42";
"VDDCR_CPU1_BN46":   PN = "BN46"  !CDS_PN = "BN46";
"VDDCR_CPU1_BN50":   PN = "BN50"  !CDS_PN = "BN50";
"VDDCR_CPU1_BP24":   PN = "BP24"  !CDS_PN = "BP24";
"VDDCR_CPU1_BP26":   PN = "BP26"  !CDS_PN = "BP26";
"VDDCR_CPU1_BP28":   PN = "BP28"  !CDS_PN = "BP28";
"VDDCR_CPU1_BP30":   PN = "BP30"  !CDS_PN = "BP30";
"VDDCR_CPU1_BP32":   PN = "BP32"  !CDS_PN = "BP32";
"VDDCR_CPU1_BP34":   PN = "BP34"  !CDS_PN = "BP34";
"VDDCR_CPU1_BP36":   PN = "BP36"  !CDS_PN = "BP36";
"VDDCR_CPU1_BP39":   PN = "BP39"  !CDS_PN = "BP39";
"VDDCR_CPU1_BP41":   PN = "BP41"  !CDS_PN = "BP41";
"VDDCR_CPU1_BP43":   PN = "BP43"  !CDS_PN = "BP43";
"VDDCR_CPU1_BP45":   PN = "BP45"  !CDS_PN = "BP45";
"VDDCR_CPU1_BP47":   PN = "BP47"  !CDS_PN = "BP47";
"VDDCR_CPU1_BP49":   PN = "BP49"  !CDS_PN = "BP49";
"VDDCR_CPU1_BR23":   PN = "BR23"  !CDS_PN = "BR23";
"VDDCR_CPU1_BR25":   PN = "BR25"  !CDS_PN = "BR25";
"VDDCR_CPU1_BR27":   PN = "BR27"  !CDS_PN = "BR27";
"VDDCR_CPU1_BR29":   PN = "BR29"  !CDS_PN = "BR29";
"VDDCR_CPU1_BR31":   PN = "BR31"  !CDS_PN = "BR31";
"VDDCR_CPU1_BR33":   PN = "BR33"  !CDS_PN = "BR33";
"VDDCR_CPU1_BR35":   PN = "BR35"  !CDS_PN = "BR35";
"VDDCR_CPU1_BR40":   PN = "BR40"  !CDS_PN = "BR40";
"VDDCR_CPU1_BR42":   PN = "BR42"  !CDS_PN = "BR42";
"VDDCR_CPU1_BR44":   PN = "BR44"  !CDS_PN = "BR44";
"VDDCR_CPU1_BR46":   PN = "BR46"  !CDS_PN = "BR46";
"VDDCR_CPU1_BR48":   PN = "BR48"  !CDS_PN = "BR48";
"VDDCR_CPU1_BR50":   PN = "BR50"  !CDS_PN = "BR50";
"VDDCR_CPU1_BR52":   PN = "BR52"  !CDS_PN = "BR52";
"VDDCR_CPU1_BT23":   PN = "BT23"  !CDS_PN = "BT23";
"VDDCR_CPU1_BT24":   PN = "BT24"  !CDS_PN = "BT24";
"VDDCR_CPU1_BT26":   PN = "BT26"  !CDS_PN = "BT26";
"VDDCR_CPU1_BT27":   PN = "BT27"  !CDS_PN = "BT27";
"VDDCR_CPU1_BT29":   PN = "BT29"  !CDS_PN = "BT29";
"VDDCR_CPU1_BT30":   PN = "BT30"  !CDS_PN = "BT30";
"VDDCR_CPU1_BT32":   PN = "BT32"  !CDS_PN = "BT32";
"VDDCR_CPU1_BT33":   PN = "BT33"  !CDS_PN = "BT33";
"VDDCR_CPU1_BT43":   PN = "BT43"  !CDS_PN = "BT43";
"VDDCR_CPU1_BT44":   PN = "BT44"  !CDS_PN = "BT44";
"VDDCR_CPU1_BT46":   PN = "BT46"  !CDS_PN = "BT46";
"VDDCR_CPU1_BT47":   PN = "BT47"  !CDS_PN = "BT47";
"VDDCR_CPU1_BT49":   PN = "BT49"  !CDS_PN = "BT49";
"VDDCR_CPU1_BT50":   PN = "BT50"  !CDS_PN = "BT50";
"VDDCR_CPU1_BT52":   PN = "BT52"  !CDS_PN = "BT52";
"VDDCR_CPU1_BT53":   PN = "BT53"  !CDS_PN = "BT53";
"VDDCR_CPU1_BW35":   PN = "BW35"  !CDS_PN = "BW35";
"VDDCR_CPU1_BW36":   PN = "BW36"  !CDS_PN = "BW36";
"VDDCR_CPU1_BW40":   PN = "BW40"  !CDS_PN = "BW40";
"VDDCR_CPU1_BW41":   PN = "BW41"  !CDS_PN = "BW41";
"VDDCR_CPU1_BY23":   PN = "BY23"  !CDS_PN = "BY23";
"VDDCR_CPU1_BY24":   PN = "BY24"  !CDS_PN = "BY24";
"VDDCR_CPU1_BY26":   PN = "BY26"  !CDS_PN = "BY26";
"VDDCR_CPU1_BY27":   PN = "BY27"  !CDS_PN = "BY27";
"VDDCR_CPU1_BY29":   PN = "BY29"  !CDS_PN = "BY29";
"VDDCR_CPU1_BY30":   PN = "BY30"  !CDS_PN = "BY30";
"VDDCR_CPU1_BY32":   PN = "BY32"  !CDS_PN = "BY32";
"VDDCR_CPU1_BY33":   PN = "BY33"  !CDS_PN = "BY33";
"VDDCR_CPU1_BY43":   PN = "BY43"  !CDS_PN = "BY43";
"VDDCR_CPU1_BY44":   PN = "BY44"  !CDS_PN = "BY44";
"VDDCR_CPU1_BY46":   PN = "BY46"  !CDS_PN = "BY46";
"VDDCR_CPU1_BY47":   PN = "BY47"  !CDS_PN = "BY47";
"VDDCR_CPU1_BY49":   PN = "BY49"  !CDS_PN = "BY49";
"VDDCR_CPU1_BY50":   PN = "BY50"  !CDS_PN = "BY50";
"VDDCR_CPU1_BY52":   PN = "BY52"  !CDS_PN = "BY52";
"VDDCR_CPU1_BY53":   PN = "BY53"  !CDS_PN = "BY53";
"VDDCR_CPU1_CC35":   PN = "CC35"  !CDS_PN = "CC35";
"VDDCR_CPU1_CC36":   PN = "CC36"  !CDS_PN = "CC36";
"VDDCR_CPU1_CC40":   PN = "CC40"  !CDS_PN = "CC40";
"VDDCR_CPU1_CC41":   PN = "CC41"  !CDS_PN = "CC41";
"VDDCR_CPU1_CD23":   PN = "CD23"  !CDS_PN = "CD23";
"VDDCR_CPU1_CD24":   PN = "CD24"  !CDS_PN = "CD24";
"VDDCR_CPU1_CD26":   PN = "CD26"  !CDS_PN = "CD26";
"VDDCR_CPU1_CD27":   PN = "CD27"  !CDS_PN = "CD27";
"VDDCR_CPU1_CD29":   PN = "CD29"  !CDS_PN = "CD29";
"VDDCR_CPU1_CD30":   PN = "CD30"  !CDS_PN = "CD30";
"VDDCR_CPU1_CD32":   PN = "CD32"  !CDS_PN = "CD32";
"VDDCR_CPU1_CD33":   PN = "CD33"  !CDS_PN = "CD33";
"VDDCR_CPU1_CD43":   PN = "CD43"  !CDS_PN = "CD43";
"VDDCR_CPU1_CD44":   PN = "CD44"  !CDS_PN = "CD44";
"VDDCR_CPU1_CD46":   PN = "CD46"  !CDS_PN = "CD46";
"VDDCR_CPU1_CD47":   PN = "CD47"  !CDS_PN = "CD47";
"VDDCR_CPU1_CD49":   PN = "CD49"  !CDS_PN = "CD49";
"VDDCR_CPU1_CD50":   PN = "CD50"  !CDS_PN = "CD50";
"VDDCR_CPU1_CD52":   PN = "CD52"  !CDS_PN = "CD52";
"VDDCR_CPU1_CD53":   PN = "CD53"  !CDS_PN = "CD53";
"VDDCR_CPU1_CG35":   PN = "CG35"  !CDS_PN = "CG35";
"VDDCR_CPU1_CG36":   PN = "CG36"  !CDS_PN = "CG36";
"VDDCR_CPU1_CG40":   PN = "CG40"  !CDS_PN = "CG40";
"VDDCR_CPU1_CG41":   PN = "CG41"  !CDS_PN = "CG41";
"VDDCR_CPU1_CH23":   PN = "CH23"  !CDS_PN = "CH23";
"VDDCR_CPU1_CH24":   PN = "CH24"  !CDS_PN = "CH24";
"VDDCR_CPU1_CH26":   PN = "CH26"  !CDS_PN = "CH26";
"VDDCR_CPU1_CH27":   PN = "CH27"  !CDS_PN = "CH27";
"VDDCR_CPU1_CH29":   PN = "CH29"  !CDS_PN = "CH29";
"VDDCR_CPU1_CH30":   PN = "CH30"  !CDS_PN = "CH30";
"VDDCR_CPU1_CH32":   PN = "CH32"  !CDS_PN = "CH32";
"VDDCR_CPU1_CH33":   PN = "CH33"  !CDS_PN = "CH33";
"VDDCR_CPU1_CH43":   PN = "CH43"  !CDS_PN = "CH43";
"VDDCR_CPU1_CH44":   PN = "CH44"  !CDS_PN = "CH44";
"VDDCR_CPU1_CH46":   PN = "CH46"  !CDS_PN = "CH46";
"VDDCR_CPU1_CH47":   PN = "CH47"  !CDS_PN = "CH47";
"VDDCR_CPU1_CH49":   PN = "CH49"  !CDS_PN = "CH49";
"VDDCR_CPU1_CH50":   PN = "CH50"  !CDS_PN = "CH50";
"VDDCR_CPU1_CH52":   PN = "CH52"  !CDS_PN = "CH52";
"VDDCR_CPU1_CH53":   PN = "CH53"  !CDS_PN = "CH53";
"VDDCR_CPU1_CK35":   PN = "CK35"  !CDS_PN = "CK35";
"VDDCR_CPU1_CK36":   PN = "CK36"  !CDS_PN = "CK36";
"VDDCR_CPU1_CK40":   PN = "CK40"  !CDS_PN = "CK40";
"VDDCR_CPU1_CK41":   PN = "CK41"  !CDS_PN = "CK41";
"VDDCR_CPU1_CL29":   PN = "CL29"  !CDS_PN = "CL29";
"VDDCR_CPU1_CL30":   PN = "CL30"  !CDS_PN = "CL30";
"VDDCR_CPU1_CL32":   PN = "CL32"  !CDS_PN = "CL32";
"VDDCR_CPU1_CL33":   PN = "CL33"  !CDS_PN = "CL33";
"VDDCR_CPU1_CL43":   PN = "CL43"  !CDS_PN = "CL43";
"VDDCR_CPU1_CL44":   PN = "CL44"  !CDS_PN = "CL44";
"VDDCR_CPU1_CL46":   PN = "CL46"  !CDS_PN = "CL46";
"VDDCR_CPU1_CL47":   PN = "CL47"  !CDS_PN = "CL47";
"VDDCR_CPU1_CN35":   PN = "CN35"  !CDS_PN = "CN35";
"VDDCR_CPU1_CN36":   PN = "CN36"  !CDS_PN = "CN36";
"VDDCR_CPU1_CN40":   PN = "CN40"  !CDS_PN = "CN40";
"VDDCR_CPU1_CN41":   PN = "CN41"  !CDS_PN = "CN41";
"VDDCR_CPU1_CP23":   PN = "CP23"  !CDS_PN = "CP23";
"VDDCR_CPU1_CP24":   PN = "CP24"  !CDS_PN = "CP24";
"VDDCR_CPU1_CP26":   PN = "CP26"  !CDS_PN = "CP26";
"VDDCR_CPU1_CP27":   PN = "CP27"  !CDS_PN = "CP27";
"VDDCR_CPU1_CP29":   PN = "CP29"  !CDS_PN = "CP29";
"VDDCR_CPU1_CP30":   PN = "CP30"  !CDS_PN = "CP30";
"VDDCR_CPU1_CP32":   PN = "CP32"  !CDS_PN = "CP32";
"VDDCR_CPU1_CP33":   PN = "CP33"  !CDS_PN = "CP33";
"VDDCR_CPU1_CP43":   PN = "CP43"  !CDS_PN = "CP43";
"VDDCR_CPU1_CP44":   PN = "CP44"  !CDS_PN = "CP44";
"VDDCR_CPU1_CP46":   PN = "CP46"  !CDS_PN = "CP46";
"VDDCR_CPU1_CP47":   PN = "CP47"  !CDS_PN = "CP47";
"VDDCR_CPU1_CP49":   PN = "CP49"  !CDS_PN = "CP49";
"VDDCR_CPU1_CP50":   PN = "CP50"  !CDS_PN = "CP50";
"VDDCR_CPU1_CP52":   PN = "CP52"  !CDS_PN = "CP52";
"VDDCR_CPU1_CP53":   PN = "CP53"  !CDS_PN = "CP53";
"VDDCR_CPU1_CU35":   PN = "CU35"  !CDS_PN = "CU35";
"VDDCR_CPU1_CU36":   PN = "CU36"  !CDS_PN = "CU36";
"VDDCR_CPU1_CU40":   PN = "CU40"  !CDS_PN = "CU40";
"VDDCR_CPU1_CU41":   PN = "CU41"  !CDS_PN = "CU41";
"VDDCR_CPU1_CV23":   PN = "CV23"  !CDS_PN = "CV23";
"VDDCR_CPU1_CV24":   PN = "CV24"  !CDS_PN = "CV24";
"VDDCR_CPU1_CV26":   PN = "CV26"  !CDS_PN = "CV26";
"VDDCR_CPU1_CV27":   PN = "CV27"  !CDS_PN = "CV27";
"VDDCR_CPU1_CV29":   PN = "CV29"  !CDS_PN = "CV29";
"VDDCR_CPU1_CV30":   PN = "CV30"  !CDS_PN = "CV30";
"VDDCR_CPU1_CV32":   PN = "CV32"  !CDS_PN = "CV32";
"VDDCR_CPU1_CV33":   PN = "CV33"  !CDS_PN = "CV33";
"VDDCR_CPU1_CV43":   PN = "CV43"  !CDS_PN = "CV43";
"VDDCR_CPU1_CV44":   PN = "CV44"  !CDS_PN = "CV44";
"VDDCR_CPU1_CV46":   PN = "CV46"  !CDS_PN = "CV46";
"VDDCR_CPU1_CV47":   PN = "CV47"  !CDS_PN = "CV47";
"VDDCR_CPU1_CV49":   PN = "CV49"  !CDS_PN = "CV49";
"VDDCR_CPU1_CV50":   PN = "CV50"  !CDS_PN = "CV50";
"VDDCR_CPU1_CV52":   PN = "CV52"  !CDS_PN = "CV52";
"VDDCR_CPU1_CV53":   PN = "CV53"  !CDS_PN = "CV53";
"VDDCR_CPU1_DA35":   PN = "DA35"  !CDS_PN = "DA35";
"VDDCR_CPU1_DA36":   PN = "DA36"  !CDS_PN = "DA36";
"VDDCR_CPU1_DA40":   PN = "DA40"  !CDS_PN = "DA40";
"VDDCR_CPU1_DA41":   PN = "DA41"  !CDS_PN = "DA41";
"VDDCR_CPU1_DB23":   PN = "DB23"  !CDS_PN = "DB23";
"VDDCR_CPU1_DB24":   PN = "DB24"  !CDS_PN = "DB24";
"VDDCR_CPU1_DB26":   PN = "DB26"  !CDS_PN = "DB26";
"VDDCR_CPU1_DB27":   PN = "DB27"  !CDS_PN = "DB27";
"VDDCR_CPU1_DB29":   PN = "DB29"  !CDS_PN = "DB29";
"VDDCR_CPU1_DB30":   PN = "DB30"  !CDS_PN = "DB30";
"VDDCR_CPU1_DB32":   PN = "DB32"  !CDS_PN = "DB32";
"VDDCR_CPU1_DB33":   PN = "DB33"  !CDS_PN = "DB33";
"VDDCR_CPU1_DB43":   PN = "DB43"  !CDS_PN = "DB43";
"VDDCR_CPU1_DB44":   PN = "DB44"  !CDS_PN = "DB44";
"VDDCR_CPU1_DB46":   PN = "DB46"  !CDS_PN = "DB46";
"VDDCR_CPU1_DB47":   PN = "DB47"  !CDS_PN = "DB47";
"VDDCR_CPU1_DB49":   PN = "DB49"  !CDS_PN = "DB49";
"VDDCR_CPU1_DB50":   PN = "DB50"  !CDS_PN = "DB50";
"VDDCR_CPU1_DB52":   PN = "DB52"  !CDS_PN = "DB52";
"VDDCR_CPU1_DB53":   PN = "DB53"  !CDS_PN = "DB53";
"VDDCR_CPU1_DC35":   PN = "DC35"  !CDS_PN = "DC35";
"VDDCR_CPU1_DC36":   PN = "DC36"  !CDS_PN = "DC36";
"VDDCR_CPU1_DC40":   PN = "DC40"  !CDS_PN = "DC40";
"VDDCR_CPU1_DC41":   PN = "DC41"  !CDS_PN = "DC41";
"VDDCR_CPU1_DD22":   PN = "DD22"  !CDS_PN = "DD22";
"VDDCR_CPU1_DD25":   PN = "DD25"  !CDS_PN = "DD25";
"VDDCR_CPU1_DD28":   PN = "DD28"  !CDS_PN = "DD28";
"VDDCR_CPU1_DD31":   PN = "DD31"  !CDS_PN = "DD31";
"VDDCR_CPU1_DD34":   PN = "DD34"  !CDS_PN = "DD34";
"VDDCR_CPU1_DD42":   PN = "DD42"  !CDS_PN = "DD42";
"VDDCR_CPU1_DD45":   PN = "DD45"  !CDS_PN = "DD45";
"VDDCR_CPU1_DD48":   PN = "DD48"  !CDS_PN = "DD48";
"VDDCR_CPU1_DD51":   PN = "DD51"  !CDS_PN = "DD51";
"VDDCR_CPU1_DD54":   PN = "DD54"  !CDS_PN = "DD54";
"VDDCR_CPU1_DE22":   PN = "DE22"  !CDS_PN = "DE22";
"VDDCR_CPU1_DE25":   PN = "DE25"  !CDS_PN = "DE25";
"VDDCR_CPU1_DE28":   PN = "DE28"  !CDS_PN = "DE28";
"VDDCR_CPU1_DE31":   PN = "DE31"  !CDS_PN = "DE31";
"VDDCR_CPU1_DE34":   PN = "DE34"  !CDS_PN = "DE34";
"VDDCR_CPU1_DE35":   PN = "DE35"  !CDS_PN = "DE35";
"VDDCR_CPU1_DE41":   PN = "DE41"  !CDS_PN = "DE41";
"VDDCR_CPU1_DE42":   PN = "DE42"  !CDS_PN = "DE42";
"VDDCR_CPU1_DE45":   PN = "DE45"  !CDS_PN = "DE45";
"VDDCR_CPU1_DE48":   PN = "DE48"  !CDS_PN = "DE48";
"VDDCR_CPU1_DE51":   PN = "DE51"  !CDS_PN = "DE51";
"VDDCR_CPU1_DE54":   PN = "DE54"  !CDS_PN = "DE54";
"VDDCR_CPU1_DG19":   PN = "DG19"  !CDS_PN = "DG19";
"VDDCR_CPU1_DG57":   PN = "DG57"  !CDS_PN = "DG57";
"VDDCR_CPU1_DH19":   PN = "DH19"  !CDS_PN = "DH19";
"VDDCR_CPU1_DH20":   PN = "DH20"  !CDS_PN = "DH20";
"VDDCR_CPU1_DH22":   PN = "DH22"  !CDS_PN = "DH22";
"VDDCR_CPU1_DH23":   PN = "DH23"  !CDS_PN = "DH23";
"VDDCR_CPU1_DH25":   PN = "DH25"  !CDS_PN = "DH25";
"VDDCR_CPU1_DH26":   PN = "DH26"  !CDS_PN = "DH26";
"VDDCR_CPU1_DH28":   PN = "DH28"  !CDS_PN = "DH28";
"VDDCR_CPU1_DH29":   PN = "DH29"  !CDS_PN = "DH29";
"VDDCR_CPU1_DH31":   PN = "DH31"  !CDS_PN = "DH31";
"VDDCR_CPU1_DH32":   PN = "DH32"  !CDS_PN = "DH32";
"VDDCR_CPU1_DH34":   PN = "DH34"  !CDS_PN = "DH34";
"VDDCR_CPU1_DH35":   PN = "DH35"  !CDS_PN = "DH35";
"VDDCR_CPU1_DH41":   PN = "DH41"  !CDS_PN = "DH41";
"VDDCR_CPU1_DH42":   PN = "DH42"  !CDS_PN = "DH42";
"VDDCR_CPU1_DH44":   PN = "DH44"  !CDS_PN = "DH44";
"VDDCR_CPU1_DH45":   PN = "DH45"  !CDS_PN = "DH45";
"VDDCR_CPU1_DH47":   PN = "DH47"  !CDS_PN = "DH47";
"VDDCR_CPU1_DH48":   PN = "DH48"  !CDS_PN = "DH48";
"VDDCR_CPU1_DH50":   PN = "DH50"  !CDS_PN = "DH50";
"VDDCR_CPU1_DH51":   PN = "DH51"  !CDS_PN = "DH51";
"VDDCR_CPU1_DH53":   PN = "DH53"  !CDS_PN = "DH53";
"VDDCR_CPU1_DH54":   PN = "DH54"  !CDS_PN = "DH54";
"VDDCR_CPU1_DH56":   PN = "DH56"  !CDS_PN = "DH56";
"VDDCR_CPU1_DH57":   PN = "DH57"  !CDS_PN = "DH57";
BODY = "GENOA_SP5","I50": #LOCATION = "U25" !CDS_LOCATION = "U25" &SEC = "26" #&CDS_SEC = "26";
"VDDCR_SOC_AA22":   PN = "AA22"  !CDS_PN = "AA22";
"VDDCR_SOC_AC4":   PN = "AC4"  !CDS_PN = "AC4";
"VDDCR_SOC_AC11":   PN = "AC11"  !CDS_PN = "AC11";
"VDDCR_SOC_AC18":   PN = "AC18"  !CDS_PN = "AC18";
"VDDCR_SOC_AD22":   PN = "AD22"  !CDS_PN = "AD22";
"VDDCR_SOC_AF5":   PN = "AF5"  !CDS_PN = "AF5";
"VDDCR_SOC_AF12":   PN = "AF12"  !CDS_PN = "AF12";
"VDDCR_SOC_AF19":   PN = "AF19"  !CDS_PN = "AF19";
"VDDCR_SOC_AH22":   PN = "AH22"  !CDS_PN = "AH22";
"VDDCR_SOC_AJ4":   PN = "AJ4"  !CDS_PN = "AJ4";
"VDDCR_SOC_AJ11":   PN = "AJ11"  !CDS_PN = "AJ11";
"VDDCR_SOC_AJ18":   PN = "AJ18"  !CDS_PN = "AJ18";
"VDDCR_SOC_AM5":   PN = "AM5"  !CDS_PN = "AM5";
"VDDCR_SOC_AM12":   PN = "AM12"  !CDS_PN = "AM12";
"VDDCR_SOC_AM19":   PN = "AM19"  !CDS_PN = "AM19";
"VDDCR_SOC_AM22":   PN = "AM22"  !CDS_PN = "AM22";
"VDDCR_SOC_AR4":   PN = "AR4"  !CDS_PN = "AR4";
"VDDCR_SOC_AR11":   PN = "AR11"  !CDS_PN = "AR11";
"VDDCR_SOC_AR18":   PN = "AR18"  !CDS_PN = "AR18";
"VDDCR_SOC_AT22":   PN = "AT22"  !CDS_PN = "AT22";
"VDDCR_SOC_AU23":   PN = "AU23"  !CDS_PN = "AU23";
"VDDCR_SOC_AU27":   PN = "AU27"  !CDS_PN = "AU27";
"VDDCR_SOC_AU31":   PN = "AU31"  !CDS_PN = "AU31";
"VDDCR_SOC_AU35":   PN = "AU35"  !CDS_PN = "AU35";
"VDDCR_SOC_AU40":   PN = "AU40"  !CDS_PN = "AU40";
"VDDCR_SOC_AV5":   PN = "AV5"  !CDS_PN = "AV5";
"VDDCR_SOC_AV12":   PN = "AV12"  !CDS_PN = "AV12";
"VDDCR_SOC_AV19":   PN = "AV19"  !CDS_PN = "AV19";
"VDDCR_SOC_AV22":   PN = "AV22"  !CDS_PN = "AV22";
"VDDCR_SOC_AV24":   PN = "AV24"  !CDS_PN = "AV24";
"VDDCR_SOC_AV26":   PN = "AV26"  !CDS_PN = "AV26";
"VDDCR_SOC_AV28":   PN = "AV28"  !CDS_PN = "AV28";
"VDDCR_SOC_AV30":   PN = "AV30"  !CDS_PN = "AV30";
"VDDCR_SOC_AV32":   PN = "AV32"  !CDS_PN = "AV32";
"VDDCR_SOC_AV34":   PN = "AV34"  !CDS_PN = "AV34";
"VDDCR_SOC_AV36":   PN = "AV36"  !CDS_PN = "AV36";
"VDDCR_SOC_AV39":   PN = "AV39"  !CDS_PN = "AV39";
"VDDCR_SOC_AV41":   PN = "AV41"  !CDS_PN = "AV41";
"VDDCR_SOC_AV43":   PN = "AV43"  !CDS_PN = "AV43";
"VDDCR_SOC_AV45":   PN = "AV45"  !CDS_PN = "AV45";
"VDDCR_SOC_AV47":   PN = "AV47"  !CDS_PN = "AV47";
"VDDCR_SOC_AW23":   PN = "AW23"  !CDS_PN = "AW23";
"VDDCR_SOC_AW25":   PN = "AW25"  !CDS_PN = "AW25";
"VDDCR_SOC_AW27":   PN = "AW27"  !CDS_PN = "AW27";
"VDDCR_SOC_AW48":   PN = "AW48"  !CDS_PN = "AW48";
"VDDCR_SOC_AY22":   PN = "AY22"  !CDS_PN = "AY22";
"VDDCR_SOC_AY24":   PN = "AY24"  !CDS_PN = "AY24";
"VDDCR_SOC_AY26":   PN = "AY26"  !CDS_PN = "AY26";
"VDDCR_SOC_AY28":   PN = "AY28"  !CDS_PN = "AY28";
"VDDCR_SOC_AY49":   PN = "AY49"  !CDS_PN = "AY49";
"VDDCR_SOC_B5":   PN = "B5"  !CDS_PN = "B5";
"VDDCR_SOC_BA4":   PN = "BA4"  !CDS_PN = "BA4";
"VDDCR_SOC_BA11":   PN = "BA11"  !CDS_PN = "BA11";
"VDDCR_SOC_BA18":   PN = "BA18"  !CDS_PN = "BA18";
"VDDCR_SOC_BA23":   PN = "BA23"  !CDS_PN = "BA23";
"VDDCR_SOC_BA25":   PN = "BA25"  !CDS_PN = "BA25";
"VDDCR_SOC_BA27":   PN = "BA27"  !CDS_PN = "BA27";
"VDDCR_SOC_BA48":   PN = "BA48"  !CDS_PN = "BA48";
"VDDCR_SOC_BB22":   PN = "BB22"  !CDS_PN = "BB22";
"VDDCR_SOC_BB24":   PN = "BB24"  !CDS_PN = "BB24";
"VDDCR_SOC_BB26":   PN = "BB26"  !CDS_PN = "BB26";
"VDDCR_SOC_BB28":   PN = "BB28"  !CDS_PN = "BB28";
"VDDCR_SOC_BB49":   PN = "BB49"  !CDS_PN = "BB49";
"VDDCR_SOC_BC23":   PN = "BC23"  !CDS_PN = "BC23";
"VDDCR_SOC_BC25":   PN = "BC25"  !CDS_PN = "BC25";
"VDDCR_SOC_BC27":   PN = "BC27"  !CDS_PN = "BC27";
"VDDCR_SOC_BC48":   PN = "BC48"  !CDS_PN = "BC48";
"VDDCR_SOC_BD5":   PN = "BD5"  !CDS_PN = "BD5";
"VDDCR_SOC_BD12":   PN = "BD12"  !CDS_PN = "BD12";
"VDDCR_SOC_BD19":   PN = "BD19"  !CDS_PN = "BD19";
"VDDCR_SOC_BD22":   PN = "BD22"  !CDS_PN = "BD22";
"VDDCR_SOC_BD24":   PN = "BD24"  !CDS_PN = "BD24";
"VDDCR_SOC_BD26":   PN = "BD26"  !CDS_PN = "BD26";
"VDDCR_SOC_BD28":   PN = "BD28"  !CDS_PN = "BD28";
"VDDCR_SOC_BD48":   PN = "BD48"  !CDS_PN = "BD48";
"VDDCR_SOC_BF23":   PN = "BF23"  !CDS_PN = "BF23";
"VDDCR_SOC_BF25":   PN = "BF25"  !CDS_PN = "BF25";
"VDDCR_SOC_BF27":   PN = "BF27"  !CDS_PN = "BF27";
"VDDCR_SOC_BF48":   PN = "BF48"  !CDS_PN = "BF48";
"VDDCR_SOC_BG22":   PN = "BG22"  !CDS_PN = "BG22";
"VDDCR_SOC_BG24":   PN = "BG24"  !CDS_PN = "BG24";
"VDDCR_SOC_BG26":   PN = "BG26"  !CDS_PN = "BG26";
"VDDCR_SOC_BG28":   PN = "BG28"  !CDS_PN = "BG28";
"VDDCR_SOC_BG48":   PN = "BG48"  !CDS_PN = "BG48";
"VDDCR_SOC_BH23":   PN = "BH23"  !CDS_PN = "BH23";
"VDDCR_SOC_BH25":   PN = "BH25"  !CDS_PN = "BH25";
"VDDCR_SOC_BH48":   PN = "BH48"  !CDS_PN = "BH48";
"VDDCR_SOC_BJ4":   PN = "BJ4"  !CDS_PN = "BJ4";
"VDDCR_SOC_BJ11":   PN = "BJ11"  !CDS_PN = "BJ11";
"VDDCR_SOC_BJ48":   PN = "BJ48"  !CDS_PN = "BJ48";
"VDDCR_SOC_BM5":   PN = "BM5"  !CDS_PN = "BM5";
"VDDCR_SOC_C4":   PN = "C4"  !CDS_PN = "C4";
"VDDCR_SOC_E4":   PN = "E4"  !CDS_PN = "E4";
"VDDCR_SOC_E11":   PN = "E11"  !CDS_PN = "E11";
"VDDCR_SOC_H5":   PN = "H5"  !CDS_PN = "H5";
"VDDCR_SOC_H12":   PN = "H12"  !CDS_PN = "H12";
"VDDCR_SOC_H19":   PN = "H19"  !CDS_PN = "H19";
"VDDCR_SOC_K22":   PN = "K22"  !CDS_PN = "K22";
"VDDCR_SOC_L4":   PN = "L4"  !CDS_PN = "L4";
"VDDCR_SOC_L11":   PN = "L11"  !CDS_PN = "L11";
"VDDCR_SOC_L18":   PN = "L18"  !CDS_PN = "L18";
"VDDCR_SOC_P5":   PN = "P5"  !CDS_PN = "P5";
"VDDCR_SOC_P12":   PN = "P12"  !CDS_PN = "P12";
"VDDCR_SOC_P19":   PN = "P19"  !CDS_PN = "P19";
"VDDCR_SOC_P22":   PN = "P22"  !CDS_PN = "P22";
"VDDCR_SOC_U4":   PN = "U4"  !CDS_PN = "U4";
"VDDCR_SOC_U11":   PN = "U11"  !CDS_PN = "U11";
"VDDCR_SOC_U18":   PN = "U18"  !CDS_PN = "U18";
"VDDCR_SOC_V22":   PN = "V22"  !CDS_PN = "V22";
"VDDCR_SOC_Y5":   PN = "Y5"  !CDS_PN = "Y5";
"VDDCR_SOC_Y12":   PN = "Y12"  !CDS_PN = "Y12";
"VDDCR_SOC_Y19":   PN = "Y19"  !CDS_PN = "Y19";
DRAWING = "@t6g_mb_lib.t6g(sch_1):page31";
BODY = "GENOA_SP5","I19": #LOCATION = "U25" !CDS_LOCATION = "U25" &SEC = "28" #&CDS_SEC = "28";
"VSS_A3":   PN = "A3"  !CDS_PN = "A3";
"VSS_A9":   PN = "A9"  !CDS_PN = "A9";
"VSS_A15":   PN = "A15"  !CDS_PN = "A15";
"VSS_A21":   PN = "A21"  !CDS_PN = "A21";
"VSS_A27":   PN = "A27"  !CDS_PN = "A27";
"VSS_A43":   PN = "A43"  !CDS_PN = "A43";
"VSS_A44":   PN = "A44"  !CDS_PN = "A44";
"VSS_A47":   PN = "A47"  !CDS_PN = "A47";
"VSS_A49":   PN = "A49"  !CDS_PN = "A49";
"VSS_A53":   PN = "A53"  !CDS_PN = "A53";
"VSS_A61":   PN = "A61"  !CDS_PN = "A61";
"VSS_A67":   PN = "A67"  !CDS_PN = "A67";
"VSS_A72":   PN = "A72"  !CDS_PN = "A72";
"VSS_A73":   PN = "A73"  !CDS_PN = "A73";
"VSS_B7":   PN = "B7"  !CDS_PN = "B7";
"VSS_B8":   PN = "B8"  !CDS_PN = "B8";
"VSS_B10":   PN = "B10"  !CDS_PN = "B10";
"VSS_B11":   PN = "B11"  !CDS_PN = "B11";
"VSS_B13":   PN = "B13"  !CDS_PN = "B13";
"VSS_B18":   PN = "B18"  !CDS_PN = "B18";
"VSS_B24":   PN = "B24"  !CDS_PN = "B24";
"VSS_B27":   PN = "B27"  !CDS_PN = "B27";
"VSS_B30":   PN = "B30"  !CDS_PN = "B30";
"VSS_B33":   PN = "B33"  !CDS_PN = "B33";
"VSS_B37":   PN = "B37"  !CDS_PN = "B37";
"VSS_B39":   PN = "B39"  !CDS_PN = "B39";
"VSS_B43":   PN = "B43"  !CDS_PN = "B43";
"VSS_B46":   PN = "B46"  !CDS_PN = "B46";
"VSS_B49":   PN = "B49"  !CDS_PN = "B49";
"VSS_B52":   PN = "B52"  !CDS_PN = "B52";
"VSS_B55":   PN = "B55"  !CDS_PN = "B55";
"VSS_B59":   PN = "B59"  !CDS_PN = "B59";
"VSS_B62":   PN = "B62"  !CDS_PN = "B62";
"VSS_B65":   PN = "B65"  !CDS_PN = "B65";
"VSS_B68":   PN = "B68"  !CDS_PN = "B68";
"VSS_B70":   PN = "B70"  !CDS_PN = "B70";
"VSS_C1":   PN = "C1"  !CDS_PN = "C1";
"VSS_C5":   PN = "C5"  !CDS_PN = "C5";
"VSS_C8":   PN = "C8"  !CDS_PN = "C8";
"VSS_C10":   PN = "C10"  !CDS_PN = "C10";
"VSS_C11":   PN = "C11"  !CDS_PN = "C11";
"VSS_C13":   PN = "C13"  !CDS_PN = "C13";
"VSS_C15":   PN = "C15"  !CDS_PN = "C15";
"VSS_C21":   PN = "C21"  !CDS_PN = "C21";
"VSS_C24":   PN = "C24"  !CDS_PN = "C24";
"VSS_C27":   PN = "C27"  !CDS_PN = "C27";
"VSS_C30":   PN = "C30"  !CDS_PN = "C30";
"VSS_C36":   PN = "C36"  !CDS_PN = "C36";
"VSS_C40":   PN = "C40"  !CDS_PN = "C40";
"VSS_C43":   PN = "C43"  !CDS_PN = "C43";
"VSS_C46":   PN = "C46"  !CDS_PN = "C46";
"VSS_C49":   PN = "C49"  !CDS_PN = "C49";
"VSS_C52":   PN = "C52"  !CDS_PN = "C52";
"VSS_C55":   PN = "C55"  !CDS_PN = "C55";
"VSS_C56":   PN = "C56"  !CDS_PN = "C56";
"VSS_C57":   PN = "C57"  !CDS_PN = "C57";
"VSS_C61":   PN = "C61"  !CDS_PN = "C61";
"VSS_C64":   PN = "C64"  !CDS_PN = "C64";
"VSS_C67":   PN = "C67"  !CDS_PN = "C67";
"VSS_C69":   PN = "C69"  !CDS_PN = "C69";
"VSS_C71":   PN = "C71"  !CDS_PN = "C71";
"VSS_C73":   PN = "C73"  !CDS_PN = "C73";
"VSS_C75":   PN = "C75"  !CDS_PN = "C75";
"VSS_D2":   PN = "D2"  !CDS_PN = "D2";
"VSS_D3":   PN = "D3"  !CDS_PN = "D3";
"VSS_D5":   PN = "D5"  !CDS_PN = "D5";
"VSS_D6":   PN = "D6"  !CDS_PN = "D6";
"VSS_D9":   PN = "D9"  !CDS_PN = "D9";
"VSS_D10":   PN = "D10"  !CDS_PN = "D10";
"VSS_D12":   PN = "D12"  !CDS_PN = "D12";
"VSS_D13":   PN = "D13"  !CDS_PN = "D13";
"VSS_D16":   PN = "D16"  !CDS_PN = "D16";
"VSS_D17":   PN = "D17"  !CDS_PN = "D17";
"VSS_D19":   PN = "D19"  !CDS_PN = "D19";
"VSS_D20":   PN = "D20"  !CDS_PN = "D20";
"VSS_D21":   PN = "D21"  !CDS_PN = "D21";
"VSS_D24":   PN = "D24"  !CDS_PN = "D24";
"VSS_D25":   PN = "D25"  !CDS_PN = "D25";
"VSS_D26":   PN = "D26"  !CDS_PN = "D26";
"VSS_D27":   PN = "D27"  !CDS_PN = "D27";
"VSS_D28":   PN = "D28"  !CDS_PN = "D28";
"VSS_D29":   PN = "D29"  !CDS_PN = "D29";
"VSS_D30":   PN = "D30"  !CDS_PN = "D30";
"VSS_D31":   PN = "D31"  !CDS_PN = "D31";
"VSS_D35":   PN = "D35"  !CDS_PN = "D35";
"VSS_D37":   PN = "D37"  !CDS_PN = "D37";
"VSS_D39":   PN = "D39"  !CDS_PN = "D39";
"VSS_D40":   PN = "D40"  !CDS_PN = "D40";
"VSS_D41":   PN = "D41"  !CDS_PN = "D41";
"VSS_D42":   PN = "D42"  !CDS_PN = "D42";
"VSS_D43":   PN = "D43"  !CDS_PN = "D43";
"VSS_D44":   PN = "D44"  !CDS_PN = "D44";
"VSS_D45":   PN = "D45"  !CDS_PN = "D45";
"VSS_D46":   PN = "D46"  !CDS_PN = "D46";
"VSS_D47":   PN = "D47"  !CDS_PN = "D47";
"VSS_D48":   PN = "D48"  !CDS_PN = "D48";
"VSS_D49":   PN = "D49"  !CDS_PN = "D49";
"VSS_D50":   PN = "D50"  !CDS_PN = "D50";
"VSS_D51":   PN = "D51"  !CDS_PN = "D51";
"VSS_D52":   PN = "D52"  !CDS_PN = "D52";
"VSS_D53":   PN = "D53"  !CDS_PN = "D53";
"VSS_D54":   PN = "D54"  !CDS_PN = "D54";
"VSS_D57":   PN = "D57"  !CDS_PN = "D57";
"VSS_D59":   PN = "D59"  !CDS_PN = "D59";
"VSS_D60":   PN = "D60"  !CDS_PN = "D60";
"VSS_D61":   PN = "D61"  !CDS_PN = "D61";
"VSS_D63":   PN = "D63"  !CDS_PN = "D63";
"VSS_D64":   PN = "D64"  !CDS_PN = "D64";
"VSS_D66":   PN = "D66"  !CDS_PN = "D66";
"VSS_D67":   PN = "D67"  !CDS_PN = "D67";
"VSS_D70":   PN = "D70"  !CDS_PN = "D70";
"VSS_D71":   PN = "D71"  !CDS_PN = "D71";
"VSS_D73":   PN = "D73"  !CDS_PN = "D73";
"VSS_D74":   PN = "D74"  !CDS_PN = "D74";
"VSS_E1":   PN = "E1"  !CDS_PN = "E1";
"VSS_E3":   PN = "E3"  !CDS_PN = "E3";
"VSS_E6":   PN = "E6"  !CDS_PN = "E6";
"VSS_E7":   PN = "E7"  !CDS_PN = "E7";
"VSS_E8":   PN = "E8"  !CDS_PN = "E8";
"VSS_E10":   PN = "E10"  !CDS_PN = "E10";
"VSS_E13":   PN = "E13"  !CDS_PN = "E13";
"VSS_E14":   PN = "E14"  !CDS_PN = "E14";
"VSS_E15":   PN = "E15"  !CDS_PN = "E15";
"VSS_E17":   PN = "E17"  !CDS_PN = "E17";
"VSS_E18":   PN = "E18"  !CDS_PN = "E18";
"VSS_E20":   PN = "E20"  !CDS_PN = "E20";
"VSS_E21":   PN = "E21"  !CDS_PN = "E21";
"VSS_E52":   PN = "E52"  !CDS_PN = "E52";
"VSS_E53":   PN = "E53"  !CDS_PN = "E53";
"VSS_E55":   PN = "E55"  !CDS_PN = "E55";
"VSS_E56":   PN = "E56"  !CDS_PN = "E56";
"VSS_E58":   PN = "E58"  !CDS_PN = "E58";
"VSS_E59":   PN = "E59"  !CDS_PN = "E59";
"VSS_E61":   PN = "E61"  !CDS_PN = "E61";
"VSS_E62":   PN = "E62"  !CDS_PN = "E62";
"VSS_E63":   PN = "E63"  !CDS_PN = "E63";
"VSS_E65":   PN = "E65"  !CDS_PN = "E65";
"VSS_E66":   PN = "E66"  !CDS_PN = "E66";
"VSS_E68":   PN = "E68"  !CDS_PN = "E68";
"VSS_E69":   PN = "E69"  !CDS_PN = "E69";
"VSS_E70":   PN = "E70"  !CDS_PN = "E70";
"VSS_E72":   PN = "E72"  !CDS_PN = "E72";
"VSS_E73":   PN = "E73"  !CDS_PN = "E73";
"VSS_E75":   PN = "E75"  !CDS_PN = "E75";
"VSS_F3":   PN = "F3"  !CDS_PN = "F3";
"VSS_F5":   PN = "F5"  !CDS_PN = "F5";
"VSS_F8":   PN = "F8"  !CDS_PN = "F8";
"VSS_F10":   PN = "F10"  !CDS_PN = "F10";
"VSS_F12":   PN = "F12"  !CDS_PN = "F12";
"VSS_F15":   PN = "F15"  !CDS_PN = "F15";
"VSS_F17":   PN = "F17"  !CDS_PN = "F17";
"VSS_F19":   PN = "F19"  !CDS_PN = "F19";
"VSS_F23":   PN = "F23"  !CDS_PN = "F23";
"VSS_F24":   PN = "F24"  !CDS_PN = "F24";
"VSS_F26":   PN = "F26"  !CDS_PN = "F26";
"VSS_F27":   PN = "F27"  !CDS_PN = "F27";
"VSS_F29":   PN = "F29"  !CDS_PN = "F29";
"VSS_F30":   PN = "F30"  !CDS_PN = "F30";
"VSS_F32":   PN = "F32"  !CDS_PN = "F32";
"VSS_F33":   PN = "F33"  !CDS_PN = "F33";
"VSS_F35":   PN = "F35"  !CDS_PN = "F35";
"VSS_F36":   PN = "F36"  !CDS_PN = "F36";
"VSS_F37":   PN = "F37"  !CDS_PN = "F37";
"VSS_F39":   PN = "F39"  !CDS_PN = "F39";
"VSS_F40":   PN = "F40"  !CDS_PN = "F40";
"VSS_F41":   PN = "F41"  !CDS_PN = "F41";
"VSS_F43":   PN = "F43"  !CDS_PN = "F43";
"VSS_F44":   PN = "F44"  !CDS_PN = "F44";
"VSS_F46":   PN = "F46"  !CDS_PN = "F46";
"VSS_F47":   PN = "F47"  !CDS_PN = "F47";
"VSS_F49":   PN = "F49"  !CDS_PN = "F49";
"VSS_F50":   PN = "F50"  !CDS_PN = "F50";
"VSS_F52":   PN = "F52"  !CDS_PN = "F52";
"VSS_F53":   PN = "F53"  !CDS_PN = "F53";
"VSS_F57":   PN = "F57"  !CDS_PN = "F57";
"VSS_F59":   PN = "F59"  !CDS_PN = "F59";
"VSS_F61":   PN = "F61"  !CDS_PN = "F61";
"VSS_F64":   PN = "F64"  !CDS_PN = "F64";
"VSS_F66":   PN = "F66"  !CDS_PN = "F66";
"VSS_F68":   PN = "F68"  !CDS_PN = "F68";
"VSS_F71":   PN = "F71"  !CDS_PN = "F71";
"VSS_F73":   PN = "F73"  !CDS_PN = "F73";
"VSS_G1":   PN = "G1"  !CDS_PN = "G1";
"VSS_G4":   PN = "G4"  !CDS_PN = "G4";
"VSS_G6":   PN = "G6"  !CDS_PN = "G6";
"VSS_G8":   PN = "G8"  !CDS_PN = "G8";
"VSS_G11":   PN = "G11"  !CDS_PN = "G11";
"VSS_G13":   PN = "G13"  !CDS_PN = "G13";
"VSS_G15":   PN = "G15"  !CDS_PN = "G15";
"VSS_G18":   PN = "G18"  !CDS_PN = "G18";
"VSS_G20":   PN = "G20"  !CDS_PN = "G20";
"VSS_G22":   PN = "G22"  !CDS_PN = "G22";
"VSS_G25":   PN = "G25"  !CDS_PN = "G25";
"VSS_G28":   PN = "G28"  !CDS_PN = "G28";
"VSS_G31":   PN = "G31"  !CDS_PN = "G31";
"VSS_G34":   PN = "G34"  !CDS_PN = "G34";
"VSS_G42":   PN = "G42"  !CDS_PN = "G42";
"VSS_G45":   PN = "G45"  !CDS_PN = "G45";
"VSS_G48":   PN = "G48"  !CDS_PN = "G48";
"VSS_G51":   PN = "G51"  !CDS_PN = "G51";
"VSS_G54":   PN = "G54"  !CDS_PN = "G54";
"VSS_G56":   PN = "G56"  !CDS_PN = "G56";
"VSS_G58":   PN = "G58"  !CDS_PN = "G58";
"VSS_G61":   PN = "G61"  !CDS_PN = "G61";
"VSS_G63":   PN = "G63"  !CDS_PN = "G63";
"VSS_G65":   PN = "G65"  !CDS_PN = "G65";
"VSS_G68":   PN = "G68"  !CDS_PN = "G68";
"VSS_G70":   PN = "G70"  !CDS_PN = "G70";
"VSS_G72":   PN = "G72"  !CDS_PN = "G72";
"VSS_G75":   PN = "G75"  !CDS_PN = "G75";
"VSS_H3":   PN = "H3"  !CDS_PN = "H3";
"VSS_H8":   PN = "H8"  !CDS_PN = "H8";
"VSS_H10":   PN = "H10"  !CDS_PN = "H10";
"VSS_H15":   PN = "H15"  !CDS_PN = "H15";
"VSS_H17":   PN = "H17"  !CDS_PN = "H17";
"VSS_H22":   PN = "H22"  !CDS_PN = "H22";
"VSS_H25":   PN = "H25"  !CDS_PN = "H25";
"VSS_H28":   PN = "H28"  !CDS_PN = "H28";
"VSS_H31":   PN = "H31"  !CDS_PN = "H31";
"VSS_H34":   PN = "H34"  !CDS_PN = "H34";
"VSS_H37":   PN = "H37"  !CDS_PN = "H37";
"VSS_H39":   PN = "H39"  !CDS_PN = "H39";
"VSS_H42":   PN = "H42"  !CDS_PN = "H42";
"VSS_H45":   PN = "H45"  !CDS_PN = "H45";
"VSS_H48":   PN = "H48"  !CDS_PN = "H48";
"VSS_H51":   PN = "H51"  !CDS_PN = "H51";
"VSS_H54":   PN = "H54"  !CDS_PN = "H54";
"VSS_H59":   PN = "H59"  !CDS_PN = "H59";
"VSS_H61":   PN = "H61"  !CDS_PN = "H61";
"VSS_H66":   PN = "H66"  !CDS_PN = "H66";
"VSS_H68":   PN = "H68"  !CDS_PN = "H68";
"VSS_H73":   PN = "H73"  !CDS_PN = "H73";
"VSS_J1":   PN = "J1"  !CDS_PN = "J1";
"VSS_J4":   PN = "J4"  !CDS_PN = "J4";
"VSS_J6":   PN = "J6"  !CDS_PN = "J6";
"VSS_J8":   PN = "J8"  !CDS_PN = "J8";
"VSS_J11":   PN = "J11"  !CDS_PN = "J11";
"VSS_J13":   PN = "J13"  !CDS_PN = "J13";
BODY = "GENOA_SP5","I20": #LOCATION = "U25" !CDS_LOCATION = "U25" &SEC = "29" #&CDS_SEC = "29";
"VSS_J15":   PN = "J15"  !CDS_PN = "J15";
"VSS_J18":   PN = "J18"  !CDS_PN = "J18";
"VSS_J20":   PN = "J20"  !CDS_PN = "J20";
"VSS_J22":   PN = "J22"  !CDS_PN = "J22";
"VSS_J25":   PN = "J25"  !CDS_PN = "J25";
"VSS_J28":   PN = "J28"  !CDS_PN = "J28";
"VSS_J31":   PN = "J31"  !CDS_PN = "J31";
"VSS_J34":   PN = "J34"  !CDS_PN = "J34";
"VSS_J42":   PN = "J42"  !CDS_PN = "J42";
"VSS_J45":   PN = "J45"  !CDS_PN = "J45";
"VSS_J48":   PN = "J48"  !CDS_PN = "J48";
"VSS_J51":   PN = "J51"  !CDS_PN = "J51";
"VSS_J54":   PN = "J54"  !CDS_PN = "J54";
"VSS_J56":   PN = "J56"  !CDS_PN = "J56";
"VSS_J58":   PN = "J58"  !CDS_PN = "J58";
"VSS_J61":   PN = "J61"  !CDS_PN = "J61";
"VSS_J63":   PN = "J63"  !CDS_PN = "J63";
"VSS_J65":   PN = "J65"  !CDS_PN = "J65";
"VSS_J68":   PN = "J68"  !CDS_PN = "J68";
"VSS_J70":   PN = "J70"  !CDS_PN = "J70";
"VSS_J72":   PN = "J72"  !CDS_PN = "J72";
"VSS_J75":   PN = "J75"  !CDS_PN = "J75";
"VSS_K3":   PN = "K3"  !CDS_PN = "K3";
"VSS_K5":   PN = "K5"  !CDS_PN = "K5";
"VSS_K8":   PN = "K8"  !CDS_PN = "K8";
"VSS_K10":   PN = "K10"  !CDS_PN = "K10";
"VSS_K12":   PN = "K12"  !CDS_PN = "K12";
"VSS_K15":   PN = "K15"  !CDS_PN = "K15";
"VSS_K17":   PN = "K17"  !CDS_PN = "K17";
"VSS_K19":   PN = "K19"  !CDS_PN = "K19";
"VSS_K24":   PN = "K24"  !CDS_PN = "K24";
"VSS_K25":   PN = "K25"  !CDS_PN = "K25";
"VSS_K26":   PN = "K26"  !CDS_PN = "K26";
"VSS_K27":   PN = "K27"  !CDS_PN = "K27";
"VSS_K28":   PN = "K28"  !CDS_PN = "K28";
"VSS_K29":   PN = "K29"  !CDS_PN = "K29";
"VSS_K30":   PN = "K30"  !CDS_PN = "K30";
"VSS_K31":   PN = "K31"  !CDS_PN = "K31";
"VSS_K32":   PN = "K32"  !CDS_PN = "K32";
"VSS_K33":   PN = "K33"  !CDS_PN = "K33";
"VSS_K34":   PN = "K34"  !CDS_PN = "K34";
"VSS_K37":   PN = "K37"  !CDS_PN = "K37";
"VSS_K39":   PN = "K39"  !CDS_PN = "K39";
"VSS_K42":   PN = "K42"  !CDS_PN = "K42";
"VSS_K43":   PN = "K43"  !CDS_PN = "K43";
"VSS_K44":   PN = "K44"  !CDS_PN = "K44";
"VSS_K45":   PN = "K45"  !CDS_PN = "K45";
"VSS_K46":   PN = "K46"  !CDS_PN = "K46";
"VSS_K47":   PN = "K47"  !CDS_PN = "K47";
"VSS_K48":   PN = "K48"  !CDS_PN = "K48";
"VSS_K49":   PN = "K49"  !CDS_PN = "K49";
"VSS_K50":   PN = "K50"  !CDS_PN = "K50";
"VSS_K51":   PN = "K51"  !CDS_PN = "K51";
"VSS_K52":   PN = "K52"  !CDS_PN = "K52";
"VSS_K53":   PN = "K53"  !CDS_PN = "K53";
"VSS_K57":   PN = "K57"  !CDS_PN = "K57";
"VSS_K61":   PN = "K61"  !CDS_PN = "K61";
"VSS_K64":   PN = "K64"  !CDS_PN = "K64";
"VSS_K66":   PN = "K66"  !CDS_PN = "K66";
"VSS_K68":   PN = "K68"  !CDS_PN = "K68";
"VSS_K71":   PN = "K71"  !CDS_PN = "K71";
"VSS_K73":   PN = "K73"  !CDS_PN = "K73";
"VSS_L1":   PN = "L1"  !CDS_PN = "L1";
"VSS_L6":   PN = "L6"  !CDS_PN = "L6";
"VSS_L8":   PN = "L8"  !CDS_PN = "L8";
"VSS_L13":   PN = "L13"  !CDS_PN = "L13";
"VSS_L15":   PN = "L15"  !CDS_PN = "L15";
"VSS_L20":   PN = "L20"  !CDS_PN = "L20";
"VSS_L22":   PN = "L22"  !CDS_PN = "L22";
"VSS_L25":   PN = "L25"  !CDS_PN = "L25";
"VSS_L28":   PN = "L28"  !CDS_PN = "L28";
"VSS_L31":   PN = "L31"  !CDS_PN = "L31";
"VSS_L34":   PN = "L34"  !CDS_PN = "L34";
"VSS_L35":   PN = "L35"  !CDS_PN = "L35";
"VSS_L36":   PN = "L36"  !CDS_PN = "L36";
"VSS_L40":   PN = "L40"  !CDS_PN = "L40";
"VSS_L41":   PN = "L41"  !CDS_PN = "L41";
"VSS_L42":   PN = "L42"  !CDS_PN = "L42";
"VSS_L45":   PN = "L45"  !CDS_PN = "L45";
"VSS_L48":   PN = "L48"  !CDS_PN = "L48";
"VSS_L51":   PN = "L51"  !CDS_PN = "L51";
"VSS_L54":   PN = "L54"  !CDS_PN = "L54";
"VSS_L56":   PN = "L56"  !CDS_PN = "L56";
"VSS_L61":   PN = "L61"  !CDS_PN = "L61";
"VSS_L63":   PN = "L63"  !CDS_PN = "L63";
"VSS_L68":   PN = "L68"  !CDS_PN = "L68";
"VSS_L70":   PN = "L70"  !CDS_PN = "L70";
"VSS_L75":   PN = "L75"  !CDS_PN = "L75";
"VSS_M3":   PN = "M3"  !CDS_PN = "M3";
"VSS_M5":   PN = "M5"  !CDS_PN = "M5";
"VSS_M8":   PN = "M8"  !CDS_PN = "M8";
"VSS_M10":   PN = "M10"  !CDS_PN = "M10";
"VSS_M12":   PN = "M12"  !CDS_PN = "M12";
"VSS_M15":   PN = "M15"  !CDS_PN = "M15";
"VSS_M17":   PN = "M17"  !CDS_PN = "M17";
"VSS_M19":   PN = "M19"  !CDS_PN = "M19";
"VSS_M22":   PN = "M22"  !CDS_PN = "M22";
"VSS_M25":   PN = "M25"  !CDS_PN = "M25";
"VSS_M28":   PN = "M28"  !CDS_PN = "M28";
"VSS_M31":   PN = "M31"  !CDS_PN = "M31";
"VSS_M34":   PN = "M34"  !CDS_PN = "M34";
"VSS_M37":   PN = "M37"  !CDS_PN = "M37";
"VSS_M39":   PN = "M39"  !CDS_PN = "M39";
"VSS_M42":   PN = "M42"  !CDS_PN = "M42";
"VSS_M45":   PN = "M45"  !CDS_PN = "M45";
"VSS_M48":   PN = "M48"  !CDS_PN = "M48";
"VSS_M51":   PN = "M51"  !CDS_PN = "M51";
"VSS_M54":   PN = "M54"  !CDS_PN = "M54";
"VSS_M57":   PN = "M57"  !CDS_PN = "M57";
"VSS_M59":   PN = "M59"  !CDS_PN = "M59";
"VSS_M61":   PN = "M61"  !CDS_PN = "M61";
"VSS_M64":   PN = "M64"  !CDS_PN = "M64";
"VSS_M66":   PN = "M66"  !CDS_PN = "M66";
"VSS_M68":   PN = "M68"  !CDS_PN = "M68";
"VSS_M71":   PN = "M71"  !CDS_PN = "M71";
"VSS_M73":   PN = "M73"  !CDS_PN = "M73";
"VSS_N1":   PN = "N1"  !CDS_PN = "N1";
"VSS_N4":   PN = "N4"  !CDS_PN = "N4";
"VSS_N6":   PN = "N6"  !CDS_PN = "N6";
"VSS_N8":   PN = "N8"  !CDS_PN = "N8";
"VSS_N11":   PN = "N11"  !CDS_PN = "N11";
"VSS_N13":   PN = "N13"  !CDS_PN = "N13";
"VSS_N15":   PN = "N15"  !CDS_PN = "N15";
"VSS_N18":   PN = "N18"  !CDS_PN = "N18";
"VSS_N20":   PN = "N20"  !CDS_PN = "N20";
"VSS_N22":   PN = "N22"  !CDS_PN = "N22";
"VSS_N25":   PN = "N25"  !CDS_PN = "N25";
"VSS_N28":   PN = "N28"  !CDS_PN = "N28";
"VSS_N31":   PN = "N31"  !CDS_PN = "N31";
"VSS_N34":   PN = "N34"  !CDS_PN = "N34";
"VSS_N42":   PN = "N42"  !CDS_PN = "N42";
"VSS_N45":   PN = "N45"  !CDS_PN = "N45";
"VSS_N48":   PN = "N48"  !CDS_PN = "N48";
"VSS_N51":   PN = "N51"  !CDS_PN = "N51";
"VSS_N54":   PN = "N54"  !CDS_PN = "N54";
"VSS_N56":   PN = "N56"  !CDS_PN = "N56";
"VSS_N58":   PN = "N58"  !CDS_PN = "N58";
"VSS_N61":   PN = "N61"  !CDS_PN = "N61";
"VSS_N63":   PN = "N63"  !CDS_PN = "N63";
"VSS_N65":   PN = "N65"  !CDS_PN = "N65";
"VSS_N68":   PN = "N68"  !CDS_PN = "N68";
"VSS_N70":   PN = "N70"  !CDS_PN = "N70";
"VSS_N72":   PN = "N72"  !CDS_PN = "N72";
"VSS_N75":   PN = "N75"  !CDS_PN = "N75";
"VSS_P3":   PN = "P3"  !CDS_PN = "P3";
"VSS_P8":   PN = "P8"  !CDS_PN = "P8";
"VSS_P10":   PN = "P10"  !CDS_PN = "P10";
"VSS_P15":   PN = "P15"  !CDS_PN = "P15";
"VSS_P17":   PN = "P17"  !CDS_PN = "P17";
"VSS_P23":   PN = "P23"  !CDS_PN = "P23";
"VSS_P24":   PN = "P24"  !CDS_PN = "P24";
"VSS_P26":   PN = "P26"  !CDS_PN = "P26";
"VSS_P27":   PN = "P27"  !CDS_PN = "P27";
"VSS_P28":   PN = "P28"  !CDS_PN = "P28";
"VSS_P29":   PN = "P29"  !CDS_PN = "P29";
"VSS_P30":   PN = "P30"  !CDS_PN = "P30";
"VSS_P31":   PN = "P31"  !CDS_PN = "P31";
"VSS_P32":   PN = "P32"  !CDS_PN = "P32";
"VSS_P33":   PN = "P33"  !CDS_PN = "P33";
"VSS_P34":   PN = "P34"  !CDS_PN = "P34";
"VSS_P37":   PN = "P37"  !CDS_PN = "P37";
"VSS_P39":   PN = "P39"  !CDS_PN = "P39";
"VSS_P42":   PN = "P42"  !CDS_PN = "P42";
"VSS_P43":   PN = "P43"  !CDS_PN = "P43";
"VSS_P44":   PN = "P44"  !CDS_PN = "P44";
"VSS_P45":   PN = "P45"  !CDS_PN = "P45";
"VSS_P46":   PN = "P46"  !CDS_PN = "P46";
"VSS_P47":   PN = "P47"  !CDS_PN = "P47";
"VSS_P48":   PN = "P48"  !CDS_PN = "P48";
"VSS_P49":   PN = "P49"  !CDS_PN = "P49";
"VSS_P50":   PN = "P50"  !CDS_PN = "P50";
"VSS_P51":   PN = "P51"  !CDS_PN = "P51";
"VSS_P52":   PN = "P52"  !CDS_PN = "P52";
"VSS_P53":   PN = "P53"  !CDS_PN = "P53";
"VSS_P59":   PN = "P59"  !CDS_PN = "P59";
"VSS_P61":   PN = "P61"  !CDS_PN = "P61";
"VSS_P66":   PN = "P66"  !CDS_PN = "P66";
"VSS_P73":   PN = "P73"  !CDS_PN = "P73";
"VSS_R1":   PN = "R1"  !CDS_PN = "R1";
"VSS_R4":   PN = "R4"  !CDS_PN = "R4";
"VSS_R6":   PN = "R6"  !CDS_PN = "R6";
"VSS_R8":   PN = "R8"  !CDS_PN = "R8";
"VSS_R11":   PN = "R11"  !CDS_PN = "R11";
"VSS_R13":   PN = "R13"  !CDS_PN = "R13";
"VSS_R15":   PN = "R15"  !CDS_PN = "R15";
"VSS_R18":   PN = "R18"  !CDS_PN = "R18";
"VSS_R20":   PN = "R20"  !CDS_PN = "R20";
"VSS_R22":   PN = "R22"  !CDS_PN = "R22";
"VSS_R25":   PN = "R25"  !CDS_PN = "R25";
"VSS_R28":   PN = "R28"  !CDS_PN = "R28";
"VSS_R31":   PN = "R31"  !CDS_PN = "R31";
"VSS_R34":   PN = "R34"  !CDS_PN = "R34";
"VSS_R35":   PN = "R35"  !CDS_PN = "R35";
"VSS_R36":   PN = "R36"  !CDS_PN = "R36";
"VSS_R40":   PN = "R40"  !CDS_PN = "R40";
"VSS_R41":   PN = "R41"  !CDS_PN = "R41";
"VSS_R42":   PN = "R42"  !CDS_PN = "R42";
"VSS_R45":   PN = "R45"  !CDS_PN = "R45";
"VSS_R48":   PN = "R48"  !CDS_PN = "R48";
"VSS_R51":   PN = "R51"  !CDS_PN = "R51";
"VSS_R54":   PN = "R54"  !CDS_PN = "R54";
"VSS_R56":   PN = "R56"  !CDS_PN = "R56";
"VSS_R58":   PN = "R58"  !CDS_PN = "R58";
"VSS_R61":   PN = "R61"  !CDS_PN = "R61";
"VSS_R63":   PN = "R63"  !CDS_PN = "R63";
"VSS_R65":   PN = "R65"  !CDS_PN = "R65";
"VSS_R68":   PN = "R68"  !CDS_PN = "R68";
"VSS_R70":   PN = "R70"  !CDS_PN = "R70";
"VSS_R72":   PN = "R72"  !CDS_PN = "R72";
"VSS_R75":   PN = "R75"  !CDS_PN = "R75";
"VSS_T3":   PN = "T3"  !CDS_PN = "T3";
"VSS_T5":   PN = "T5"  !CDS_PN = "T5";
"VSS_T8":   PN = "T8"  !CDS_PN = "T8";
"VSS_T10":   PN = "T10"  !CDS_PN = "T10";
"VSS_T12":   PN = "T12"  !CDS_PN = "T12";
"VSS_T15":   PN = "T15"  !CDS_PN = "T15";
"VSS_T17":   PN = "T17"  !CDS_PN = "T17";
"VSS_T19":   PN = "T19"  !CDS_PN = "T19";
"VSS_T22":   PN = "T22"  !CDS_PN = "T22";
"VSS_T25":   PN = "T25"  !CDS_PN = "T25";
"VSS_T28":   PN = "T28"  !CDS_PN = "T28";
"VSS_T31":   PN = "T31"  !CDS_PN = "T31";
"VSS_T34":   PN = "T34"  !CDS_PN = "T34";
"VSS_T37":   PN = "T37"  !CDS_PN = "T37";
"VSS_T39":   PN = "T39"  !CDS_PN = "T39";
"VSS_T42":   PN = "T42"  !CDS_PN = "T42";
"VSS_T45":   PN = "T45"  !CDS_PN = "T45";
"VSS_T48":   PN = "T48"  !CDS_PN = "T48";
"VSS_T51":   PN = "T51"  !CDS_PN = "T51";
"VSS_T54":   PN = "T54"  !CDS_PN = "T54";
"VSS_T57":   PN = "T57"  !CDS_PN = "T57";
"VSS_T59":   PN = "T59"  !CDS_PN = "T59";
"VSS_T61":   PN = "T61"  !CDS_PN = "T61";
"VSS_T64":   PN = "T64"  !CDS_PN = "T64";
BODY = "GENOA_SP5","I21": #LOCATION = "U25" !CDS_LOCATION = "U25" &SEC = "30" #&CDS_SEC = "30";
"VSS_AA1":   PN = "AA1"  !CDS_PN = "AA1";
"VSS_AA4":   PN = "AA4"  !CDS_PN = "AA4";
"VSS_AA6":   PN = "AA6"  !CDS_PN = "AA6";
"VSS_AA8":   PN = "AA8"  !CDS_PN = "AA8";
"VSS_AA11":   PN = "AA11"  !CDS_PN = "AA11";
"VSS_AA13":   PN = "AA13"  !CDS_PN = "AA13";
"VSS_AA15":   PN = "AA15"  !CDS_PN = "AA15";
"VSS_AA18":   PN = "AA18"  !CDS_PN = "AA18";
"VSS_AA20":   PN = "AA20"  !CDS_PN = "AA20";
"VSS_AA31":   PN = "AA31"  !CDS_PN = "AA31";
"VSS_AA34":   PN = "AA34"  !CDS_PN = "AA34";
"VSS_AA35":   PN = "AA35"  !CDS_PN = "AA35";
"VSS_AA36":   PN = "AA36"  !CDS_PN = "AA36";
"VSS_AA40":   PN = "AA40"  !CDS_PN = "AA40";
"VSS_AA41":   PN = "AA41"  !CDS_PN = "AA41";
"VSS_AA45":   PN = "AA45"  !CDS_PN = "AA45";
"VSS_AA56":   PN = "AA56"  !CDS_PN = "AA56";
"VSS_AA58":   PN = "AA58"  !CDS_PN = "AA58";
"VSS_AA61":   PN = "AA61"  !CDS_PN = "AA61";
"VSS_AA63":   PN = "AA63"  !CDS_PN = "AA63";
"VSS_AA65":   PN = "AA65"  !CDS_PN = "AA65";
"VSS_AA68":   PN = "AA68"  !CDS_PN = "AA68";
"VSS_AA70":   PN = "AA70"  !CDS_PN = "AA70";
"VSS_AA75":   PN = "AA75"  !CDS_PN = "AA75";
"VSS_AB3":   PN = "AB3"  !CDS_PN = "AB3";
"VSS_AB5":   PN = "AB5"  !CDS_PN = "AB5";
"VSS_AB8":   PN = "AB8"  !CDS_PN = "AB8";
"VSS_AB10":   PN = "AB10"  !CDS_PN = "AB10";
"VSS_AB12":   PN = "AB12"  !CDS_PN = "AB12";
"VSS_AB15":   PN = "AB15"  !CDS_PN = "AB15";
"VSS_AB17":   PN = "AB17"  !CDS_PN = "AB17";
"VSS_AB19":   PN = "AB19"  !CDS_PN = "AB19";
"VSS_AB22":   PN = "AB22"  !CDS_PN = "AB22";
"VSS_AB25":   PN = "AB25"  !CDS_PN = "AB25";
"VSS_AB28":   PN = "AB28"  !CDS_PN = "AB28";
"VSS_AB31":   PN = "AB31"  !CDS_PN = "AB31";
"VSS_AB34":   PN = "AB34"  !CDS_PN = "AB34";
"VSS_AB37":   PN = "AB37"  !CDS_PN = "AB37";
"VSS_AB39":   PN = "AB39"  !CDS_PN = "AB39";
"VSS_AB42":   PN = "AB42"  !CDS_PN = "AB42";
"VSS_AB45":   PN = "AB45"  !CDS_PN = "AB45";
"VSS_AB48":   PN = "AB48"  !CDS_PN = "AB48";
"VSS_AB51":   PN = "AB51"  !CDS_PN = "AB51";
"VSS_AB54":   PN = "AB54"  !CDS_PN = "AB54";
"VSS_AB57":   PN = "AB57"  !CDS_PN = "AB57";
"VSS_AB59":   PN = "AB59"  !CDS_PN = "AB59";
"VSS_AB61":   PN = "AB61"  !CDS_PN = "AB61";
"VSS_AB64":   PN = "AB64"  !CDS_PN = "AB64";
"VSS_AB66":   PN = "AB66"  !CDS_PN = "AB66";
"VSS_AB68":   PN = "AB68"  !CDS_PN = "AB68";
"VSS_AB71":   PN = "AB71"  !CDS_PN = "AB71";
"VSS_AB73":   PN = "AB73"  !CDS_PN = "AB73";
"VSS_AC1":   PN = "AC1"  !CDS_PN = "AC1";
"VSS_AC6":   PN = "AC6"  !CDS_PN = "AC6";
"VSS_AC8":   PN = "AC8"  !CDS_PN = "AC8";
"VSS_AC13":   PN = "AC13"  !CDS_PN = "AC13";
"VSS_AC15":   PN = "AC15"  !CDS_PN = "AC15";
"VSS_AC20":   PN = "AC20"  !CDS_PN = "AC20";
"VSS_AC22":   PN = "AC22"  !CDS_PN = "AC22";
"VSS_AC25":   PN = "AC25"  !CDS_PN = "AC25";
"VSS_AC28":   PN = "AC28"  !CDS_PN = "AC28";
"VSS_AC31":   PN = "AC31"  !CDS_PN = "AC31";
"VSS_AC34":   PN = "AC34"  !CDS_PN = "AC34";
"VSS_AC42":   PN = "AC42"  !CDS_PN = "AC42";
"VSS_AC45":   PN = "AC45"  !CDS_PN = "AC45";
"VSS_AC48":   PN = "AC48"  !CDS_PN = "AC48";
"VSS_AC51":   PN = "AC51"  !CDS_PN = "AC51";
"VSS_AC54":   PN = "AC54"  !CDS_PN = "AC54";
"VSS_AC56":   PN = "AC56"  !CDS_PN = "AC56";
"VSS_AC61":   PN = "AC61"  !CDS_PN = "AC61";
"VSS_AC63":   PN = "AC63"  !CDS_PN = "AC63";
"VSS_AC68":   PN = "AC68"  !CDS_PN = "AC68";
"VSS_AC70":   PN = "AC70"  !CDS_PN = "AC70";
"VSS_AC75":   PN = "AC75"  !CDS_PN = "AC75";
"VSS_AD3":   PN = "AD3"  !CDS_PN = "AD3";
"VSS_AD5":   PN = "AD5"  !CDS_PN = "AD5";
"VSS_AD8":   PN = "AD8"  !CDS_PN = "AD8";
"VSS_AD10":   PN = "AD10"  !CDS_PN = "AD10";
"VSS_AD12":   PN = "AD12"  !CDS_PN = "AD12";
"VSS_AD15":   PN = "AD15"  !CDS_PN = "AD15";
"VSS_AD17":   PN = "AD17"  !CDS_PN = "AD17";
"VSS_AD19":   PN = "AD19"  !CDS_PN = "AD19";
"VSS_AD23":   PN = "AD23"  !CDS_PN = "AD23";
"VSS_AD24":   PN = "AD24"  !CDS_PN = "AD24";
"VSS_AD25":   PN = "AD25"  !CDS_PN = "AD25";
"VSS_AD26":   PN = "AD26"  !CDS_PN = "AD26";
"VSS_AD27":   PN = "AD27"  !CDS_PN = "AD27";
"VSS_AD28":   PN = "AD28"  !CDS_PN = "AD28";
"VSS_AD29":   PN = "AD29"  !CDS_PN = "AD29";
"VSS_AD30":   PN = "AD30"  !CDS_PN = "AD30";
"VSS_AD32":   PN = "AD32"  !CDS_PN = "AD32";
"VSS_AD33":   PN = "AD33"  !CDS_PN = "AD33";
"VSS_AD34":   PN = "AD34"  !CDS_PN = "AD34";
"VSS_AD37":   PN = "AD37"  !CDS_PN = "AD37";
"VSS_AD39":   PN = "AD39"  !CDS_PN = "AD39";
"VSS_AD42":   PN = "AD42"  !CDS_PN = "AD42";
"VSS_AD43":   PN = "AD43"  !CDS_PN = "AD43";
"VSS_AD44":   PN = "AD44"  !CDS_PN = "AD44";
"VSS_AD45":   PN = "AD45"  !CDS_PN = "AD45";
"VSS_AD46":   PN = "AD46"  !CDS_PN = "AD46";
"VSS_AD47":   PN = "AD47"  !CDS_PN = "AD47";
"VSS_AD48":   PN = "AD48"  !CDS_PN = "AD48";
"VSS_T66":   PN = "T66"  !CDS_PN = "T66";
"VSS_T68":   PN = "T68"  !CDS_PN = "T68";
"VSS_T71":   PN = "T71"  !CDS_PN = "T71";
"VSS_T73":   PN = "T73"  !CDS_PN = "T73";
"VSS_U1":   PN = "U1"  !CDS_PN = "U1";
"VSS_U6":   PN = "U6"  !CDS_PN = "U6";
"VSS_U8":   PN = "U8"  !CDS_PN = "U8";
"VSS_U13":   PN = "U13"  !CDS_PN = "U13";
"VSS_U15":   PN = "U15"  !CDS_PN = "U15";
"VSS_U20":   PN = "U20"  !CDS_PN = "U20";
"VSS_U22":   PN = "U22"  !CDS_PN = "U22";
"VSS_U25":   PN = "U25"  !CDS_PN = "U25";
"VSS_U28":   PN = "U28"  !CDS_PN = "U28";
"VSS_U31":   PN = "U31"  !CDS_PN = "U31";
"VSS_U34":   PN = "U34"  !CDS_PN = "U34";
"VSS_U42":   PN = "U42"  !CDS_PN = "U42";
"VSS_U45":   PN = "U45"  !CDS_PN = "U45";
"VSS_U48":   PN = "U48"  !CDS_PN = "U48";
"VSS_U51":   PN = "U51"  !CDS_PN = "U51";
"VSS_U54":   PN = "U54"  !CDS_PN = "U54";
"VSS_U56":   PN = "U56"  !CDS_PN = "U56";
"VSS_U61":   PN = "U61"  !CDS_PN = "U61";
"VSS_U63":   PN = "U63"  !CDS_PN = "U63";
"VSS_U68":   PN = "U68"  !CDS_PN = "U68";
"VSS_U70":   PN = "U70"  !CDS_PN = "U70";
"VSS_U75":   PN = "U75"  !CDS_PN = "U75";
"VSS_V3":   PN = "V3"  !CDS_PN = "V3";
"VSS_V5":   PN = "V5"  !CDS_PN = "V5";
"VSS_V8":   PN = "V8"  !CDS_PN = "V8";
"VSS_V10":   PN = "V10"  !CDS_PN = "V10";
"VSS_V12":   PN = "V12"  !CDS_PN = "V12";
"VSS_V15":   PN = "V15"  !CDS_PN = "V15";
"VSS_V17":   PN = "V17"  !CDS_PN = "V17";
"VSS_V19":   PN = "V19"  !CDS_PN = "V19";
"VSS_V23":   PN = "V23"  !CDS_PN = "V23";
"VSS_V24":   PN = "V24"  !CDS_PN = "V24";
"VSS_V25":   PN = "V25"  !CDS_PN = "V25";
"VSS_V26":   PN = "V26"  !CDS_PN = "V26";
"VSS_V28":   PN = "V28"  !CDS_PN = "V28";
"VSS_V29":   PN = "V29"  !CDS_PN = "V29";
"VSS_V30":   PN = "V30"  !CDS_PN = "V30";
"VSS_V31":   PN = "V31"  !CDS_PN = "V31";
"VSS_V32":   PN = "V32"  !CDS_PN = "V32";
"VSS_V33":   PN = "V33"  !CDS_PN = "V33";
"VSS_V34":   PN = "V34"  !CDS_PN = "V34";
"VSS_V37":   PN = "V37"  !CDS_PN = "V37";
"VSS_V39":   PN = "V39"  !CDS_PN = "V39";
"VSS_V42":   PN = "V42"  !CDS_PN = "V42";
"VSS_V43":   PN = "V43"  !CDS_PN = "V43";
"VSS_V44":   PN = "V44"  !CDS_PN = "V44";
"VSS_V45":   PN = "V45"  !CDS_PN = "V45";
"VSS_V46":   PN = "V46"  !CDS_PN = "V46";
"VSS_V47":   PN = "V47"  !CDS_PN = "V47";
"VSS_V48":   PN = "V48"  !CDS_PN = "V48";
"VSS_V49":   PN = "V49"  !CDS_PN = "V49";
"VSS_V50":   PN = "V50"  !CDS_PN = "V50";
"VSS_V51":   PN = "V51"  !CDS_PN = "V51";
"VSS_V52":   PN = "V52"  !CDS_PN = "V52";
"VSS_V53":   PN = "V53"  !CDS_PN = "V53";
"VSS_V57":   PN = "V57"  !CDS_PN = "V57";
"VSS_V59":   PN = "V59"  !CDS_PN = "V59";
"VSS_V61":   PN = "V61"  !CDS_PN = "V61";
"VSS_V64":   PN = "V64"  !CDS_PN = "V64";
"VSS_V66":   PN = "V66"  !CDS_PN = "V66";
"VSS_V71":   PN = "V71"  !CDS_PN = "V71";
"VSS_V73":   PN = "V73"  !CDS_PN = "V73";
"VSS_W1":   PN = "W1"  !CDS_PN = "W1";
"VSS_W4":   PN = "W4"  !CDS_PN = "W4";
"VSS_W6":   PN = "W6"  !CDS_PN = "W6";
"VSS_W8":   PN = "W8"  !CDS_PN = "W8";
"VSS_W11":   PN = "W11"  !CDS_PN = "W11";
"VSS_W13":   PN = "W13"  !CDS_PN = "W13";
"VSS_W15":   PN = "W15"  !CDS_PN = "W15";
"VSS_W18":   PN = "W18"  !CDS_PN = "W18";
"VSS_W20":   PN = "W20"  !CDS_PN = "W20";
"VSS_W22":   PN = "W22"  !CDS_PN = "W22";
"VSS_W25":   PN = "W25"  !CDS_PN = "W25";
"VSS_W28":   PN = "W28"  !CDS_PN = "W28";
"VSS_W34":   PN = "W34"  !CDS_PN = "W34";
"VSS_W35":   PN = "W35"  !CDS_PN = "W35";
"VSS_W36":   PN = "W36"  !CDS_PN = "W36";
"VSS_W40":   PN = "W40"  !CDS_PN = "W40";
"VSS_W41":   PN = "W41"  !CDS_PN = "W41";
"VSS_W42":   PN = "W42"  !CDS_PN = "W42";
"VSS_W45":   PN = "W45"  !CDS_PN = "W45";
"VSS_W48":   PN = "W48"  !CDS_PN = "W48";
"VSS_W51":   PN = "W51"  !CDS_PN = "W51";
"VSS_W54":   PN = "W54"  !CDS_PN = "W54";
"VSS_W56":   PN = "W56"  !CDS_PN = "W56";
"VSS_W58":   PN = "W58"  !CDS_PN = "W58";
"VSS_W61":   PN = "W61"  !CDS_PN = "W61";
"VSS_W63":   PN = "W63"  !CDS_PN = "W63";
"VSS_W65":   PN = "W65"  !CDS_PN = "W65";
"VSS_W68":   PN = "W68"  !CDS_PN = "W68";
"VSS_W70":   PN = "W70"  !CDS_PN = "W70";
"VSS_W72":   PN = "W72"  !CDS_PN = "W72";
"VSS_W75":   PN = "W75"  !CDS_PN = "W75";
"VSS_Y3":   PN = "Y3"  !CDS_PN = "Y3";
"VSS_Y8":   PN = "Y8"  !CDS_PN = "Y8";
"VSS_Y10":   PN = "Y10"  !CDS_PN = "Y10";
"VSS_Y15":   PN = "Y15"  !CDS_PN = "Y15";
"VSS_Y17":   PN = "Y17"  !CDS_PN = "Y17";
"VSS_Y22":   PN = "Y22"  !CDS_PN = "Y22";
"VSS_Y23":   PN = "Y23"  !CDS_PN = "Y23";
"VSS_Y24":   PN = "Y24"  !CDS_PN = "Y24";
"VSS_Y25":   PN = "Y25"  !CDS_PN = "Y25";
"VSS_Y26":   PN = "Y26"  !CDS_PN = "Y26";
"VSS_Y27":   PN = "Y27"  !CDS_PN = "Y27";
"VSS_Y28":   PN = "Y28"  !CDS_PN = "Y28";
"VSS_Y31":   PN = "Y31"  !CDS_PN = "Y31";
"VSS_Y32":   PN = "Y32"  !CDS_PN = "Y32";
"VSS_Y33":   PN = "Y33"  !CDS_PN = "Y33";
"VSS_Y34":   PN = "Y34"  !CDS_PN = "Y34";
"VSS_Y37":   PN = "Y37"  !CDS_PN = "Y37";
"VSS_Y39":   PN = "Y39"  !CDS_PN = "Y39";
"VSS_Y42":   PN = "Y42"  !CDS_PN = "Y42";
"VSS_Y43":   PN = "Y43"  !CDS_PN = "Y43";
"VSS_Y44":   PN = "Y44"  !CDS_PN = "Y44";
"VSS_Y45":   PN = "Y45"  !CDS_PN = "Y45";
"VSS_Y48":   PN = "Y48"  !CDS_PN = "Y48";
"VSS_Y49":   PN = "Y49"  !CDS_PN = "Y49";
"VSS_Y50":   PN = "Y50"  !CDS_PN = "Y50";
"VSS_Y51":   PN = "Y51"  !CDS_PN = "Y51";
"VSS_Y52":   PN = "Y52"  !CDS_PN = "Y52";
"VSS_Y53":   PN = "Y53"  !CDS_PN = "Y53";
"VSS_Y54":   PN = "Y54"  !CDS_PN = "Y54";
"VSS_Y59":   PN = "Y59"  !CDS_PN = "Y59";
"VSS_Y61":   PN = "Y61"  !CDS_PN = "Y61";
"VSS_Y66":   PN = "Y66"  !CDS_PN = "Y66";
"VSS_Y68":   PN = "Y68"  !CDS_PN = "Y68";
"VSS_Y73":   PN = "Y73"  !CDS_PN = "Y73";
BODY = "GENOA_SP5","I22": #LOCATION = "U25" !CDS_LOCATION = "U25" &SEC = "31" #&CDS_SEC = "31";
"VSS_AD49":   PN = "AD49"  !CDS_PN = "AD49";
"VSS_AD50":   PN = "AD50"  !CDS_PN = "AD50";
"VSS_AD51":   PN = "AD51"  !CDS_PN = "AD51";
"VSS_AD52":   PN = "AD52"  !CDS_PN = "AD52";
"VSS_AD53":   PN = "AD53"  !CDS_PN = "AD53";
"VSS_AD57":   PN = "AD57"  !CDS_PN = "AD57";
"VSS_AD59":   PN = "AD59"  !CDS_PN = "AD59";
"VSS_AD61":   PN = "AD61"  !CDS_PN = "AD61";
"VSS_AD64":   PN = "AD64"  !CDS_PN = "AD64";
"VSS_AD66":   PN = "AD66"  !CDS_PN = "AD66";
"VSS_AD68":   PN = "AD68"  !CDS_PN = "AD68";
"VSS_AD71":   PN = "AD71"  !CDS_PN = "AD71";
"VSS_AD73":   PN = "AD73"  !CDS_PN = "AD73";
"VSS_AE1":   PN = "AE1"  !CDS_PN = "AE1";
"VSS_AE6":   PN = "AE6"  !CDS_PN = "AE6";
"VSS_AE8":   PN = "AE8"  !CDS_PN = "AE8";
"VSS_AE11":   PN = "AE11"  !CDS_PN = "AE11";
"VSS_AE13":   PN = "AE13"  !CDS_PN = "AE13";
"VSS_AE15":   PN = "AE15"  !CDS_PN = "AE15";
"VSS_AE18":   PN = "AE18"  !CDS_PN = "AE18";
"VSS_AE20":   PN = "AE20"  !CDS_PN = "AE20";
"VSS_AE22":   PN = "AE22"  !CDS_PN = "AE22";
"VSS_AE25":   PN = "AE25"  !CDS_PN = "AE25";
"VSS_AE28":   PN = "AE28"  !CDS_PN = "AE28";
"VSS_AE31":   PN = "AE31"  !CDS_PN = "AE31";
"VSS_AE34":   PN = "AE34"  !CDS_PN = "AE34";
"VSS_AE35":   PN = "AE35"  !CDS_PN = "AE35";
"VSS_AE36":   PN = "AE36"  !CDS_PN = "AE36";
"VSS_AE40":   PN = "AE40"  !CDS_PN = "AE40";
"VSS_AE41":   PN = "AE41"  !CDS_PN = "AE41";
"VSS_AE42":   PN = "AE42"  !CDS_PN = "AE42";
"VSS_AE45":   PN = "AE45"  !CDS_PN = "AE45";
"VSS_AE48":   PN = "AE48"  !CDS_PN = "AE48";
"VSS_AE51":   PN = "AE51"  !CDS_PN = "AE51";
"VSS_AE54":   PN = "AE54"  !CDS_PN = "AE54";
"VSS_AE56":   PN = "AE56"  !CDS_PN = "AE56";
"VSS_AE58":   PN = "AE58"  !CDS_PN = "AE58";
"VSS_AE61":   PN = "AE61"  !CDS_PN = "AE61";
"VSS_AE63":   PN = "AE63"  !CDS_PN = "AE63";
"VSS_AE65":   PN = "AE65"  !CDS_PN = "AE65";
"VSS_AE68":   PN = "AE68"  !CDS_PN = "AE68";
"VSS_AE70":   PN = "AE70"  !CDS_PN = "AE70";
"VSS_AE72":   PN = "AE72"  !CDS_PN = "AE72";
"VSS_AE75":   PN = "AE75"  !CDS_PN = "AE75";
"VSS_AF3":   PN = "AF3"  !CDS_PN = "AF3";
"VSS_AF8":   PN = "AF8"  !CDS_PN = "AF8";
"VSS_AF10":   PN = "AF10"  !CDS_PN = "AF10";
"VSS_AF15":   PN = "AF15"  !CDS_PN = "AF15";
"VSS_AF17":   PN = "AF17"  !CDS_PN = "AF17";
"VSS_AF22":   PN = "AF22"  !CDS_PN = "AF22";
"VSS_AF25":   PN = "AF25"  !CDS_PN = "AF25";
"VSS_AF28":   PN = "AF28"  !CDS_PN = "AF28";
"VSS_AF31":   PN = "AF31"  !CDS_PN = "AF31";
"VSS_AF34":   PN = "AF34"  !CDS_PN = "AF34";
"VSS_AF37":   PN = "AF37"  !CDS_PN = "AF37";
"VSS_AF39":   PN = "AF39"  !CDS_PN = "AF39";
"VSS_AF42":   PN = "AF42"  !CDS_PN = "AF42";
"VSS_AF45":   PN = "AF45"  !CDS_PN = "AF45";
"VSS_AF48":   PN = "AF48"  !CDS_PN = "AF48";
"VSS_AF51":   PN = "AF51"  !CDS_PN = "AF51";
"VSS_AF54":   PN = "AF54"  !CDS_PN = "AF54";
"VSS_AF59":   PN = "AF59"  !CDS_PN = "AF59";
"VSS_AF61":   PN = "AF61"  !CDS_PN = "AF61";
"VSS_AF66":   PN = "AF66"  !CDS_PN = "AF66";
"VSS_AF68":   PN = "AF68"  !CDS_PN = "AF68";
"VSS_AF73":   PN = "AF73"  !CDS_PN = "AF73";
"VSS_AG1":   PN = "AG1"  !CDS_PN = "AG1";
"VSS_AG4":   PN = "AG4"  !CDS_PN = "AG4";
"VSS_AG6":   PN = "AG6"  !CDS_PN = "AG6";
"VSS_AG8":   PN = "AG8"  !CDS_PN = "AG8";
"VSS_AG11":   PN = "AG11"  !CDS_PN = "AG11";
"VSS_AG13":   PN = "AG13"  !CDS_PN = "AG13";
"VSS_AG15":   PN = "AG15"  !CDS_PN = "AG15";
"VSS_AG18":   PN = "AG18"  !CDS_PN = "AG18";
"VSS_AG20":   PN = "AG20"  !CDS_PN = "AG20";
"VSS_AG22":   PN = "AG22"  !CDS_PN = "AG22";
"VSS_AG25":   PN = "AG25"  !CDS_PN = "AG25";
"VSS_AG28":   PN = "AG28"  !CDS_PN = "AG28";
"VSS_AG31":   PN = "AG31"  !CDS_PN = "AG31";
"VSS_AG34":   PN = "AG34"  !CDS_PN = "AG34";
"VSS_AG42":   PN = "AG42"  !CDS_PN = "AG42";
"VSS_AG45":   PN = "AG45"  !CDS_PN = "AG45";
"VSS_AG48":   PN = "AG48"  !CDS_PN = "AG48";
"VSS_AG51":   PN = "AG51"  !CDS_PN = "AG51";
"VSS_AG54":   PN = "AG54"  !CDS_PN = "AG54";
"VSS_AG56":   PN = "AG56"  !CDS_PN = "AG56";
"VSS_AG58":   PN = "AG58"  !CDS_PN = "AG58";
"VSS_AG61":   PN = "AG61"  !CDS_PN = "AG61";
"VSS_AG63":   PN = "AG63"  !CDS_PN = "AG63";
"VSS_AG65":   PN = "AG65"  !CDS_PN = "AG65";
"VSS_AG68":   PN = "AG68"  !CDS_PN = "AG68";
"VSS_AG70":   PN = "AG70"  !CDS_PN = "AG70";
"VSS_AG72":   PN = "AG72"  !CDS_PN = "AG72";
"VSS_AG75":   PN = "AG75"  !CDS_PN = "AG75";
"VSS_AH3":   PN = "AH3"  !CDS_PN = "AH3";
"VSS_AH5":   PN = "AH5"  !CDS_PN = "AH5";
"VSS_AH8":   PN = "AH8"  !CDS_PN = "AH8";
"VSS_AH10":   PN = "AH10"  !CDS_PN = "AH10";
"VSS_AH12":   PN = "AH12"  !CDS_PN = "AH12";
"VSS_AH15":   PN = "AH15"  !CDS_PN = "AH15";
"VSS_AH17":   PN = "AH17"  !CDS_PN = "AH17";
"VSS_AH19":   PN = "AH19"  !CDS_PN = "AH19";
"VSS_AH23":   PN = "AH23"  !CDS_PN = "AH23";
"VSS_AH24":   PN = "AH24"  !CDS_PN = "AH24";
"VSS_AH25":   PN = "AH25"  !CDS_PN = "AH25";
"VSS_AH26":   PN = "AH26"  !CDS_PN = "AH26";
"VSS_AH27":   PN = "AH27"  !CDS_PN = "AH27";
"VSS_AH28":   PN = "AH28"  !CDS_PN = "AH28";
"VSS_AH29":   PN = "AH29"  !CDS_PN = "AH29";
"VSS_AH30":   PN = "AH30"  !CDS_PN = "AH30";
"VSS_AH31":   PN = "AH31"  !CDS_PN = "AH31";
"VSS_AH32":   PN = "AH32"  !CDS_PN = "AH32";
"VSS_AH34":   PN = "AH34"  !CDS_PN = "AH34";
"VSS_AH37":   PN = "AH37"  !CDS_PN = "AH37";
"VSS_AH39":   PN = "AH39"  !CDS_PN = "AH39";
"VSS_AH42":   PN = "AH42"  !CDS_PN = "AH42";
"VSS_AH43":   PN = "AH43"  !CDS_PN = "AH43";
"VSS_AH44":   PN = "AH44"  !CDS_PN = "AH44";
"VSS_AH45":   PN = "AH45"  !CDS_PN = "AH45";
"VSS_AH46":   PN = "AH46"  !CDS_PN = "AH46";
"VSS_AH47":   PN = "AH47"  !CDS_PN = "AH47";
"VSS_AH48":   PN = "AH48"  !CDS_PN = "AH48";
"VSS_AH49":   PN = "AH49"  !CDS_PN = "AH49";
"VSS_AH50":   PN = "AH50"  !CDS_PN = "AH50";
"VSS_AH51":   PN = "AH51"  !CDS_PN = "AH51";
"VSS_AH52":   PN = "AH52"  !CDS_PN = "AH52";
"VSS_AH53":   PN = "AH53"  !CDS_PN = "AH53";
"VSS_AH57":   PN = "AH57"  !CDS_PN = "AH57";
"VSS_AH59":   PN = "AH59"  !CDS_PN = "AH59";
"VSS_AH61":   PN = "AH61"  !CDS_PN = "AH61";
"VSS_AH64":   PN = "AH64"  !CDS_PN = "AH64";
"VSS_AH66":   PN = "AH66"  !CDS_PN = "AH66";
"VSS_AH68":   PN = "AH68"  !CDS_PN = "AH68";
"VSS_AH71":   PN = "AH71"  !CDS_PN = "AH71";
"VSS_AH73":   PN = "AH73"  !CDS_PN = "AH73";
"VSS_AJ1":   PN = "AJ1"  !CDS_PN = "AJ1";
"VSS_AJ6":   PN = "AJ6"  !CDS_PN = "AJ6";
"VSS_AJ8":   PN = "AJ8"  !CDS_PN = "AJ8";
"VSS_AJ15":   PN = "AJ15"  !CDS_PN = "AJ15";
"VSS_AJ20":   PN = "AJ20"  !CDS_PN = "AJ20";
"VSS_AJ22":   PN = "AJ22"  !CDS_PN = "AJ22";
"VSS_AJ25":   PN = "AJ25"  !CDS_PN = "AJ25";
"VSS_AJ28":   PN = "AJ28"  !CDS_PN = "AJ28";
"VSS_AJ31":   PN = "AJ31"  !CDS_PN = "AJ31";
"VSS_AJ34":   PN = "AJ34"  !CDS_PN = "AJ34";
"VSS_AJ35":   PN = "AJ35"  !CDS_PN = "AJ35";
"VSS_AJ36":   PN = "AJ36"  !CDS_PN = "AJ36";
"VSS_AJ40":   PN = "AJ40"  !CDS_PN = "AJ40";
"VSS_AJ41":   PN = "AJ41"  !CDS_PN = "AJ41";
"VSS_AJ42":   PN = "AJ42"  !CDS_PN = "AJ42";
"VSS_AJ45":   PN = "AJ45"  !CDS_PN = "AJ45";
"VSS_AJ48":   PN = "AJ48"  !CDS_PN = "AJ48";
"VSS_AJ51":   PN = "AJ51"  !CDS_PN = "AJ51";
"VSS_AJ54":   PN = "AJ54"  !CDS_PN = "AJ54";
"VSS_AJ56":   PN = "AJ56"  !CDS_PN = "AJ56";
"VSS_AJ61":   PN = "AJ61"  !CDS_PN = "AJ61";
"VSS_AJ63":   PN = "AJ63"  !CDS_PN = "AJ63";
"VSS_AJ68":   PN = "AJ68"  !CDS_PN = "AJ68";
"VSS_AJ70":   PN = "AJ70"  !CDS_PN = "AJ70";
"VSS_AJ75":   PN = "AJ75"  !CDS_PN = "AJ75";
"VSS_AK3":   PN = "AK3"  !CDS_PN = "AK3";
"VSS_AK5":   PN = "AK5"  !CDS_PN = "AK5";
"VSS_AK8":   PN = "AK8"  !CDS_PN = "AK8";
"VSS_AK10":   PN = "AK10"  !CDS_PN = "AK10";
"VSS_AK12":   PN = "AK12"  !CDS_PN = "AK12";
"VSS_AK15":   PN = "AK15"  !CDS_PN = "AK15";
"VSS_AK17":   PN = "AK17"  !CDS_PN = "AK17";
"VSS_AK19":   PN = "AK19"  !CDS_PN = "AK19";
"VSS_AK22":   PN = "AK22"  !CDS_PN = "AK22";
"VSS_AK25":   PN = "AK25"  !CDS_PN = "AK25";
"VSS_AK28":   PN = "AK28"  !CDS_PN = "AK28";
"VSS_AK31":   PN = "AK31"  !CDS_PN = "AK31";
"VSS_AK34":   PN = "AK34"  !CDS_PN = "AK34";
"VSS_AK37":   PN = "AK37"  !CDS_PN = "AK37";
"VSS_AK39":   PN = "AK39"  !CDS_PN = "AK39";
"VSS_AK42":   PN = "AK42"  !CDS_PN = "AK42";
"VSS_AK45":   PN = "AK45"  !CDS_PN = "AK45";
"VSS_AK48":   PN = "AK48"  !CDS_PN = "AK48";
"VSS_AK51":   PN = "AK51"  !CDS_PN = "AK51";
"VSS_AK54":   PN = "AK54"  !CDS_PN = "AK54";
"VSS_AK57":   PN = "AK57"  !CDS_PN = "AK57";
"VSS_AK59":   PN = "AK59"  !CDS_PN = "AK59";
"VSS_AK61":   PN = "AK61"  !CDS_PN = "AK61";
"VSS_AK64":   PN = "AK64"  !CDS_PN = "AK64";
"VSS_AK66":   PN = "AK66"  !CDS_PN = "AK66";
"VSS_AK68":   PN = "AK68"  !CDS_PN = "AK68";
"VSS_AK71":   PN = "AK71"  !CDS_PN = "AK71";
"VSS_AK73":   PN = "AK73"  !CDS_PN = "AK73";
"VSS_AL1":   PN = "AL1"  !CDS_PN = "AL1";
"VSS_AL4":   PN = "AL4"  !CDS_PN = "AL4";
"VSS_AL6":   PN = "AL6"  !CDS_PN = "AL6";
"VSS_AL8":   PN = "AL8"  !CDS_PN = "AL8";
"VSS_AL11":   PN = "AL11"  !CDS_PN = "AL11";
"VSS_AL13":   PN = "AL13"  !CDS_PN = "AL13";
"VSS_AL15":   PN = "AL15"  !CDS_PN = "AL15";
"VSS_AL18":   PN = "AL18"  !CDS_PN = "AL18";
"VSS_AL20":   PN = "AL20"  !CDS_PN = "AL20";
"VSS_AL22":   PN = "AL22"  !CDS_PN = "AL22";
"VSS_AL25":   PN = "AL25"  !CDS_PN = "AL25";
"VSS_AL28":   PN = "AL28"  !CDS_PN = "AL28";
"VSS_AL31":   PN = "AL31"  !CDS_PN = "AL31";
"VSS_AL34":   PN = "AL34"  !CDS_PN = "AL34";
"VSS_AL42":   PN = "AL42"  !CDS_PN = "AL42";
"VSS_AL45":   PN = "AL45"  !CDS_PN = "AL45";
"VSS_AL48":   PN = "AL48"  !CDS_PN = "AL48";
"VSS_AL51":   PN = "AL51"  !CDS_PN = "AL51";
"VSS_AL54":   PN = "AL54"  !CDS_PN = "AL54";
"VSS_AL56":   PN = "AL56"  !CDS_PN = "AL56";
"VSS_AL58":   PN = "AL58"  !CDS_PN = "AL58";
"VSS_AL61":   PN = "AL61"  !CDS_PN = "AL61";
"VSS_AL63":   PN = "AL63"  !CDS_PN = "AL63";
"VSS_AL65":   PN = "AL65"  !CDS_PN = "AL65";
"VSS_AL68":   PN = "AL68"  !CDS_PN = "AL68";
"VSS_AL70":   PN = "AL70"  !CDS_PN = "AL70";
"VSS_AL72":   PN = "AL72"  !CDS_PN = "AL72";
"VSS_AL75":   PN = "AL75"  !CDS_PN = "AL75";
"VSS_AM3":   PN = "AM3"  !CDS_PN = "AM3";
"VSS_AM8":   PN = "AM8"  !CDS_PN = "AM8";
"VSS_AM10":   PN = "AM10"  !CDS_PN = "AM10";
"VSS_AM15":   PN = "AM15"  !CDS_PN = "AM15";
"VSS_AM17":   PN = "AM17"  !CDS_PN = "AM17";
"VSS_AM23":   PN = "AM23"  !CDS_PN = "AM23";
"VSS_AM24":   PN = "AM24"  !CDS_PN = "AM24";
"VSS_AM25":   PN = "AM25"  !CDS_PN = "AM25";
"VSS_AM26":   PN = "AM26"  !CDS_PN = "AM26";
"VSS_AM27":   PN = "AM27"  !CDS_PN = "AM27";
"VSS_AM28":   PN = "AM28"  !CDS_PN = "AM28";
"VSS_AM29":   PN = "AM29"  !CDS_PN = "AM29";
"VSS_AM30":   PN = "AM30"  !CDS_PN = "AM30";
"VSS_AM31":   PN = "AM31"  !CDS_PN = "AM31";
"VSS_AM32":   PN = "AM32"  !CDS_PN = "AM32";
"VSS_AM33":   PN = "AM33"  !CDS_PN = "AM33";
"VSS_AM34":   PN = "AM34"  !CDS_PN = "AM34";
"VSS_AM39":   PN = "AM39"  !CDS_PN = "AM39";
BODY = "GENOA_SP5","I23": #LOCATION = "U25" !CDS_LOCATION = "U25" &SEC = "32" #&CDS_SEC = "32";
"VSS_AM42":   PN = "AM42"  !CDS_PN = "AM42";
"VSS_AM43":   PN = "AM43"  !CDS_PN = "AM43";
"VSS_AM44":   PN = "AM44"  !CDS_PN = "AM44";
"VSS_AM45":   PN = "AM45"  !CDS_PN = "AM45";
"VSS_AM46":   PN = "AM46"  !CDS_PN = "AM46";
"VSS_AM47":   PN = "AM47"  !CDS_PN = "AM47";
"VSS_AM48":   PN = "AM48"  !CDS_PN = "AM48";
"VSS_AM49":   PN = "AM49"  !CDS_PN = "AM49";
"VSS_AM50":   PN = "AM50"  !CDS_PN = "AM50";
"VSS_AM51":   PN = "AM51"  !CDS_PN = "AM51";
"VSS_AM52":   PN = "AM52"  !CDS_PN = "AM52";
"VSS_AM53":   PN = "AM53"  !CDS_PN = "AM53";
"VSS_AM59":   PN = "AM59"  !CDS_PN = "AM59";
"VSS_AM61":   PN = "AM61"  !CDS_PN = "AM61";
"VSS_AM66":   PN = "AM66"  !CDS_PN = "AM66";
"VSS_AM68":   PN = "AM68"  !CDS_PN = "AM68";
"VSS_AM73":   PN = "AM73"  !CDS_PN = "AM73";
"VSS_AN1":   PN = "AN1"  !CDS_PN = "AN1";
"VSS_AN4":   PN = "AN4"  !CDS_PN = "AN4";
"VSS_AN6":   PN = "AN6"  !CDS_PN = "AN6";
"VSS_AN8":   PN = "AN8"  !CDS_PN = "AN8";
"VSS_AN11":   PN = "AN11"  !CDS_PN = "AN11";
"VSS_AN13":   PN = "AN13"  !CDS_PN = "AN13";
"VSS_AN15":   PN = "AN15"  !CDS_PN = "AN15";
"VSS_AN18":   PN = "AN18"  !CDS_PN = "AN18";
"VSS_AN22":   PN = "AN22"  !CDS_PN = "AN22";
"VSS_AN25":   PN = "AN25"  !CDS_PN = "AN25";
"VSS_AN28":   PN = "AN28"  !CDS_PN = "AN28";
"VSS_AN31":   PN = "AN31"  !CDS_PN = "AN31";
"VSS_AN34":   PN = "AN34"  !CDS_PN = "AN34";
"VSS_AN35":   PN = "AN35"  !CDS_PN = "AN35";
"VSS_AN36":   PN = "AN36"  !CDS_PN = "AN36";
"VSS_AN40":   PN = "AN40"  !CDS_PN = "AN40";
"VSS_AN41":   PN = "AN41"  !CDS_PN = "AN41";
"VSS_AN42":   PN = "AN42"  !CDS_PN = "AN42";
"VSS_AN45":   PN = "AN45"  !CDS_PN = "AN45";
"VSS_AN48":   PN = "AN48"  !CDS_PN = "AN48";
"VSS_AN51":   PN = "AN51"  !CDS_PN = "AN51";
"VSS_AN54":   PN = "AN54"  !CDS_PN = "AN54";
"VSS_AN56":   PN = "AN56"  !CDS_PN = "AN56";
"VSS_AN58":   PN = "AN58"  !CDS_PN = "AN58";
"VSS_AN61":   PN = "AN61"  !CDS_PN = "AN61";
"VSS_AN63":   PN = "AN63"  !CDS_PN = "AN63";
"VSS_AN65":   PN = "AN65"  !CDS_PN = "AN65";
"VSS_AN68":   PN = "AN68"  !CDS_PN = "AN68";
"VSS_AN70":   PN = "AN70"  !CDS_PN = "AN70";
"VSS_AN72":   PN = "AN72"  !CDS_PN = "AN72";
"VSS_AN75":   PN = "AN75"  !CDS_PN = "AN75";
"VSS_AP3":   PN = "AP3"  !CDS_PN = "AP3";
"VSS_AP5":   PN = "AP5"  !CDS_PN = "AP5";
"VSS_AP8":   PN = "AP8"  !CDS_PN = "AP8";
"VSS_AP10":   PN = "AP10"  !CDS_PN = "AP10";
"VSS_AP12":   PN = "AP12"  !CDS_PN = "AP12";
"VSS_AP15":   PN = "AP15"  !CDS_PN = "AP15";
"VSS_AP17":   PN = "AP17"  !CDS_PN = "AP17";
"VSS_AP19":   PN = "AP19"  !CDS_PN = "AP19";
"VSS_AP22":   PN = "AP22"  !CDS_PN = "AP22";
"VSS_AP25":   PN = "AP25"  !CDS_PN = "AP25";
"VSS_AP28":   PN = "AP28"  !CDS_PN = "AP28";
"VSS_AP31":   PN = "AP31"  !CDS_PN = "AP31";
"VSS_AP34":   PN = "AP34"  !CDS_PN = "AP34";
"VSS_AP37":   PN = "AP37"  !CDS_PN = "AP37";
"VSS_AP39":   PN = "AP39"  !CDS_PN = "AP39";
"VSS_AP42":   PN = "AP42"  !CDS_PN = "AP42";
"VSS_AP45":   PN = "AP45"  !CDS_PN = "AP45";
"VSS_AP48":   PN = "AP48"  !CDS_PN = "AP48";
"VSS_AP51":   PN = "AP51"  !CDS_PN = "AP51";
"VSS_AP54":   PN = "AP54"  !CDS_PN = "AP54";
"VSS_AP57":   PN = "AP57"  !CDS_PN = "AP57";
"VSS_AP59":   PN = "AP59"  !CDS_PN = "AP59";
"VSS_AP61":   PN = "AP61"  !CDS_PN = "AP61";
"VSS_AP64":   PN = "AP64"  !CDS_PN = "AP64";
"VSS_AP66":   PN = "AP66"  !CDS_PN = "AP66";
"VSS_AP68":   PN = "AP68"  !CDS_PN = "AP68";
"VSS_AP71":   PN = "AP71"  !CDS_PN = "AP71";
"VSS_AP73":   PN = "AP73"  !CDS_PN = "AP73";
"VSS_AR1":   PN = "AR1"  !CDS_PN = "AR1";
"VSS_AR5":   PN = "AR5"  !CDS_PN = "AR5";
"VSS_AR6":   PN = "AR6"  !CDS_PN = "AR6";
"VSS_AR8":   PN = "AR8"  !CDS_PN = "AR8";
"VSS_AR9":   PN = "AR9"  !CDS_PN = "AR9";
"VSS_AR12":   PN = "AR12"  !CDS_PN = "AR12";
"VSS_AR13":   PN = "AR13"  !CDS_PN = "AR13";
"VSS_AR15":   PN = "AR15"  !CDS_PN = "AR15";
"VSS_AR16":   PN = "AR16"  !CDS_PN = "AR16";
"VSS_AR19":   PN = "AR19"  !CDS_PN = "AR19";
"VSS_AR20":   PN = "AR20"  !CDS_PN = "AR20";
"VSS_AR22":   PN = "AR22"  !CDS_PN = "AR22";
"VSS_AR24":   PN = "AR24"  !CDS_PN = "AR24";
"VSS_AR26":   PN = "AR26"  !CDS_PN = "AR26";
"VSS_AR28":   PN = "AR28"  !CDS_PN = "AR28";
"VSS_AR30":   PN = "AR30"  !CDS_PN = "AR30";
"VSS_AR32":   PN = "AR32"  !CDS_PN = "AR32";
"VSS_AR34":   PN = "AR34"  !CDS_PN = "AR34";
"VSS_AR36":   PN = "AR36"  !CDS_PN = "AR36";
"VSS_AR41":   PN = "AR41"  !CDS_PN = "AR41";
"VSS_AR43":   PN = "AR43"  !CDS_PN = "AR43";
"VSS_AR45":   PN = "AR45"  !CDS_PN = "AR45";
"VSS_AR47":   PN = "AR47"  !CDS_PN = "AR47";
"VSS_AR49":   PN = "AR49"  !CDS_PN = "AR49";
"VSS_AR51":   PN = "AR51"  !CDS_PN = "AR51";
"VSS_AR53":   PN = "AR53"  !CDS_PN = "AR53";
"VSS_AR56":   PN = "AR56"  !CDS_PN = "AR56";
"VSS_AR57":   PN = "AR57"  !CDS_PN = "AR57";
"VSS_AR60":   PN = "AR60"  !CDS_PN = "AR60";
"VSS_AR61":   PN = "AR61"  !CDS_PN = "AR61";
"VSS_AR63":   PN = "AR63"  !CDS_PN = "AR63";
"VSS_AR64":   PN = "AR64"  !CDS_PN = "AR64";
"VSS_AR67":   PN = "AR67"  !CDS_PN = "AR67";
"VSS_AR68":   PN = "AR68"  !CDS_PN = "AR68";
"VSS_AR70":   PN = "AR70"  !CDS_PN = "AR70";
"VSS_AR71":   PN = "AR71"  !CDS_PN = "AR71";
"VSS_AR75":   PN = "AR75"  !CDS_PN = "AR75";
"VSS_AT3":   PN = "AT3"  !CDS_PN = "AT3";
"VSS_AT4":   PN = "AT4"  !CDS_PN = "AT4";
"VSS_AT5":   PN = "AT5"  !CDS_PN = "AT5";
"VSS_AT6":   PN = "AT6"  !CDS_PN = "AT6";
"VSS_AT8":   PN = "AT8"  !CDS_PN = "AT8";
"VSS_AT9":   PN = "AT9"  !CDS_PN = "AT9";
"VSS_AT10":   PN = "AT10"  !CDS_PN = "AT10";
"VSS_AT12":   PN = "AT12"  !CDS_PN = "AT12";
"VSS_AT13":   PN = "AT13"  !CDS_PN = "AT13";
"VSS_AT15":   PN = "AT15"  !CDS_PN = "AT15";
"VSS_AT16":   PN = "AT16"  !CDS_PN = "AT16";
"VSS_AT17":   PN = "AT17"  !CDS_PN = "AT17";
"VSS_AT19":   PN = "AT19"  !CDS_PN = "AT19";
"VSS_AT20":   PN = "AT20"  !CDS_PN = "AT20";
"VSS_AT23":   PN = "AT23"  !CDS_PN = "AT23";
"VSS_AT25":   PN = "AT25"  !CDS_PN = "AT25";
"VSS_AT27":   PN = "AT27"  !CDS_PN = "AT27";
"VSS_AT29":   PN = "AT29"  !CDS_PN = "AT29";
"VSS_AT31":   PN = "AT31"  !CDS_PN = "AT31";
"VSS_AT33":   PN = "AT33"  !CDS_PN = "AT33";
"VSS_AT35":   PN = "AT35"  !CDS_PN = "AT35";
"VSS_AT37":   PN = "AT37"  !CDS_PN = "AT37";
"VSS_AT40":   PN = "AT40"  !CDS_PN = "AT40";
"VSS_AT42":   PN = "AT42"  !CDS_PN = "AT42";
"VSS_AT44":   PN = "AT44"  !CDS_PN = "AT44";
"VSS_AT46":   PN = "AT46"  !CDS_PN = "AT46";
"VSS_AT48":   PN = "AT48"  !CDS_PN = "AT48";
"VSS_AT50":   PN = "AT50"  !CDS_PN = "AT50";
"VSS_AT52":   PN = "AT52"  !CDS_PN = "AT52";
"VSS_AT54":   PN = "AT54"  !CDS_PN = "AT54";
"VSS_AT56":   PN = "AT56"  !CDS_PN = "AT56";
"VSS_AT57":   PN = "AT57"  !CDS_PN = "AT57";
"VSS_AT59":   PN = "AT59"  !CDS_PN = "AT59";
"VSS_AT60":   PN = "AT60"  !CDS_PN = "AT60";
"VSS_AT61":   PN = "AT61"  !CDS_PN = "AT61";
"VSS_AT63":   PN = "AT63"  !CDS_PN = "AT63";
"VSS_AT64":   PN = "AT64"  !CDS_PN = "AT64";
"VSS_AT66":   PN = "AT66"  !CDS_PN = "AT66";
"VSS_AT67":   PN = "AT67"  !CDS_PN = "AT67";
"VSS_AT68":   PN = "AT68"  !CDS_PN = "AT68";
"VSS_AT70":   PN = "AT70"  !CDS_PN = "AT70";
"VSS_AT71":   PN = "AT71"  !CDS_PN = "AT71";
"VSS_AT72":   PN = "AT72"  !CDS_PN = "AT72";
"VSS_AT73":   PN = "AT73"  !CDS_PN = "AT73";
"VSS_AU1":   PN = "AU1"  !CDS_PN = "AU1";
"VSS_AU3":   PN = "AU3"  !CDS_PN = "AU3";
"VSS_AU4":   PN = "AU4"  !CDS_PN = "AU4";
"VSS_AU6":   PN = "AU6"  !CDS_PN = "AU6";
"VSS_AU8":   PN = "AU8"  !CDS_PN = "AU8";
"VSS_AU11":   PN = "AU11"  !CDS_PN = "AU11";
"VSS_AU13":   PN = "AU13"  !CDS_PN = "AU13";
"VSS_AU15":   PN = "AU15"  !CDS_PN = "AU15";
"VSS_AU18":   PN = "AU18"  !CDS_PN = "AU18";
"VSS_AU20":   PN = "AU20"  !CDS_PN = "AU20";
"VSS_AU22":   PN = "AU22"  !CDS_PN = "AU22";
"VSS_AU24":   PN = "AU24"  !CDS_PN = "AU24";
"VSS_AU26":   PN = "AU26"  !CDS_PN = "AU26";
"VSS_AU28":   PN = "AU28"  !CDS_PN = "AU28";
"VSS_AU30":   PN = "AU30"  !CDS_PN = "AU30";
"VSS_AU32":   PN = "AU32"  !CDS_PN = "AU32";
"VSS_AU34":   PN = "AU34"  !CDS_PN = "AU34";
"VSS_AU36":   PN = "AU36"  !CDS_PN = "AU36";
"VSS_AU41":   PN = "AU41"  !CDS_PN = "AU41";
"VSS_AU43":   PN = "AU43"  !CDS_PN = "AU43";
"VSS_AU45":   PN = "AU45"  !CDS_PN = "AU45";
"VSS_AU47":   PN = "AU47"  !CDS_PN = "AU47";
"VSS_AU49":   PN = "AU49"  !CDS_PN = "AU49";
"VSS_AU51":   PN = "AU51"  !CDS_PN = "AU51";
"VSS_AU53":   PN = "AU53"  !CDS_PN = "AU53";
"VSS_AU56":   PN = "AU56"  !CDS_PN = "AU56";
"VSS_AU58":   PN = "AU58"  !CDS_PN = "AU58";
"VSS_AU61":   PN = "AU61"  !CDS_PN = "AU61";
"VSS_AU63":   PN = "AU63"  !CDS_PN = "AU63";
"VSS_AU65":   PN = "AU65"  !CDS_PN = "AU65";
"VSS_AU68":   PN = "AU68"  !CDS_PN = "AU68";
"VSS_AU70":   PN = "AU70"  !CDS_PN = "AU70";
"VSS_AU72":   PN = "AU72"  !CDS_PN = "AU72";
"VSS_AU73":   PN = "AU73"  !CDS_PN = "AU73";
"VSS_AU75":   PN = "AU75"  !CDS_PN = "AU75";
"VSS_AV3":   PN = "AV3"  !CDS_PN = "AV3";
"VSS_AV8":   PN = "AV8"  !CDS_PN = "AV8";
"VSS_AV10":   PN = "AV10"  !CDS_PN = "AV10";
"VSS_AV15":   PN = "AV15"  !CDS_PN = "AV15";
"VSS_AV17":   PN = "AV17"  !CDS_PN = "AV17";
"VSS_AV23":   PN = "AV23"  !CDS_PN = "AV23";
"VSS_AV25":   PN = "AV25"  !CDS_PN = "AV25";
"VSS_AV27":   PN = "AV27"  !CDS_PN = "AV27";
"VSS_AV29":   PN = "AV29"  !CDS_PN = "AV29";
"VSS_AV31":   PN = "AV31"  !CDS_PN = "AV31";
"VSS_AV33":   PN = "AV33"  !CDS_PN = "AV33";
"VSS_AV35":   PN = "AV35"  !CDS_PN = "AV35";
"VSS_AV37":   PN = "AV37"  !CDS_PN = "AV37";
"VSS_AV40":   PN = "AV40"  !CDS_PN = "AV40";
"VSS_AV42":   PN = "AV42"  !CDS_PN = "AV42";
"VSS_AV44":   PN = "AV44"  !CDS_PN = "AV44";
"VSS_AV46":   PN = "AV46"  !CDS_PN = "AV46";
"VSS_AV48":   PN = "AV48"  !CDS_PN = "AV48";
"VSS_AV50":   PN = "AV50"  !CDS_PN = "AV50";
"VSS_AV52":   PN = "AV52"  !CDS_PN = "AV52";
"VSS_AV54":   PN = "AV54"  !CDS_PN = "AV54";
"VSS_AV59":   PN = "AV59"  !CDS_PN = "AV59";
"VSS_AV61":   PN = "AV61"  !CDS_PN = "AV61";
"VSS_AV66":   PN = "AV66"  !CDS_PN = "AV66";
"VSS_AV68":   PN = "AV68"  !CDS_PN = "AV68";
"VSS_AV73":   PN = "AV73"  !CDS_PN = "AV73";
"VSS_AW1":   PN = "AW1"  !CDS_PN = "AW1";
"VSS_AW4":   PN = "AW4"  !CDS_PN = "AW4";
"VSS_AW6":   PN = "AW6"  !CDS_PN = "AW6";
"VSS_AW8":   PN = "AW8"  !CDS_PN = "AW8";
"VSS_AW11":   PN = "AW11"  !CDS_PN = "AW11";
"VSS_AW13":   PN = "AW13"  !CDS_PN = "AW13";
"VSS_AW15":   PN = "AW15"  !CDS_PN = "AW15";
"VSS_AW18":   PN = "AW18"  !CDS_PN = "AW18";
"VSS_AW20":   PN = "AW20"  !CDS_PN = "AW20";
"VSS_AW22":   PN = "AW22"  !CDS_PN = "AW22";
"VSS_AW24":   PN = "AW24"  !CDS_PN = "AW24";
"VSS_AW26":   PN = "AW26"  !CDS_PN = "AW26";
"VSS_AW28":   PN = "AW28"  !CDS_PN = "AW28";
"VSS_AW49":   PN = "AW49"  !CDS_PN = "AW49";
"VSS_AW51":   PN = "AW51"  !CDS_PN = "AW51";
"VSS_AW53":   PN = "AW53"  !CDS_PN = "AW53";
"VSS_AW56":   PN = "AW56"  !CDS_PN = "AW56";
"VSS_AW58":   PN = "AW58"  !CDS_PN = "AW58";
"VSS_AW61":   PN = "AW61"  !CDS_PN = "AW61";
BODY = "GENOA_SP5","I24": #LOCATION = "U25" !CDS_LOCATION = "U25" &SEC = "33" #&CDS_SEC = "33";
"VSS_AW63":   PN = "AW63"  !CDS_PN = "AW63";
"VSS_AW65":   PN = "AW65"  !CDS_PN = "AW65";
"VSS_AW68":   PN = "AW68"  !CDS_PN = "AW68";
"VSS_AW70":   PN = "AW70"  !CDS_PN = "AW70";
"VSS_AW72":   PN = "AW72"  !CDS_PN = "AW72";
"VSS_AW75":   PN = "AW75"  !CDS_PN = "AW75";
"VSS_AY3":   PN = "AY3"  !CDS_PN = "AY3";
"VSS_AY5":   PN = "AY5"  !CDS_PN = "AY5";
"VSS_AY8":   PN = "AY8"  !CDS_PN = "AY8";
"VSS_AY10":   PN = "AY10"  !CDS_PN = "AY10";
"VSS_AY12":   PN = "AY12"  !CDS_PN = "AY12";
"VSS_AY15":   PN = "AY15"  !CDS_PN = "AY15";
"VSS_AY17":   PN = "AY17"  !CDS_PN = "AY17";
"VSS_AY19":   PN = "AY19"  !CDS_PN = "AY19";
"VSS_AY23":   PN = "AY23"  !CDS_PN = "AY23";
"VSS_AY25":   PN = "AY25"  !CDS_PN = "AY25";
"VSS_AY27":   PN = "AY27"  !CDS_PN = "AY27";
"VSS_AY48":   PN = "AY48"  !CDS_PN = "AY48";
"VSS_AY50":   PN = "AY50"  !CDS_PN = "AY50";
"VSS_AY52":   PN = "AY52"  !CDS_PN = "AY52";
"VSS_AY54":   PN = "AY54"  !CDS_PN = "AY54";
"VSS_AY57":   PN = "AY57"  !CDS_PN = "AY57";
"VSS_AY59":   PN = "AY59"  !CDS_PN = "AY59";
"VSS_AY61":   PN = "AY61"  !CDS_PN = "AY61";
"VSS_AY64":   PN = "AY64"  !CDS_PN = "AY64";
"VSS_AY66":   PN = "AY66"  !CDS_PN = "AY66";
"VSS_AY68":   PN = "AY68"  !CDS_PN = "AY68";
"VSS_AY71":   PN = "AY71"  !CDS_PN = "AY71";
"VSS_AY73":   PN = "AY73"  !CDS_PN = "AY73";
"VSS_BA1":   PN = "BA1"  !CDS_PN = "BA1";
"VSS_BA6":   PN = "BA6"  !CDS_PN = "BA6";
"VSS_BA8":   PN = "BA8"  !CDS_PN = "BA8";
"VSS_BA13":   PN = "BA13"  !CDS_PN = "BA13";
"VSS_BA15":   PN = "BA15"  !CDS_PN = "BA15";
"VSS_BA20":   PN = "BA20"  !CDS_PN = "BA20";
"VSS_BA22":   PN = "BA22"  !CDS_PN = "BA22";
"VSS_BA24":   PN = "BA24"  !CDS_PN = "BA24";
"VSS_BA26":   PN = "BA26"  !CDS_PN = "BA26";
"VSS_BA28":   PN = "BA28"  !CDS_PN = "BA28";
"VSS_BA49":   PN = "BA49"  !CDS_PN = "BA49";
"VSS_BA51":   PN = "BA51"  !CDS_PN = "BA51";
"VSS_BA53":   PN = "BA53"  !CDS_PN = "BA53";
"VSS_BA56":   PN = "BA56"  !CDS_PN = "BA56";
"VSS_BA61":   PN = "BA61"  !CDS_PN = "BA61";
"VSS_BA63":   PN = "BA63"  !CDS_PN = "BA63";
"VSS_BA68":   PN = "BA68"  !CDS_PN = "BA68";
"VSS_BA70":   PN = "BA70"  !CDS_PN = "BA70";
"VSS_BA75":   PN = "BA75"  !CDS_PN = "BA75";
"VSS_BB3":   PN = "BB3"  !CDS_PN = "BB3";
"VSS_BB5":   PN = "BB5"  !CDS_PN = "BB5";
"VSS_BB8":   PN = "BB8"  !CDS_PN = "BB8";
"VSS_BB10":   PN = "BB10"  !CDS_PN = "BB10";
"VSS_BB12":   PN = "BB12"  !CDS_PN = "BB12";
"VSS_BB15":   PN = "BB15"  !CDS_PN = "BB15";
"VSS_BB17":   PN = "BB17"  !CDS_PN = "BB17";
"VSS_BB19":   PN = "BB19"  !CDS_PN = "BB19";
"VSS_BB23":   PN = "BB23"  !CDS_PN = "BB23";
"VSS_BB25":   PN = "BB25"  !CDS_PN = "BB25";
"VSS_BB27":   PN = "BB27"  !CDS_PN = "BB27";
"VSS_BB48":   PN = "BB48"  !CDS_PN = "BB48";
"VSS_BB50":   PN = "BB50"  !CDS_PN = "BB50";
"VSS_BB52":   PN = "BB52"  !CDS_PN = "BB52";
"VSS_BB54":   PN = "BB54"  !CDS_PN = "BB54";
"VSS_BB57":   PN = "BB57"  !CDS_PN = "BB57";
"VSS_BB59":   PN = "BB59"  !CDS_PN = "BB59";
"VSS_BB61":   PN = "BB61"  !CDS_PN = "BB61";
"VSS_BB64":   PN = "BB64"  !CDS_PN = "BB64";
"VSS_BB66":   PN = "BB66"  !CDS_PN = "BB66";
"VSS_BB68":   PN = "BB68"  !CDS_PN = "BB68";
"VSS_BB71":   PN = "BB71"  !CDS_PN = "BB71";
"VSS_BB73":   PN = "BB73"  !CDS_PN = "BB73";
"VSS_BC1":   PN = "BC1"  !CDS_PN = "BC1";
"VSS_BC4":   PN = "BC4"  !CDS_PN = "BC4";
"VSS_BC6":   PN = "BC6"  !CDS_PN = "BC6";
"VSS_BC8":   PN = "BC8"  !CDS_PN = "BC8";
"VSS_BC11":   PN = "BC11"  !CDS_PN = "BC11";
"VSS_BC13":   PN = "BC13"  !CDS_PN = "BC13";
"VSS_BC15":   PN = "BC15"  !CDS_PN = "BC15";
"VSS_BC18":   PN = "BC18"  !CDS_PN = "BC18";
"VSS_BC20":   PN = "BC20"  !CDS_PN = "BC20";
"VSS_BC22":   PN = "BC22"  !CDS_PN = "BC22";
"VSS_BC24":   PN = "BC24"  !CDS_PN = "BC24";
"VSS_BC26":   PN = "BC26"  !CDS_PN = "BC26";
"VSS_BC28":   PN = "BC28"  !CDS_PN = "BC28";
"VSS_BC49":   PN = "BC49"  !CDS_PN = "BC49";
"VSS_BC50":   PN = "BC50"  !CDS_PN = "BC50";
"VSS_BC51":   PN = "BC51"  !CDS_PN = "BC51";
"VSS_BC53":   PN = "BC53"  !CDS_PN = "BC53";
"VSS_BC56":   PN = "BC56"  !CDS_PN = "BC56";
"VSS_BC58":   PN = "BC58"  !CDS_PN = "BC58";
"VSS_BC61":   PN = "BC61"  !CDS_PN = "BC61";
"VSS_BC63":   PN = "BC63"  !CDS_PN = "BC63";
"VSS_BC65":   PN = "BC65"  !CDS_PN = "BC65";
"VSS_BC68":   PN = "BC68"  !CDS_PN = "BC68";
"VSS_BC70":   PN = "BC70"  !CDS_PN = "BC70";
"VSS_BC72":   PN = "BC72"  !CDS_PN = "BC72";
"VSS_BC75":   PN = "BC75"  !CDS_PN = "BC75";
"VSS_BD3":   PN = "BD3"  !CDS_PN = "BD3";
"VSS_BD8":   PN = "BD8"  !CDS_PN = "BD8";
"VSS_BD10":   PN = "BD10"  !CDS_PN = "BD10";
"VSS_BD15":   PN = "BD15"  !CDS_PN = "BD15";
"VSS_BD17":   PN = "BD17"  !CDS_PN = "BD17";
"VSS_BD23":   PN = "BD23"  !CDS_PN = "BD23";
"VSS_BD25":   PN = "BD25"  !CDS_PN = "BD25";
"VSS_BD27":   PN = "BD27"  !CDS_PN = "BD27";
"VSS_BD49":   PN = "BD49"  !CDS_PN = "BD49";
"VSS_BD51":   PN = "BD51"  !CDS_PN = "BD51";
"VSS_BD53":   PN = "BD53"  !CDS_PN = "BD53";
"VSS_BD57":   PN = "BD57"  !CDS_PN = "BD57";
"VSS_BD59":   PN = "BD59"  !CDS_PN = "BD59";
"VSS_BD61":   PN = "BD61"  !CDS_PN = "BD61";
"VSS_BD64":   PN = "BD64"  !CDS_PN = "BD64";
"VSS_BD66":   PN = "BD66"  !CDS_PN = "BD66";
"VSS_BD68":   PN = "BD68"  !CDS_PN = "BD68";
"VSS_BD71":   PN = "BD71"  !CDS_PN = "BD71";
"VSS_BD73":   PN = "BD73"  !CDS_PN = "BD73";
"VSS_BF3":   PN = "BF3"  !CDS_PN = "BF3";
"VSS_BF5":   PN = "BF5"  !CDS_PN = "BF5";
"VSS_BF8":   PN = "BF8"  !CDS_PN = "BF8";
"VSS_BF10":   PN = "BF10"  !CDS_PN = "BF10";
"VSS_BF12":   PN = "BF12"  !CDS_PN = "BF12";
"VSS_BF15":   PN = "BF15"  !CDS_PN = "BF15";
"VSS_BF17":   PN = "BF17"  !CDS_PN = "BF17";
"VSS_BF19":   PN = "BF19"  !CDS_PN = "BF19";
"VSS_BF22":   PN = "BF22"  !CDS_PN = "BF22";
"VSS_BF24":   PN = "BF24"  !CDS_PN = "BF24";
"VSS_BF26":   PN = "BF26"  !CDS_PN = "BF26";
"VSS_BF28":   PN = "BF28"  !CDS_PN = "BF28";
"VSS_BF49":   PN = "BF49"  !CDS_PN = "BF49";
"VSS_BF50":   PN = "BF50"  !CDS_PN = "BF50";
"VSS_BF52":   PN = "BF52"  !CDS_PN = "BF52";
"VSS_BF54":   PN = "BF54"  !CDS_PN = "BF54";
"VSS_BF59":   PN = "BF59"  !CDS_PN = "BF59";
"VSS_BF61":   PN = "BF61"  !CDS_PN = "BF61";
"VSS_BF66":   PN = "BF66"  !CDS_PN = "BF66";
"VSS_BF68":   PN = "BF68"  !CDS_PN = "BF68";
"VSS_BF73":   PN = "BF73"  !CDS_PN = "BF73";
"VSS_BG1":   PN = "BG1"  !CDS_PN = "BG1";
"VSS_BG4":   PN = "BG4"  !CDS_PN = "BG4";
"VSS_BG6":   PN = "BG6"  !CDS_PN = "BG6";
"VSS_BG8":   PN = "BG8"  !CDS_PN = "BG8";
"VSS_BG11":   PN = "BG11"  !CDS_PN = "BG11";
"VSS_BG13":   PN = "BG13"  !CDS_PN = "BG13";
"VSS_BG15":   PN = "BG15"  !CDS_PN = "BG15";
"VSS_BG18":   PN = "BG18"  !CDS_PN = "BG18";
"VSS_BG20":   PN = "BG20"  !CDS_PN = "BG20";
"VSS_BG23":   PN = "BG23"  !CDS_PN = "BG23";
"VSS_BG25":   PN = "BG25"  !CDS_PN = "BG25";
"VSS_BG27":   PN = "BG27"  !CDS_PN = "BG27";
"VSS_BG49":   PN = "BG49"  !CDS_PN = "BG49";
"VSS_BG51":   PN = "BG51"  !CDS_PN = "BG51";
"VSS_BG53":   PN = "BG53"  !CDS_PN = "BG53";
"VSS_BG56":   PN = "BG56"  !CDS_PN = "BG56";
"VSS_BG58":   PN = "BG58"  !CDS_PN = "BG58";
"VSS_BG61":   PN = "BG61"  !CDS_PN = "BG61";
"VSS_BG63":   PN = "BG63"  !CDS_PN = "BG63";
"VSS_BG65":   PN = "BG65"  !CDS_PN = "BG65";
"VSS_BG68":   PN = "BG68"  !CDS_PN = "BG68";
"VSS_BG70":   PN = "BG70"  !CDS_PN = "BG70";
"VSS_BG72":   PN = "BG72"  !CDS_PN = "BG72";
"VSS_BG75":   PN = "BG75"  !CDS_PN = "BG75";
"VSS_BH3":   PN = "BH3"  !CDS_PN = "BH3";
"VSS_BH5":   PN = "BH5"  !CDS_PN = "BH5";
"VSS_BH8":   PN = "BH8"  !CDS_PN = "BH8";
"VSS_BH10":   PN = "BH10"  !CDS_PN = "BH10";
"VSS_BH12":   PN = "BH12"  !CDS_PN = "BH12";
"VSS_BH15":   PN = "BH15"  !CDS_PN = "BH15";
"VSS_BH17":   PN = "BH17"  !CDS_PN = "BH17";
"VSS_BH19":   PN = "BH19"  !CDS_PN = "BH19";
"VSS_BH22":   PN = "BH22"  !CDS_PN = "BH22";
"VSS_BH24":   PN = "BH24"  !CDS_PN = "BH24";
"VSS_BH26":   PN = "BH26"  !CDS_PN = "BH26";
"VSS_BH28":   PN = "BH28"  !CDS_PN = "BH28";
"VSS_BH49":   PN = "BH49"  !CDS_PN = "BH49";
"VSS_BH50":   PN = "BH50"  !CDS_PN = "BH50";
"VSS_BH52":   PN = "BH52"  !CDS_PN = "BH52";
"VSS_BH54":   PN = "BH54"  !CDS_PN = "BH54";
"VSS_BH57":   PN = "BH57"  !CDS_PN = "BH57";
"VSS_BH59":   PN = "BH59"  !CDS_PN = "BH59";
"VSS_BH61":   PN = "BH61"  !CDS_PN = "BH61";
"VSS_BH64":   PN = "BH64"  !CDS_PN = "BH64";
"VSS_BH66":   PN = "BH66"  !CDS_PN = "BH66";
"VSS_BH68":   PN = "BH68"  !CDS_PN = "BH68";
"VSS_BH71":   PN = "BH71"  !CDS_PN = "BH71";
"VSS_BH73":   PN = "BH73"  !CDS_PN = "BH73";
"VSS_BJ1":   PN = "BJ1"  !CDS_PN = "BJ1";
"VSS_BJ6":   PN = "BJ6"  !CDS_PN = "BJ6";
"VSS_BJ8":   PN = "BJ8"  !CDS_PN = "BJ8";
"VSS_BJ13":   PN = "BJ13"  !CDS_PN = "BJ13";
"VSS_BJ15":   PN = "BJ15"  !CDS_PN = "BJ15";
"VSS_BJ20":   PN = "BJ20"  !CDS_PN = "BJ20";
"VSS_BJ22":   PN = "BJ22"  !CDS_PN = "BJ22";
"VSS_BJ24":   PN = "BJ24"  !CDS_PN = "BJ24";
"VSS_BJ26":   PN = "BJ26"  !CDS_PN = "BJ26";
"VSS_BJ28":   PN = "BJ28"  !CDS_PN = "BJ28";
"VSS_BJ49":   PN = "BJ49"  !CDS_PN = "BJ49";
"VSS_BJ51":   PN = "BJ51"  !CDS_PN = "BJ51";
"VSS_BJ53":   PN = "BJ53"  !CDS_PN = "BJ53";
"VSS_BJ56":   PN = "BJ56"  !CDS_PN = "BJ56";
"VSS_BJ61":   PN = "BJ61"  !CDS_PN = "BJ61";
"VSS_BJ63":   PN = "BJ63"  !CDS_PN = "BJ63";
"VSS_BJ68":   PN = "BJ68"  !CDS_PN = "BJ68";
"VSS_BJ70":   PN = "BJ70"  !CDS_PN = "BJ70";
"VSS_BJ75":   PN = "BJ75"  !CDS_PN = "BJ75";
"VSS_BK3":   PN = "BK3"  !CDS_PN = "BK3";
"VSS_BK5":   PN = "BK5"  !CDS_PN = "BK5";
"VSS_BK8":   PN = "BK8"  !CDS_PN = "BK8";
"VSS_BK10":   PN = "BK10"  !CDS_PN = "BK10";
"VSS_BK12":   PN = "BK12"  !CDS_PN = "BK12";
"VSS_BK15":   PN = "BK15"  !CDS_PN = "BK15";
"VSS_BK17":   PN = "BK17"  !CDS_PN = "BK17";
"VSS_BK19":   PN = "BK19"  !CDS_PN = "BK19";
"VSS_BK23":   PN = "BK23"  !CDS_PN = "BK23";
"VSS_BK25":   PN = "BK25"  !CDS_PN = "BK25";
"VSS_BK27":   PN = "BK27"  !CDS_PN = "BK27";
"VSS_BK48":   PN = "BK48"  !CDS_PN = "BK48";
"VSS_BK50":   PN = "BK50"  !CDS_PN = "BK50";
"VSS_BK52":   PN = "BK52"  !CDS_PN = "BK52";
"VSS_BK54":   PN = "BK54"  !CDS_PN = "BK54";
"VSS_BK57":   PN = "BK57"  !CDS_PN = "BK57";
"VSS_BK59":   PN = "BK59"  !CDS_PN = "BK59";
"VSS_BK61":   PN = "BK61"  !CDS_PN = "BK61";
"VSS_BK64":   PN = "BK64"  !CDS_PN = "BK64";
"VSS_BK66":   PN = "BK66"  !CDS_PN = "BK66";
"VSS_BK68":   PN = "BK68"  !CDS_PN = "BK68";
"VSS_BK71":   PN = "BK71"  !CDS_PN = "BK71";
"VSS_BK73":   PN = "BK73"  !CDS_PN = "BK73";
"VSS_BL1":   PN = "BL1"  !CDS_PN = "BL1";
"VSS_BL4":   PN = "BL4"  !CDS_PN = "BL4";
"VSS_BL6":   PN = "BL6"  !CDS_PN = "BL6";
"VSS_BL8":   PN = "BL8"  !CDS_PN = "BL8";
"VSS_BL11":   PN = "BL11"  !CDS_PN = "BL11";
"VSS_BL13":   PN = "BL13"  !CDS_PN = "BL13";
"VSS_BL15":   PN = "BL15"  !CDS_PN = "BL15";
"VSS_BL18":   PN = "BL18"  !CDS_PN = "BL18";
"VSS_BL20":   PN = "BL20"  !CDS_PN = "BL20";
"VSS_BL22":   PN = "BL22"  !CDS_PN = "BL22";
"VSS_BL24":   PN = "BL24"  !CDS_PN = "BL24";
DRAWING = "@t6g_mb_lib.t6g(sch_1):page32";
BODY = "GENOA_SP5","I13": #LOCATION = "U25" !CDS_LOCATION = "U25" &SEC = "34" #&CDS_SEC = "34";
"VSS_BL26":   PN = "BL26"  !CDS_PN = "BL26";
"VSS_BL28":   PN = "BL28"  !CDS_PN = "BL28";
"VSS_BL49":   PN = "BL49"  !CDS_PN = "BL49";
"VSS_BL51":   PN = "BL51"  !CDS_PN = "BL51";
"VSS_BL53":   PN = "BL53"  !CDS_PN = "BL53";
"VSS_BL56":   PN = "BL56"  !CDS_PN = "BL56";
"VSS_BL58":   PN = "BL58"  !CDS_PN = "BL58";
"VSS_BL61":   PN = "BL61"  !CDS_PN = "BL61";
"VSS_BL63":   PN = "BL63"  !CDS_PN = "BL63";
"VSS_BL65":   PN = "BL65"  !CDS_PN = "BL65";
"VSS_BL68":   PN = "BL68"  !CDS_PN = "BL68";
"VSS_BL70":   PN = "BL70"  !CDS_PN = "BL70";
"VSS_BL72":   PN = "BL72"  !CDS_PN = "BL72";
"VSS_BL75":   PN = "BL75"  !CDS_PN = "BL75";
"VSS_BM3":   PN = "BM3"  !CDS_PN = "BM3";
"VSS_BM8":   PN = "BM8"  !CDS_PN = "BM8";
"VSS_BM10":   PN = "BM10"  !CDS_PN = "BM10";
"VSS_BM15":   PN = "BM15"  !CDS_PN = "BM15";
"VSS_BM17":   PN = "BM17"  !CDS_PN = "BM17";
"VSS_BM23":   PN = "BM23"  !CDS_PN = "BM23";
"VSS_BM25":   PN = "BM25"  !CDS_PN = "BM25";
"VSS_BM27":   PN = "BM27"  !CDS_PN = "BM27";
"VSS_BM29":   PN = "BM29"  !CDS_PN = "BM29";
"VSS_BM31":   PN = "BM31"  !CDS_PN = "BM31";
"VSS_BM33":   PN = "BM33"  !CDS_PN = "BM33";
"VSS_BM35":   PN = "BM35"  !CDS_PN = "BM35";
"VSS_BM37":   PN = "BM37"  !CDS_PN = "BM37";
"VSS_BM40":   PN = "BM40"  !CDS_PN = "BM40";
"VSS_BM42":   PN = "BM42"  !CDS_PN = "BM42";
"VSS_BM44":   PN = "BM44"  !CDS_PN = "BM44";
"VSS_BM46":   PN = "BM46"  !CDS_PN = "BM46";
"VSS_BM48":   PN = "BM48"  !CDS_PN = "BM48";
"VSS_BM50":   PN = "BM50"  !CDS_PN = "BM50";
"VSS_BM52":   PN = "BM52"  !CDS_PN = "BM52";
"VSS_BM54":   PN = "BM54"  !CDS_PN = "BM54";
"VSS_BM59":   PN = "BM59"  !CDS_PN = "BM59";
"VSS_BM61":   PN = "BM61"  !CDS_PN = "BM61";
"VSS_BM66":   PN = "BM66"  !CDS_PN = "BM66";
"VSS_BM68":   PN = "BM68"  !CDS_PN = "BM68";
"VSS_BM73":   PN = "BM73"  !CDS_PN = "BM73";
"VSS_BN1":   PN = "BN1"  !CDS_PN = "BN1";
"VSS_BN4":   PN = "BN4"  !CDS_PN = "BN4";
"VSS_BN6":   PN = "BN6"  !CDS_PN = "BN6";
"VSS_BN8":   PN = "BN8"  !CDS_PN = "BN8";
"VSS_BN11":   PN = "BN11"  !CDS_PN = "BN11";
"VSS_BN13":   PN = "BN13"  !CDS_PN = "BN13";
"VSS_BN15":   PN = "BN15"  !CDS_PN = "BN15";
"VSS_BN18":   PN = "BN18"  !CDS_PN = "BN18";
"VSS_BN20":   PN = "BN20"  !CDS_PN = "BN20";
"VSS_BN22":   PN = "BN22"  !CDS_PN = "BN22";
"VSS_BN24":   PN = "BN24"  !CDS_PN = "BN24";
"VSS_BN26":   PN = "BN26"  !CDS_PN = "BN26";
"VSS_BN28":   PN = "BN28"  !CDS_PN = "BN28";
"VSS_BN30":   PN = "BN30"  !CDS_PN = "BN30";
"VSS_BN32":   PN = "BN32"  !CDS_PN = "BN32";
"VSS_BN34":   PN = "BN34"  !CDS_PN = "BN34";
"VSS_BN36":   PN = "BN36"  !CDS_PN = "BN36";
"VSS_BN41":   PN = "BN41"  !CDS_PN = "BN41";
"VSS_BN43":   PN = "BN43"  !CDS_PN = "BN43";
"VSS_BN45":   PN = "BN45"  !CDS_PN = "BN45";
"VSS_BN47":   PN = "BN47"  !CDS_PN = "BN47";
"VSS_BN49":   PN = "BN49"  !CDS_PN = "BN49";
"VSS_BN51":   PN = "BN51"  !CDS_PN = "BN51";
"VSS_BN53":   PN = "BN53"  !CDS_PN = "BN53";
"VSS_BN56":   PN = "BN56"  !CDS_PN = "BN56";
"VSS_BN58":   PN = "BN58"  !CDS_PN = "BN58";
"VSS_BN61":   PN = "BN61"  !CDS_PN = "BN61";
"VSS_BN63":   PN = "BN63"  !CDS_PN = "BN63";
"VSS_BN65":   PN = "BN65"  !CDS_PN = "BN65";
"VSS_BN68":   PN = "BN68"  !CDS_PN = "BN68";
"VSS_BN70":   PN = "BN70"  !CDS_PN = "BN70";
"VSS_BN72":   PN = "BN72"  !CDS_PN = "BN72";
"VSS_BN75":   PN = "BN75"  !CDS_PN = "BN75";
"VSS_BP3":   PN = "BP3"  !CDS_PN = "BP3";
"VSS_BP5":   PN = "BP5"  !CDS_PN = "BP5";
"VSS_BP8":   PN = "BP8"  !CDS_PN = "BP8";
"VSS_BP10":   PN = "BP10"  !CDS_PN = "BP10";
"VSS_BP12":   PN = "BP12"  !CDS_PN = "BP12";
"VSS_BP15":   PN = "BP15"  !CDS_PN = "BP15";
"VSS_BP17":   PN = "BP17"  !CDS_PN = "BP17";
"VSS_BP19":   PN = "BP19"  !CDS_PN = "BP19";
"VSS_BP23":   PN = "BP23"  !CDS_PN = "BP23";
"VSS_BP25":   PN = "BP25"  !CDS_PN = "BP25";
"VSS_BP27":   PN = "BP27"  !CDS_PN = "BP27";
"VSS_BP29":   PN = "BP29"  !CDS_PN = "BP29";
"VSS_BP31":   PN = "BP31"  !CDS_PN = "BP31";
"VSS_BP33":   PN = "BP33"  !CDS_PN = "BP33";
"VSS_BP35":   PN = "BP35"  !CDS_PN = "BP35";
"VSS_BP37":   PN = "BP37"  !CDS_PN = "BP37";
"VSS_BP40":   PN = "BP40"  !CDS_PN = "BP40";
"VSS_BP42":   PN = "BP42"  !CDS_PN = "BP42";
"VSS_BP44":   PN = "BP44"  !CDS_PN = "BP44";
"VSS_BP46":   PN = "BP46"  !CDS_PN = "BP46";
"VSS_BP48":   PN = "BP48"  !CDS_PN = "BP48";
"VSS_BP50":   PN = "BP50"  !CDS_PN = "BP50";
"VSS_BP52":   PN = "BP52"  !CDS_PN = "BP52";
"VSS_BP54":   PN = "BP54"  !CDS_PN = "BP54";
"VSS_BP57":   PN = "BP57"  !CDS_PN = "BP57";
"VSS_BP59":   PN = "BP59"  !CDS_PN = "BP59";
"VSS_BP61":   PN = "BP61"  !CDS_PN = "BP61";
"VSS_BP64":   PN = "BP64"  !CDS_PN = "BP64";
"VSS_BP66":   PN = "BP66"  !CDS_PN = "BP66";
"VSS_BP68":   PN = "BP68"  !CDS_PN = "BP68";
"VSS_BP71":   PN = "BP71"  !CDS_PN = "BP71";
"VSS_BP73":   PN = "BP73"  !CDS_PN = "BP73";
"VSS_BR1":   PN = "BR1"  !CDS_PN = "BR1";
"VSS_BR3":   PN = "BR3"  !CDS_PN = "BR3";
"VSS_BR6":   PN = "BR6"  !CDS_PN = "BR6";
"VSS_BR7":   PN = "BR7"  !CDS_PN = "BR7";
"VSS_BR8":   PN = "BR8"  !CDS_PN = "BR8";
"VSS_BR10":   PN = "BR10"  !CDS_PN = "BR10";
"VSS_BR13":   PN = "BR13"  !CDS_PN = "BR13";
"VSS_BR14":   PN = "BR14"  !CDS_PN = "BR14";
"VSS_BR15":   PN = "BR15"  !CDS_PN = "BR15";
"VSS_BR17":   PN = "BR17"  !CDS_PN = "BR17";
"VSS_BR20":   PN = "BR20"  !CDS_PN = "BR20";
"VSS_BR21":   PN = "BR21"  !CDS_PN = "BR21";
"VSS_BR22":   PN = "BR22"  !CDS_PN = "BR22";
"VSS_BR24":   PN = "BR24"  !CDS_PN = "BR24";
"VSS_BR26":   PN = "BR26"  !CDS_PN = "BR26";
"VSS_BR28":   PN = "BR28"  !CDS_PN = "BR28";
"VSS_BR30":   PN = "BR30"  !CDS_PN = "BR30";
"VSS_BR32":   PN = "BR32"  !CDS_PN = "BR32";
"VSS_BR34":   PN = "BR34"  !CDS_PN = "BR34";
"VSS_BR36":   PN = "BR36"  !CDS_PN = "BR36";
"VSS_BR41":   PN = "BR41"  !CDS_PN = "BR41";
"VSS_BR43":   PN = "BR43"  !CDS_PN = "BR43";
"VSS_BR45":   PN = "BR45"  !CDS_PN = "BR45";
"VSS_BR47":   PN = "BR47"  !CDS_PN = "BR47";
"VSS_BR49":   PN = "BR49"  !CDS_PN = "BR49";
"VSS_BR51":   PN = "BR51"  !CDS_PN = "BR51";
"VSS_BR55":   PN = "BR55"  !CDS_PN = "BR55";
"VSS_BR56":   PN = "BR56"  !CDS_PN = "BR56";
"VSS_BR59":   PN = "BR59"  !CDS_PN = "BR59";
"VSS_BR61":   PN = "BR61"  !CDS_PN = "BR61";
"VSS_BR62":   PN = "BR62"  !CDS_PN = "BR62";
"VSS_BR63":   PN = "BR63"  !CDS_PN = "BR63";
"VSS_BR66":   PN = "BR66"  !CDS_PN = "BR66";
"VSS_BR68":   PN = "BR68"  !CDS_PN = "BR68";
"VSS_BR69":   PN = "BR69"  !CDS_PN = "BR69";
"VSS_BR70":   PN = "BR70"  !CDS_PN = "BR70";
"VSS_BR73":   PN = "BR73"  !CDS_PN = "BR73";
"VSS_BR75":   PN = "BR75"  !CDS_PN = "BR75";
"VSS_BT3":   PN = "BT3"  !CDS_PN = "BT3";
"VSS_BT4":   PN = "BT4"  !CDS_PN = "BT4";
"VSS_BT5":   PN = "BT5"  !CDS_PN = "BT5";
"VSS_BT7":   PN = "BT7"  !CDS_PN = "BT7";
"VSS_BT8":   PN = "BT8"  !CDS_PN = "BT8";
"VSS_BT10":   PN = "BT10"  !CDS_PN = "BT10";
"VSS_BT11":   PN = "BT11"  !CDS_PN = "BT11";
"VSS_BT12":   PN = "BT12"  !CDS_PN = "BT12";
"VSS_BT14":   PN = "BT14"  !CDS_PN = "BT14";
"VSS_BT15":   PN = "BT15"  !CDS_PN = "BT15";
"VSS_BT17":   PN = "BT17"  !CDS_PN = "BT17";
"VSS_BT18":   PN = "BT18"  !CDS_PN = "BT18";
"VSS_BT19":   PN = "BT19"  !CDS_PN = "BT19";
"VSS_BT21":   PN = "BT21"  !CDS_PN = "BT21";
"VSS_BT22":   PN = "BT22"  !CDS_PN = "BT22";
"VSS_BT25":   PN = "BT25"  !CDS_PN = "BT25";
"VSS_BT28":   PN = "BT28"  !CDS_PN = "BT28";
"VSS_BT31":   PN = "BT31"  !CDS_PN = "BT31";
"VSS_BT34":   PN = "BT34"  !CDS_PN = "BT34";
"VSS_BT37":   PN = "BT37"  !CDS_PN = "BT37";
"VSS_BT39":   PN = "BT39"  !CDS_PN = "BT39";
"VSS_BT42":   PN = "BT42"  !CDS_PN = "BT42";
"VSS_BT45":   PN = "BT45"  !CDS_PN = "BT45";
"VSS_BT48":   PN = "BT48"  !CDS_PN = "BT48";
"VSS_BT51":   PN = "BT51"  !CDS_PN = "BT51";
"VSS_BT54":   PN = "BT54"  !CDS_PN = "BT54";
"VSS_BT55":   PN = "BT55"  !CDS_PN = "BT55";
"VSS_BT57":   PN = "BT57"  !CDS_PN = "BT57";
"VSS_BT58":   PN = "BT58"  !CDS_PN = "BT58";
"VSS_BT59":   PN = "BT59"  !CDS_PN = "BT59";
"VSS_BT61":   PN = "BT61"  !CDS_PN = "BT61";
"VSS_BT62":   PN = "BT62"  !CDS_PN = "BT62";
"VSS_BT64":   PN = "BT64"  !CDS_PN = "BT64";
"VSS_BT65":   PN = "BT65"  !CDS_PN = "BT65";
"VSS_BT66":   PN = "BT66"  !CDS_PN = "BT66";
"VSS_BT68":   PN = "BT68"  !CDS_PN = "BT68";
"VSS_BT69":   PN = "BT69"  !CDS_PN = "BT69";
"VSS_BT71":   PN = "BT71"  !CDS_PN = "BT71";
"VSS_BT72":   PN = "BT72"  !CDS_PN = "BT72";
"VSS_BT73":   PN = "BT73"  !CDS_PN = "BT73";
"VSS_BU1":   PN = "BU1"  !CDS_PN = "BU1";
"VSS_BU4":   PN = "BU4"  !CDS_PN = "BU4";
"VSS_BU6":   PN = "BU6"  !CDS_PN = "BU6";
"VSS_BU8":   PN = "BU8"  !CDS_PN = "BU8";
"VSS_BU11":   PN = "BU11"  !CDS_PN = "BU11";
"VSS_BU13":   PN = "BU13"  !CDS_PN = "BU13";
"VSS_BU15":   PN = "BU15"  !CDS_PN = "BU15";
"VSS_BU18":   PN = "BU18"  !CDS_PN = "BU18";
"VSS_BU20":   PN = "BU20"  !CDS_PN = "BU20";
"VSS_BU22":   PN = "BU22"  !CDS_PN = "BU22";
"VSS_BU25":   PN = "BU25"  !CDS_PN = "BU25";
"VSS_BU28":   PN = "BU28"  !CDS_PN = "BU28";
"VSS_BU31":   PN = "BU31"  !CDS_PN = "BU31";
"VSS_BU34":   PN = "BU34"  !CDS_PN = "BU34";
"VSS_BU35":   PN = "BU35"  !CDS_PN = "BU35";
"VSS_BU36":   PN = "BU36"  !CDS_PN = "BU36";
"VSS_BU40":   PN = "BU40"  !CDS_PN = "BU40";
"VSS_BU41":   PN = "BU41"  !CDS_PN = "BU41";
"VSS_BU42":   PN = "BU42"  !CDS_PN = "BU42";
"VSS_BU45":   PN = "BU45"  !CDS_PN = "BU45";
"VSS_BU48":   PN = "BU48"  !CDS_PN = "BU48";
"VSS_BU51":   PN = "BU51"  !CDS_PN = "BU51";
"VSS_BU54":   PN = "BU54"  !CDS_PN = "BU54";
"VSS_BU56":   PN = "BU56"  !CDS_PN = "BU56";
"VSS_BU58":   PN = "BU58"  !CDS_PN = "BU58";
"VSS_BU61":   PN = "BU61"  !CDS_PN = "BU61";
"VSS_BU63":   PN = "BU63"  !CDS_PN = "BU63";
"VSS_BU65":   PN = "BU65"  !CDS_PN = "BU65";
"VSS_BU68":   PN = "BU68"  !CDS_PN = "BU68";
"VSS_BU70":   PN = "BU70"  !CDS_PN = "BU70";
"VSS_BU72":   PN = "BU72"  !CDS_PN = "BU72";
"VSS_BU75":   PN = "BU75"  !CDS_PN = "BU75";
"VSS_BV3":   PN = "BV3"  !CDS_PN = "BV3";
"VSS_BV8":   PN = "BV8"  !CDS_PN = "BV8";
"VSS_BV10":   PN = "BV10"  !CDS_PN = "BV10";
"VSS_BV15":   PN = "BV15"  !CDS_PN = "BV15";
"VSS_BV17":   PN = "BV17"  !CDS_PN = "BV17";
"VSS_BV23":   PN = "BV23"  !CDS_PN = "BV23";
"VSS_BV24":   PN = "BV24"  !CDS_PN = "BV24";
"VSS_BV25":   PN = "BV25"  !CDS_PN = "BV25";
"VSS_BV26":   PN = "BV26"  !CDS_PN = "BV26";
"VSS_BV27":   PN = "BV27"  !CDS_PN = "BV27";
"VSS_BV28":   PN = "BV28"  !CDS_PN = "BV28";
"VSS_BV29":   PN = "BV29"  !CDS_PN = "BV29";
"VSS_BV30":   PN = "BV30"  !CDS_PN = "BV30";
"VSS_BV31":   PN = "BV31"  !CDS_PN = "BV31";
"VSS_BV32":   PN = "BV32"  !CDS_PN = "BV32";
"VSS_BV33":   PN = "BV33"  !CDS_PN = "BV33";
"VSS_BV34":   PN = "BV34"  !CDS_PN = "BV34";
"VSS_BV37":   PN = "BV37"  !CDS_PN = "BV37";
"VSS_BV39":   PN = "BV39"  !CDS_PN = "BV39";
"VSS_BV43":   PN = "BV43"  !CDS_PN = "BV43";
"VSS_BV44":   PN = "BV44"  !CDS_PN = "BV44";
"VSS_BV45":   PN = "BV45"  !CDS_PN = "BV45";
BODY = "GENOA_SP5","I14": #LOCATION = "U25" !CDS_LOCATION = "U25" &SEC = "37" #&CDS_SEC = "37";
"VSS_BV46":   PN = "BV46"  !CDS_PN = "BV46";
"VSS_BV47":   PN = "BV47"  !CDS_PN = "BV47";
"VSS_BV48":   PN = "BV48"  !CDS_PN = "BV48";
"VSS_BV49":   PN = "BV49"  !CDS_PN = "BV49";
"VSS_BV50":   PN = "BV50"  !CDS_PN = "BV50";
"VSS_BV51":   PN = "BV51"  !CDS_PN = "BV51";
"VSS_BV52":   PN = "BV52"  !CDS_PN = "BV52";
"VSS_BV53":   PN = "BV53"  !CDS_PN = "BV53";
"VSS_BV59":   PN = "BV59"  !CDS_PN = "BV59";
"VSS_BV61":   PN = "BV61"  !CDS_PN = "BV61";
"VSS_BV66":   PN = "BV66"  !CDS_PN = "BV66";
"VSS_BV68":   PN = "BV68"  !CDS_PN = "BV68";
"VSS_BV73":   PN = "BV73"  !CDS_PN = "BV73";
"VSS_BW1":   PN = "BW1"  !CDS_PN = "BW1";
"VSS_BW4":   PN = "BW4"  !CDS_PN = "BW4";
"VSS_BW6":   PN = "BW6"  !CDS_PN = "BW6";
"VSS_BW8":   PN = "BW8"  !CDS_PN = "BW8";
"VSS_BW11":   PN = "BW11"  !CDS_PN = "BW11";
"VSS_BW13":   PN = "BW13"  !CDS_PN = "BW13";
"VSS_BW15":   PN = "BW15"  !CDS_PN = "BW15";
"VSS_BW18":   PN = "BW18"  !CDS_PN = "BW18";
"VSS_BW20":   PN = "BW20"  !CDS_PN = "BW20";
"VSS_BW22":   PN = "BW22"  !CDS_PN = "BW22";
"VSS_BW28":   PN = "BW28"  !CDS_PN = "BW28";
"VSS_BW31":   PN = "BW31"  !CDS_PN = "BW31";
"VSS_BW34":   PN = "BW34"  !CDS_PN = "BW34";
"VSS_BW42":   PN = "BW42"  !CDS_PN = "BW42";
"VSS_BW45":   PN = "BW45"  !CDS_PN = "BW45";
"VSS_BW48":   PN = "BW48"  !CDS_PN = "BW48";
"VSS_BW51":   PN = "BW51"  !CDS_PN = "BW51";
"VSS_BW54":   PN = "BW54"  !CDS_PN = "BW54";
"VSS_BW56":   PN = "BW56"  !CDS_PN = "BW56";
"VSS_BW58":   PN = "BW58"  !CDS_PN = "BW58";
"VSS_BW61":   PN = "BW61"  !CDS_PN = "BW61";
"VSS_BW63":   PN = "BW63"  !CDS_PN = "BW63";
"VSS_BW65":   PN = "BW65"  !CDS_PN = "BW65";
"VSS_BW68":   PN = "BW68"  !CDS_PN = "BW68";
"VSS_BW70":   PN = "BW70"  !CDS_PN = "BW70";
"VSS_BW72":   PN = "BW72"  !CDS_PN = "BW72";
"VSS_BW75":   PN = "BW75"  !CDS_PN = "BW75";
"VSS_BY3":   PN = "BY3"  !CDS_PN = "BY3";
"VSS_BY5":   PN = "BY5"  !CDS_PN = "BY5";
"VSS_BY8":   PN = "BY8"  !CDS_PN = "BY8";
"VSS_BY10":   PN = "BY10"  !CDS_PN = "BY10";
"VSS_BY12":   PN = "BY12"  !CDS_PN = "BY12";
"VSS_BY15":   PN = "BY15"  !CDS_PN = "BY15";
"VSS_BY17":   PN = "BY17"  !CDS_PN = "BY17";
"VSS_BY19":   PN = "BY19"  !CDS_PN = "BY19";
"VSS_BY22":   PN = "BY22"  !CDS_PN = "BY22";
"VSS_BY25":   PN = "BY25"  !CDS_PN = "BY25";
"VSS_BY28":   PN = "BY28"  !CDS_PN = "BY28";
"VSS_BY31":   PN = "BY31"  !CDS_PN = "BY31";
"VSS_BY34":   PN = "BY34"  !CDS_PN = "BY34";
"VSS_BY37":   PN = "BY37"  !CDS_PN = "BY37";
"VSS_BY39":   PN = "BY39"  !CDS_PN = "BY39";
"VSS_BY42":   PN = "BY42"  !CDS_PN = "BY42";
"VSS_BY45":   PN = "BY45"  !CDS_PN = "BY45";
"VSS_BY48":   PN = "BY48"  !CDS_PN = "BY48";
"VSS_BY51":   PN = "BY51"  !CDS_PN = "BY51";
"VSS_BY54":   PN = "BY54"  !CDS_PN = "BY54";
"VSS_BY57":   PN = "BY57"  !CDS_PN = "BY57";
"VSS_BY59":   PN = "BY59"  !CDS_PN = "BY59";
"VSS_BY61":   PN = "BY61"  !CDS_PN = "BY61";
"VSS_BY64":   PN = "BY64"  !CDS_PN = "BY64";
"VSS_BY66":   PN = "BY66"  !CDS_PN = "BY66";
"VSS_BY68":   PN = "BY68"  !CDS_PN = "BY68";
"VSS_BY71":   PN = "BY71"  !CDS_PN = "BY71";
"VSS_BY73":   PN = "BY73"  !CDS_PN = "BY73";
"VSS_CA1":   PN = "CA1"  !CDS_PN = "CA1";
"VSS_CA6":   PN = "CA6"  !CDS_PN = "CA6";
"VSS_CA8":   PN = "CA8"  !CDS_PN = "CA8";
"VSS_CA13":   PN = "CA13"  !CDS_PN = "CA13";
"VSS_CA15":   PN = "CA15"  !CDS_PN = "CA15";
"VSS_CA20":   PN = "CA20"  !CDS_PN = "CA20";
"VSS_CA22":   PN = "CA22"  !CDS_PN = "CA22";
"VSS_CA25":   PN = "CA25"  !CDS_PN = "CA25";
"VSS_CA28":   PN = "CA28"  !CDS_PN = "CA28";
"VSS_CA31":   PN = "CA31"  !CDS_PN = "CA31";
"VSS_CA34":   PN = "CA34"  !CDS_PN = "CA34";
"VSS_CA35":   PN = "CA35"  !CDS_PN = "CA35";
"VSS_CA36":   PN = "CA36"  !CDS_PN = "CA36";
"VSS_CA40":   PN = "CA40"  !CDS_PN = "CA40";
"VSS_CA41":   PN = "CA41"  !CDS_PN = "CA41";
"VSS_CA42":   PN = "CA42"  !CDS_PN = "CA42";
"VSS_CA45":   PN = "CA45"  !CDS_PN = "CA45";
"VSS_CA48":   PN = "CA48"  !CDS_PN = "CA48";
"VSS_CA51":   PN = "CA51"  !CDS_PN = "CA51";
"VSS_CA54":   PN = "CA54"  !CDS_PN = "CA54";
"VSS_CA56":   PN = "CA56"  !CDS_PN = "CA56";
"VSS_CA61":   PN = "CA61"  !CDS_PN = "CA61";
"VSS_CA63":   PN = "CA63"  !CDS_PN = "CA63";
"VSS_CA68":   PN = "CA68"  !CDS_PN = "CA68";
"VSS_CA70":   PN = "CA70"  !CDS_PN = "CA70";
"VSS_CA75":   PN = "CA75"  !CDS_PN = "CA75";
"VSS_CB3":   PN = "CB3"  !CDS_PN = "CB3";
"VSS_CB5":   PN = "CB5"  !CDS_PN = "CB5";
"VSS_CB8":   PN = "CB8"  !CDS_PN = "CB8";
"VSS_CB10":   PN = "CB10"  !CDS_PN = "CB10";
"VSS_CB12":   PN = "CB12"  !CDS_PN = "CB12";
"VSS_CB15":   PN = "CB15"  !CDS_PN = "CB15";
"VSS_CB17":   PN = "CB17"  !CDS_PN = "CB17";
"VSS_CB19":   PN = "CB19"  !CDS_PN = "CB19";
"VSS_CB23":   PN = "CB23"  !CDS_PN = "CB23";
"VSS_CB24":   PN = "CB24"  !CDS_PN = "CB24";
"VSS_CB25":   PN = "CB25"  !CDS_PN = "CB25";
"VSS_CB26":   PN = "CB26"  !CDS_PN = "CB26";
"VSS_CB27":   PN = "CB27"  !CDS_PN = "CB27";
"VSS_CB28":   PN = "CB28"  !CDS_PN = "CB28";
"VSS_CB29":   PN = "CB29"  !CDS_PN = "CB29";
"VSS_CB30":   PN = "CB30"  !CDS_PN = "CB30";
"VSS_CB31":   PN = "CB31"  !CDS_PN = "CB31";
"VSS_CB32":   PN = "CB32"  !CDS_PN = "CB32";
"VSS_CB33":   PN = "CB33"  !CDS_PN = "CB33";
"VSS_CB34":   PN = "CB34"  !CDS_PN = "CB34";
"VSS_CB37":   PN = "CB37"  !CDS_PN = "CB37";
"VSS_CB39":   PN = "CB39"  !CDS_PN = "CB39";
"VSS_CB42":   PN = "CB42"  !CDS_PN = "CB42";
"VSS_CB43":   PN = "CB43"  !CDS_PN = "CB43";
"VSS_CB45":   PN = "CB45"  !CDS_PN = "CB45";
"VSS_CB46":   PN = "CB46"  !CDS_PN = "CB46";
"VSS_CB47":   PN = "CB47"  !CDS_PN = "CB47";
"VSS_CB48":   PN = "CB48"  !CDS_PN = "CB48";
"VSS_CB49":   PN = "CB49"  !CDS_PN = "CB49";
"VSS_CB50":   PN = "CB50"  !CDS_PN = "CB50";
"VSS_CB51":   PN = "CB51"  !CDS_PN = "CB51";
"VSS_CB52":   PN = "CB52"  !CDS_PN = "CB52";
"VSS_CB53":   PN = "CB53"  !CDS_PN = "CB53";
"VSS_CB57":   PN = "CB57"  !CDS_PN = "CB57";
"VSS_CB59":   PN = "CB59"  !CDS_PN = "CB59";
"VSS_CB61":   PN = "CB61"  !CDS_PN = "CB61";
"VSS_CB64":   PN = "CB64"  !CDS_PN = "CB64";
"VSS_CB66":   PN = "CB66"  !CDS_PN = "CB66";
"VSS_CB68":   PN = "CB68"  !CDS_PN = "CB68";
"VSS_CB71":   PN = "CB71"  !CDS_PN = "CB71";
"VSS_CB73":   PN = "CB73"  !CDS_PN = "CB73";
"VSS_CC1":   PN = "CC1"  !CDS_PN = "CC1";
"VSS_CC4":   PN = "CC4"  !CDS_PN = "CC4";
"VSS_CC6":   PN = "CC6"  !CDS_PN = "CC6";
"VSS_CC8":   PN = "CC8"  !CDS_PN = "CC8";
"VSS_CC11":   PN = "CC11"  !CDS_PN = "CC11";
"VSS_CC13":   PN = "CC13"  !CDS_PN = "CC13";
"VSS_CC15":   PN = "CC15"  !CDS_PN = "CC15";
"VSS_CC18":   PN = "CC18"  !CDS_PN = "CC18";
"VSS_CC20":   PN = "CC20"  !CDS_PN = "CC20";
"VSS_CC25":   PN = "CC25"  !CDS_PN = "CC25";
"VSS_CC28":   PN = "CC28"  !CDS_PN = "CC28";
"VSS_CC31":   PN = "CC31"  !CDS_PN = "CC31";
"VSS_CC34":   PN = "CC34"  !CDS_PN = "CC34";
"VSS_CC42":   PN = "CC42"  !CDS_PN = "CC42";
"VSS_CC45":   PN = "CC45"  !CDS_PN = "CC45";
"VSS_CC48":   PN = "CC48"  !CDS_PN = "CC48";
"VSS_CC51":   PN = "CC51"  !CDS_PN = "CC51";
"VSS_CC54":   PN = "CC54"  !CDS_PN = "CC54";
"VSS_CC56":   PN = "CC56"  !CDS_PN = "CC56";
"VSS_CC58":   PN = "CC58"  !CDS_PN = "CC58";
"VSS_CC61":   PN = "CC61"  !CDS_PN = "CC61";
"VSS_CC63":   PN = "CC63"  !CDS_PN = "CC63";
"VSS_CC65":   PN = "CC65"  !CDS_PN = "CC65";
"VSS_CC68":   PN = "CC68"  !CDS_PN = "CC68";
"VSS_CC70":   PN = "CC70"  !CDS_PN = "CC70";
"VSS_CC72":   PN = "CC72"  !CDS_PN = "CC72";
"VSS_CC75":   PN = "CC75"  !CDS_PN = "CC75";
"VSS_CD3":   PN = "CD3"  !CDS_PN = "CD3";
"VSS_CD8":   PN = "CD8"  !CDS_PN = "CD8";
"VSS_CD10":   PN = "CD10"  !CDS_PN = "CD10";
"VSS_CD15":   PN = "CD15"  !CDS_PN = "CD15";
"VSS_CD17":   PN = "CD17"  !CDS_PN = "CD17";
"VSS_CD22":   PN = "CD22"  !CDS_PN = "CD22";
"VSS_CD25":   PN = "CD25"  !CDS_PN = "CD25";
"VSS_CD28":   PN = "CD28"  !CDS_PN = "CD28";
"VSS_CD31":   PN = "CD31"  !CDS_PN = "CD31";
"VSS_CD34":   PN = "CD34"  !CDS_PN = "CD34";
"VSS_CD37":   PN = "CD37"  !CDS_PN = "CD37";
"VSS_CD39":   PN = "CD39"  !CDS_PN = "CD39";
"VSS_CD42":   PN = "CD42"  !CDS_PN = "CD42";
"VSS_CD45":   PN = "CD45"  !CDS_PN = "CD45";
"VSS_CD48":   PN = "CD48"  !CDS_PN = "CD48";
"VSS_CD51":   PN = "CD51"  !CDS_PN = "CD51";
"VSS_CD54":   PN = "CD54"  !CDS_PN = "CD54";
"VSS_CD59":   PN = "CD59"  !CDS_PN = "CD59";
"VSS_CD61":   PN = "CD61"  !CDS_PN = "CD61";
"VSS_CD66":   PN = "CD66"  !CDS_PN = "CD66";
"VSS_CD68":   PN = "CD68"  !CDS_PN = "CD68";
"VSS_CD73":   PN = "CD73"  !CDS_PN = "CD73";
"VSS_CE1":   PN = "CE1"  !CDS_PN = "CE1";
"VSS_CE4":   PN = "CE4"  !CDS_PN = "CE4";
"VSS_CE6":   PN = "CE6"  !CDS_PN = "CE6";
"VSS_CE8":   PN = "CE8"  !CDS_PN = "CE8";
"VSS_CE11":   PN = "CE11"  !CDS_PN = "CE11";
"VSS_CE13":   PN = "CE13"  !CDS_PN = "CE13";
"VSS_CE15":   PN = "CE15"  !CDS_PN = "CE15";
"VSS_CE18":   PN = "CE18"  !CDS_PN = "CE18";
"VSS_CE20":   PN = "CE20"  !CDS_PN = "CE20";
"VSS_CE22":   PN = "CE22"  !CDS_PN = "CE22";
"VSS_CE25":   PN = "CE25"  !CDS_PN = "CE25";
"VSS_CE28":   PN = "CE28"  !CDS_PN = "CE28";
"VSS_CE31":   PN = "CE31"  !CDS_PN = "CE31";
"VSS_CE34":   PN = "CE34"  !CDS_PN = "CE34";
"VSS_CE35":   PN = "CE35"  !CDS_PN = "CE35";
"VSS_CE36":   PN = "CE36"  !CDS_PN = "CE36";
"VSS_CE40":   PN = "CE40"  !CDS_PN = "CE40";
"VSS_CE41":   PN = "CE41"  !CDS_PN = "CE41";
"VSS_CE42":   PN = "CE42"  !CDS_PN = "CE42";
"VSS_CE45":   PN = "CE45"  !CDS_PN = "CE45";
"VSS_CE48":   PN = "CE48"  !CDS_PN = "CE48";
"VSS_CE51":   PN = "CE51"  !CDS_PN = "CE51";
"VSS_CE54":   PN = "CE54"  !CDS_PN = "CE54";
"VSS_CE56":   PN = "CE56"  !CDS_PN = "CE56";
"VSS_CE58":   PN = "CE58"  !CDS_PN = "CE58";
"VSS_CE61":   PN = "CE61"  !CDS_PN = "CE61";
"VSS_CE63":   PN = "CE63"  !CDS_PN = "CE63";
"VSS_CE65":   PN = "CE65"  !CDS_PN = "CE65";
"VSS_CE68":   PN = "CE68"  !CDS_PN = "CE68";
"VSS_CE70":   PN = "CE70"  !CDS_PN = "CE70";
"VSS_CE72":   PN = "CE72"  !CDS_PN = "CE72";
"VSS_CE75":   PN = "CE75"  !CDS_PN = "CE75";
"VSS_CF3":   PN = "CF3"  !CDS_PN = "CF3";
"VSS_CF5":   PN = "CF5"  !CDS_PN = "CF5";
"VSS_CF8":   PN = "CF8"  !CDS_PN = "CF8";
"VSS_CF10":   PN = "CF10"  !CDS_PN = "CF10";
"VSS_CF12":   PN = "CF12"  !CDS_PN = "CF12";
"VSS_CF15":   PN = "CF15"  !CDS_PN = "CF15";
"VSS_CF17":   PN = "CF17"  !CDS_PN = "CF17";
"VSS_CF19":   PN = "CF19"  !CDS_PN = "CF19";
"VSS_CF23":   PN = "CF23"  !CDS_PN = "CF23";
"VSS_CF24":   PN = "CF24"  !CDS_PN = "CF24";
"VSS_CF25":   PN = "CF25"  !CDS_PN = "CF25";
"VSS_CF26":   PN = "CF26"  !CDS_PN = "CF26";
"VSS_CF27":   PN = "CF27"  !CDS_PN = "CF27";
"VSS_CF28":   PN = "CF28"  !CDS_PN = "CF28";
"VSS_CF29":   PN = "CF29"  !CDS_PN = "CF29";
"VSS_CF30":   PN = "CF30"  !CDS_PN = "CF30";
"VSS_CF31":   PN = "CF31"  !CDS_PN = "CF31";
"VSS_CF32":   PN = "CF32"  !CDS_PN = "CF32";
"VSS_CF33":   PN = "CF33"  !CDS_PN = "CF33";
BODY = "GENOA_SP5","I15": #LOCATION = "U25" !CDS_LOCATION = "U25" &SEC = "38" #&CDS_SEC = "38";
"VSS_CF34":   PN = "CF34"  !CDS_PN = "CF34";
"VSS_CF37":   PN = "CF37"  !CDS_PN = "CF37";
"VSS_CF39":   PN = "CF39"  !CDS_PN = "CF39";
"VSS_CF42":   PN = "CF42"  !CDS_PN = "CF42";
"VSS_CF43":   PN = "CF43"  !CDS_PN = "CF43";
"VSS_CF44":   PN = "CF44"  !CDS_PN = "CF44";
"VSS_CF45":   PN = "CF45"  !CDS_PN = "CF45";
"VSS_CF47":   PN = "CF47"  !CDS_PN = "CF47";
"VSS_CF48":   PN = "CF48"  !CDS_PN = "CF48";
"VSS_CF49":   PN = "CF49"  !CDS_PN = "CF49";
"VSS_CF50":   PN = "CF50"  !CDS_PN = "CF50";
"VSS_CF51":   PN = "CF51"  !CDS_PN = "CF51";
"VSS_CF52":   PN = "CF52"  !CDS_PN = "CF52";
"VSS_CF53":   PN = "CF53"  !CDS_PN = "CF53";
"VSS_CF57":   PN = "CF57"  !CDS_PN = "CF57";
"VSS_CF59":   PN = "CF59"  !CDS_PN = "CF59";
"VSS_CF61":   PN = "CF61"  !CDS_PN = "CF61";
"VSS_CF64":   PN = "CF64"  !CDS_PN = "CF64";
"VSS_CF66":   PN = "CF66"  !CDS_PN = "CF66";
"VSS_CF68":   PN = "CF68"  !CDS_PN = "CF68";
"VSS_CF71":   PN = "CF71"  !CDS_PN = "CF71";
"VSS_CF73":   PN = "CF73"  !CDS_PN = "CF73";
"VSS_CG1":   PN = "CG1"  !CDS_PN = "CG1";
"VSS_CG6":   PN = "CG6"  !CDS_PN = "CG6";
"VSS_CG8":   PN = "CG8"  !CDS_PN = "CG8";
"VSS_CG13":   PN = "CG13"  !CDS_PN = "CG13";
"VSS_CG15":   PN = "CG15"  !CDS_PN = "CG15";
"VSS_CG20":   PN = "CG20"  !CDS_PN = "CG20";
"VSS_CG22":   PN = "CG22"  !CDS_PN = "CG22";
"VSS_CG25":   PN = "CG25"  !CDS_PN = "CG25";
"VSS_CG28":   PN = "CG28"  !CDS_PN = "CG28";
"VSS_CG31":   PN = "CG31"  !CDS_PN = "CG31";
"VSS_CG34":   PN = "CG34"  !CDS_PN = "CG34";
"VSS_CG45":   PN = "CG45"  !CDS_PN = "CG45";
"VSS_CG48":   PN = "CG48"  !CDS_PN = "CG48";
"VSS_CG51":   PN = "CG51"  !CDS_PN = "CG51";
"VSS_CG54":   PN = "CG54"  !CDS_PN = "CG54";
"VSS_CG56":   PN = "CG56"  !CDS_PN = "CG56";
"VSS_CG61":   PN = "CG61"  !CDS_PN = "CG61";
"VSS_CG63":   PN = "CG63"  !CDS_PN = "CG63";
"VSS_CG68":   PN = "CG68"  !CDS_PN = "CG68";
"VSS_CG70":   PN = "CG70"  !CDS_PN = "CG70";
"VSS_CG75":   PN = "CG75"  !CDS_PN = "CG75";
"VSS_CH3":   PN = "CH3"  !CDS_PN = "CH3";
"VSS_CH5":   PN = "CH5"  !CDS_PN = "CH5";
"VSS_CH8":   PN = "CH8"  !CDS_PN = "CH8";
"VSS_CH10":   PN = "CH10"  !CDS_PN = "CH10";
"VSS_CH12":   PN = "CH12"  !CDS_PN = "CH12";
"VSS_CH15":   PN = "CH15"  !CDS_PN = "CH15";
"VSS_CH17":   PN = "CH17"  !CDS_PN = "CH17";
"VSS_CH19":   PN = "CH19"  !CDS_PN = "CH19";
"VSS_CH22":   PN = "CH22"  !CDS_PN = "CH22";
"VSS_CH25":   PN = "CH25"  !CDS_PN = "CH25";
"VSS_CH28":   PN = "CH28"  !CDS_PN = "CH28";
"VSS_CH31":   PN = "CH31"  !CDS_PN = "CH31";
"VSS_CH34":   PN = "CH34"  !CDS_PN = "CH34";
"VSS_CH37":   PN = "CH37"  !CDS_PN = "CH37";
"VSS_CH39":   PN = "CH39"  !CDS_PN = "CH39";
"VSS_CH42":   PN = "CH42"  !CDS_PN = "CH42";
"VSS_CH45":   PN = "CH45"  !CDS_PN = "CH45";
"VSS_CH48":   PN = "CH48"  !CDS_PN = "CH48";
"VSS_CH51":   PN = "CH51"  !CDS_PN = "CH51";
"VSS_CH54":   PN = "CH54"  !CDS_PN = "CH54";
"VSS_CH57":   PN = "CH57"  !CDS_PN = "CH57";
"VSS_CH59":   PN = "CH59"  !CDS_PN = "CH59";
"VSS_CH61":   PN = "CH61"  !CDS_PN = "CH61";
"VSS_CH64":   PN = "CH64"  !CDS_PN = "CH64";
"VSS_CH66":   PN = "CH66"  !CDS_PN = "CH66";
"VSS_CH68":   PN = "CH68"  !CDS_PN = "CH68";
"VSS_CH71":   PN = "CH71"  !CDS_PN = "CH71";
"VSS_CH73":   PN = "CH73"  !CDS_PN = "CH73";
"VSS_CJ1":   PN = "CJ1"  !CDS_PN = "CJ1";
"VSS_CJ4":   PN = "CJ4"  !CDS_PN = "CJ4";
"VSS_CJ6":   PN = "CJ6"  !CDS_PN = "CJ6";
"VSS_CJ8":   PN = "CJ8"  !CDS_PN = "CJ8";
"VSS_CJ11":   PN = "CJ11"  !CDS_PN = "CJ11";
"VSS_CJ13":   PN = "CJ13"  !CDS_PN = "CJ13";
"VSS_CJ15":   PN = "CJ15"  !CDS_PN = "CJ15";
"VSS_CJ18":   PN = "CJ18"  !CDS_PN = "CJ18";
"VSS_CJ20":   PN = "CJ20"  !CDS_PN = "CJ20";
"VSS_CJ23":   PN = "CJ23"  !CDS_PN = "CJ23";
"VSS_CJ31":   PN = "CJ31"  !CDS_PN = "CJ31";
"VSS_CJ34":   PN = "CJ34"  !CDS_PN = "CJ34";
"VSS_CJ35":   PN = "CJ35"  !CDS_PN = "CJ35";
"VSS_CJ36":   PN = "CJ36"  !CDS_PN = "CJ36";
"VSS_CJ40":   PN = "CJ40"  !CDS_PN = "CJ40";
"VSS_CJ41":   PN = "CJ41"  !CDS_PN = "CJ41";
"VSS_CJ42":   PN = "CJ42"  !CDS_PN = "CJ42";
"VSS_CJ45":   PN = "CJ45"  !CDS_PN = "CJ45";
"VSS_CJ56":   PN = "CJ56"  !CDS_PN = "CJ56";
"VSS_CJ58":   PN = "CJ58"  !CDS_PN = "CJ58";
"VSS_CJ61":   PN = "CJ61"  !CDS_PN = "CJ61";
"VSS_CJ63":   PN = "CJ63"  !CDS_PN = "CJ63";
"VSS_CJ65":   PN = "CJ65"  !CDS_PN = "CJ65";
"VSS_CJ68":   PN = "CJ68"  !CDS_PN = "CJ68";
"VSS_CJ70":   PN = "CJ70"  !CDS_PN = "CJ70";
"VSS_CJ72":   PN = "CJ72"  !CDS_PN = "CJ72";
"VSS_CJ75":   PN = "CJ75"  !CDS_PN = "CJ75";
"VSS_CK3":   PN = "CK3"  !CDS_PN = "CK3";
"VSS_CK8":   PN = "CK8"  !CDS_PN = "CK8";
"VSS_CK15":   PN = "CK15"  !CDS_PN = "CK15";
"VSS_CK17":   PN = "CK17"  !CDS_PN = "CK17";
"VSS_CK22":   PN = "CK22"  !CDS_PN = "CK22";
"VSS_CK23":   PN = "CK23"  !CDS_PN = "CK23";
"VSS_CK24":   PN = "CK24"  !CDS_PN = "CK24";
"VSS_CK25":   PN = "CK25"  !CDS_PN = "CK25";
"VSS_CK26":   PN = "CK26"  !CDS_PN = "CK26";
"VSS_CK27":   PN = "CK27"  !CDS_PN = "CK27";
"VSS_CK28":   PN = "CK28"  !CDS_PN = "CK28";
"VSS_CK32":   PN = "CK32"  !CDS_PN = "CK32";
"VSS_CK33":   PN = "CK33"  !CDS_PN = "CK33";
"VSS_CK34":   PN = "CK34"  !CDS_PN = "CK34";
"VSS_CK37":   PN = "CK37"  !CDS_PN = "CK37";
"VSS_CK39":   PN = "CK39"  !CDS_PN = "CK39";
"VSS_CK42":   PN = "CK42"  !CDS_PN = "CK42";
"VSS_CK43":   PN = "CK43"  !CDS_PN = "CK43";
"VSS_CK44":   PN = "CK44"  !CDS_PN = "CK44";
"VSS_CK45":   PN = "CK45"  !CDS_PN = "CK45";
"VSS_CK48":   PN = "CK48"  !CDS_PN = "CK48";
"VSS_CK49":   PN = "CK49"  !CDS_PN = "CK49";
"VSS_CK50":   PN = "CK50"  !CDS_PN = "CK50";
"VSS_CK51":   PN = "CK51"  !CDS_PN = "CK51";
"VSS_CK52":   PN = "CK52"  !CDS_PN = "CK52";
"VSS_CK53":   PN = "CK53"  !CDS_PN = "CK53";
"VSS_CK54":   PN = "CK54"  !CDS_PN = "CK54";
"VSS_CK59":   PN = "CK59"  !CDS_PN = "CK59";
"VSS_CK61":   PN = "CK61"  !CDS_PN = "CK61";
"VSS_CK66":   PN = "CK66"  !CDS_PN = "CK66";
"VSS_CK68":   PN = "CK68"  !CDS_PN = "CK68";
"VSS_CK73":   PN = "CK73"  !CDS_PN = "CK73";
"VSS_CL1":   PN = "CL1"  !CDS_PN = "CL1";
"VSS_CL4":   PN = "CL4"  !CDS_PN = "CL4";
"VSS_CL6":   PN = "CL6"  !CDS_PN = "CL6";
"VSS_CL8":   PN = "CL8"  !CDS_PN = "CL8";
"VSS_CL11":   PN = "CL11"  !CDS_PN = "CL11";
"VSS_CL13":   PN = "CL13"  !CDS_PN = "CL13";
"VSS_CL15":   PN = "CL15"  !CDS_PN = "CL15";
"VSS_CL18":   PN = "CL18"  !CDS_PN = "CL18";
"VSS_CL20":   PN = "CL20"  !CDS_PN = "CL20";
"VSS_CL22":   PN = "CL22"  !CDS_PN = "CL22";
"VSS_CL25":   PN = "CL25"  !CDS_PN = "CL25";
"VSS_CL28":   PN = "CL28"  !CDS_PN = "CL28";
"VSS_CL31":   PN = "CL31"  !CDS_PN = "CL31";
"VSS_CL34":   PN = "CL34"  !CDS_PN = "CL34";
"VSS_CL35":   PN = "CL35"  !CDS_PN = "CL35";
"VSS_CL36":   PN = "CL36"  !CDS_PN = "CL36";
"VSS_CL40":   PN = "CL40"  !CDS_PN = "CL40";
"VSS_CL41":   PN = "CL41"  !CDS_PN = "CL41";
"VSS_CL42":   PN = "CL42"  !CDS_PN = "CL42";
"VSS_CL45":   PN = "CL45"  !CDS_PN = "CL45";
"VSS_CL48":   PN = "CL48"  !CDS_PN = "CL48";
"VSS_CL51":   PN = "CL51"  !CDS_PN = "CL51";
"VSS_CL54":   PN = "CL54"  !CDS_PN = "CL54";
"VSS_CL56":   PN = "CL56"  !CDS_PN = "CL56";
"VSS_CL58":   PN = "CL58"  !CDS_PN = "CL58";
"VSS_CL61":   PN = "CL61"  !CDS_PN = "CL61";
"VSS_CL63":   PN = "CL63"  !CDS_PN = "CL63";
"VSS_CL65":   PN = "CL65"  !CDS_PN = "CL65";
"VSS_CL68":   PN = "CL68"  !CDS_PN = "CL68";
"VSS_CL70":   PN = "CL70"  !CDS_PN = "CL70";
"VSS_CL72":   PN = "CL72"  !CDS_PN = "CL72";
"VSS_CL75":   PN = "CL75"  !CDS_PN = "CL75";
"VSS_CM3":   PN = "CM3"  !CDS_PN = "CM3";
"VSS_CM5":   PN = "CM5"  !CDS_PN = "CM5";
"VSS_CM8":   PN = "CM8"  !CDS_PN = "CM8";
"VSS_CM10":   PN = "CM10"  !CDS_PN = "CM10";
"VSS_CM12":   PN = "CM12"  !CDS_PN = "CM12";
"VSS_CM15":   PN = "CM15"  !CDS_PN = "CM15";
"VSS_CM17":   PN = "CM17"  !CDS_PN = "CM17";
"VSS_CM19":   PN = "CM19"  !CDS_PN = "CM19";
"VSS_CM23":   PN = "CM23"  !CDS_PN = "CM23";
"VSS_CM24":   PN = "CM24"  !CDS_PN = "CM24";
"VSS_CM25":   PN = "CM25"  !CDS_PN = "CM25";
"VSS_CM26":   PN = "CM26"  !CDS_PN = "CM26";
"VSS_CM27":   PN = "CM27"  !CDS_PN = "CM27";
"VSS_CM28":   PN = "CM28"  !CDS_PN = "CM28";
"VSS_CM29":   PN = "CM29"  !CDS_PN = "CM29";
"VSS_CM30":   PN = "CM30"  !CDS_PN = "CM30";
"VSS_CM31":   PN = "CM31"  !CDS_PN = "CM31";
"VSS_CM32":   PN = "CM32"  !CDS_PN = "CM32";
"VSS_CM33":   PN = "CM33"  !CDS_PN = "CM33";
"VSS_CM34":   PN = "CM34"  !CDS_PN = "CM34";
"VSS_CM37":   PN = "CM37"  !CDS_PN = "CM37";
"VSS_CM39":   PN = "CM39"  !CDS_PN = "CM39";
"VSS_CM42":   PN = "CM42"  !CDS_PN = "CM42";
"VSS_CM43":   PN = "CM43"  !CDS_PN = "CM43";
"VSS_CM44":   PN = "CM44"  !CDS_PN = "CM44";
"VSS_CM45":   PN = "CM45"  !CDS_PN = "CM45";
"VSS_CM46":   PN = "CM46"  !CDS_PN = "CM46";
"VSS_CM47":   PN = "CM47"  !CDS_PN = "CM47";
"VSS_CM48":   PN = "CM48"  !CDS_PN = "CM48";
"VSS_CM49":   PN = "CM49"  !CDS_PN = "CM49";
"VSS_CM51":   PN = "CM51"  !CDS_PN = "CM51";
"VSS_CM52":   PN = "CM52"  !CDS_PN = "CM52";
"VSS_CM53":   PN = "CM53"  !CDS_PN = "CM53";
"VSS_CM57":   PN = "CM57"  !CDS_PN = "CM57";
"VSS_CM59":   PN = "CM59"  !CDS_PN = "CM59";
"VSS_CM61":   PN = "CM61"  !CDS_PN = "CM61";
"VSS_CM64":   PN = "CM64"  !CDS_PN = "CM64";
"VSS_CM66":   PN = "CM66"  !CDS_PN = "CM66";
"VSS_CM68":   PN = "CM68"  !CDS_PN = "CM68";
"VSS_CM71":   PN = "CM71"  !CDS_PN = "CM71";
"VSS_CM73":   PN = "CM73"  !CDS_PN = "CM73";
"VSS_CN1":   PN = "CN1"  !CDS_PN = "CN1";
"VSS_CN6":   PN = "CN6"  !CDS_PN = "CN6";
"VSS_CN8":   PN = "CN8"  !CDS_PN = "CN8";
"VSS_CN13":   PN = "CN13"  !CDS_PN = "CN13";
"VSS_CN15":   PN = "CN15"  !CDS_PN = "CN15";
"VSS_CN20":   PN = "CN20"  !CDS_PN = "CN20";
"VSS_CN22":   PN = "CN22"  !CDS_PN = "CN22";
"VSS_CN25":   PN = "CN25"  !CDS_PN = "CN25";
"VSS_CN28":   PN = "CN28"  !CDS_PN = "CN28";
"VSS_CN31":   PN = "CN31"  !CDS_PN = "CN31";
"VSS_CN34":   PN = "CN34"  !CDS_PN = "CN34";
"VSS_CN42":   PN = "CN42"  !CDS_PN = "CN42";
"VSS_CN45":   PN = "CN45"  !CDS_PN = "CN45";
"VSS_CN48":   PN = "CN48"  !CDS_PN = "CN48";
"VSS_CN51":   PN = "CN51"  !CDS_PN = "CN51";
"VSS_CN56":   PN = "CN56"  !CDS_PN = "CN56";
"VSS_CN61":   PN = "CN61"  !CDS_PN = "CN61";
"VSS_CN63":   PN = "CN63"  !CDS_PN = "CN63";
"VSS_CN68":   PN = "CN68"  !CDS_PN = "CN68";
"VSS_CN70":   PN = "CN70"  !CDS_PN = "CN70";
"VSS_CN75":   PN = "CN75"  !CDS_PN = "CN75";
"VSS_CP3":   PN = "CP3"  !CDS_PN = "CP3";
"VSS_CP5":   PN = "CP5"  !CDS_PN = "CP5";
"VSS_CP8":   PN = "CP8"  !CDS_PN = "CP8";
"VSS_CP10":   PN = "CP10"  !CDS_PN = "CP10";
"VSS_CP12":   PN = "CP12"  !CDS_PN = "CP12";
"VSS_CP15":   PN = "CP15"  !CDS_PN = "CP15";
"VSS_CP17":   PN = "CP17"  !CDS_PN = "CP17";
"VSS_CP19":   PN = "CP19"  !CDS_PN = "CP19";
BODY = "GENOA_SP5","I16": #LOCATION = "U25" !CDS_LOCATION = "U25" &SEC = "39" #&CDS_SEC = "39";
"VSS_CP22":   PN = "CP22"  !CDS_PN = "CP22";
"VSS_CP25":   PN = "CP25"  !CDS_PN = "CP25";
"VSS_CP28":   PN = "CP28"  !CDS_PN = "CP28";
"VSS_CP31":   PN = "CP31"  !CDS_PN = "CP31";
"VSS_CP34":   PN = "CP34"  !CDS_PN = "CP34";
"VSS_CP37":   PN = "CP37"  !CDS_PN = "CP37";
"VSS_CP39":   PN = "CP39"  !CDS_PN = "CP39";
"VSS_CP42":   PN = "CP42"  !CDS_PN = "CP42";
"VSS_CP45":   PN = "CP45"  !CDS_PN = "CP45";
"VSS_CP48":   PN = "CP48"  !CDS_PN = "CP48";
"VSS_CP51":   PN = "CP51"  !CDS_PN = "CP51";
"VSS_CP54":   PN = "CP54"  !CDS_PN = "CP54";
"VSS_CP57":   PN = "CP57"  !CDS_PN = "CP57";
"VSS_CP59":   PN = "CP59"  !CDS_PN = "CP59";
"VSS_CP61":   PN = "CP61"  !CDS_PN = "CP61";
"VSS_CP64":   PN = "CP64"  !CDS_PN = "CP64";
"VSS_CP66":   PN = "CP66"  !CDS_PN = "CP66";
"VSS_CP68":   PN = "CP68"  !CDS_PN = "CP68";
"VSS_CP71":   PN = "CP71"  !CDS_PN = "CP71";
"VSS_CP73":   PN = "CP73"  !CDS_PN = "CP73";
"VSS_CR1":   PN = "CR1"  !CDS_PN = "CR1";
"VSS_CR4":   PN = "CR4"  !CDS_PN = "CR4";
"VSS_CR6":   PN = "CR6"  !CDS_PN = "CR6";
"VSS_CR8":   PN = "CR8"  !CDS_PN = "CR8";
"VSS_CR11":   PN = "CR11"  !CDS_PN = "CR11";
"VSS_CR13":   PN = "CR13"  !CDS_PN = "CR13";
"VSS_CR15":   PN = "CR15"  !CDS_PN = "CR15";
"VSS_CR18":   PN = "CR18"  !CDS_PN = "CR18";
"VSS_CR20":   PN = "CR20"  !CDS_PN = "CR20";
"VSS_CR22":   PN = "CR22"  !CDS_PN = "CR22";
"VSS_CR25":   PN = "CR25"  !CDS_PN = "CR25";
"VSS_CR28":   PN = "CR28"  !CDS_PN = "CR28";
"VSS_CR31":   PN = "CR31"  !CDS_PN = "CR31";
"VSS_CR34":   PN = "CR34"  !CDS_PN = "CR34";
"VSS_CR35":   PN = "CR35"  !CDS_PN = "CR35";
"VSS_CR36":   PN = "CR36"  !CDS_PN = "CR36";
"VSS_CR40":   PN = "CR40"  !CDS_PN = "CR40";
"VSS_CR41":   PN = "CR41"  !CDS_PN = "CR41";
"VSS_CR42":   PN = "CR42"  !CDS_PN = "CR42";
"VSS_CR45":   PN = "CR45"  !CDS_PN = "CR45";
"VSS_CR48":   PN = "CR48"  !CDS_PN = "CR48";
"VSS_CR51":   PN = "CR51"  !CDS_PN = "CR51";
"VSS_CR54":   PN = "CR54"  !CDS_PN = "CR54";
"VSS_CR56":   PN = "CR56"  !CDS_PN = "CR56";
"VSS_CR58":   PN = "CR58"  !CDS_PN = "CR58";
"VSS_CR61":   PN = "CR61"  !CDS_PN = "CR61";
"VSS_CR63":   PN = "CR63"  !CDS_PN = "CR63";
"VSS_CR65":   PN = "CR65"  !CDS_PN = "CR65";
"VSS_CR68":   PN = "CR68"  !CDS_PN = "CR68";
"VSS_CR70":   PN = "CR70"  !CDS_PN = "CR70";
"VSS_CR72":   PN = "CR72"  !CDS_PN = "CR72";
"VSS_CR75":   PN = "CR75"  !CDS_PN = "CR75";
"VSS_CT3":   PN = "CT3"  !CDS_PN = "CT3";
"VSS_CT8":   PN = "CT8"  !CDS_PN = "CT8";
"VSS_CT10":   PN = "CT10"  !CDS_PN = "CT10";
"VSS_CT15":   PN = "CT15"  !CDS_PN = "CT15";
"VSS_CT17":   PN = "CT17"  !CDS_PN = "CT17";
"VSS_CT23":   PN = "CT23"  !CDS_PN = "CT23";
"VSS_CT24":   PN = "CT24"  !CDS_PN = "CT24";
"VSS_CT25":   PN = "CT25"  !CDS_PN = "CT25";
"VSS_CT26":   PN = "CT26"  !CDS_PN = "CT26";
"VSS_CT27":   PN = "CT27"  !CDS_PN = "CT27";
"VSS_CT28":   PN = "CT28"  !CDS_PN = "CT28";
"VSS_CT29":   PN = "CT29"  !CDS_PN = "CT29";
"VSS_CT30":   PN = "CT30"  !CDS_PN = "CT30";
"VSS_CT31":   PN = "CT31"  !CDS_PN = "CT31";
"VSS_CT32":   PN = "CT32"  !CDS_PN = "CT32";
"VSS_CT33":   PN = "CT33"  !CDS_PN = "CT33";
"VSS_CT34":   PN = "CT34"  !CDS_PN = "CT34";
"VSS_CT37":   PN = "CT37"  !CDS_PN = "CT37";
"VSS_CT39":   PN = "CT39"  !CDS_PN = "CT39";
"VSS_CT42":   PN = "CT42"  !CDS_PN = "CT42";
"VSS_CT43":   PN = "CT43"  !CDS_PN = "CT43";
"VSS_CT44":   PN = "CT44"  !CDS_PN = "CT44";
"VSS_CT45":   PN = "CT45"  !CDS_PN = "CT45";
"VSS_CT46":   PN = "CT46"  !CDS_PN = "CT46";
"VSS_CT47":   PN = "CT47"  !CDS_PN = "CT47";
"VSS_CT48":   PN = "CT48"  !CDS_PN = "CT48";
"VSS_CT49":   PN = "CT49"  !CDS_PN = "CT49";
"VSS_CT50":   PN = "CT50"  !CDS_PN = "CT50";
"VSS_CT51":   PN = "CT51"  !CDS_PN = "CT51";
"VSS_CT53":   PN = "CT53"  !CDS_PN = "CT53";
"VSS_CT59":   PN = "CT59"  !CDS_PN = "CT59";
"VSS_CT61":   PN = "CT61"  !CDS_PN = "CT61";
"VSS_CT66":   PN = "CT66"  !CDS_PN = "CT66";
"VSS_CT68":   PN = "CT68"  !CDS_PN = "CT68";
"VSS_CT73":   PN = "CT73"  !CDS_PN = "CT73";
"VSS_CU1":   PN = "CU1"  !CDS_PN = "CU1";
"VSS_CU4":   PN = "CU4"  !CDS_PN = "CU4";
"VSS_CU6":   PN = "CU6"  !CDS_PN = "CU6";
"VSS_CU8":   PN = "CU8"  !CDS_PN = "CU8";
"VSS_CU11":   PN = "CU11"  !CDS_PN = "CU11";
"VSS_CU13":   PN = "CU13"  !CDS_PN = "CU13";
"VSS_CU15":   PN = "CU15"  !CDS_PN = "CU15";
"VSS_CU18":   PN = "CU18"  !CDS_PN = "CU18";
"VSS_CU20":   PN = "CU20"  !CDS_PN = "CU20";
"VSS_CU22":   PN = "CU22"  !CDS_PN = "CU22";
"VSS_CU25":   PN = "CU25"  !CDS_PN = "CU25";
"VSS_CU28":   PN = "CU28"  !CDS_PN = "CU28";
"VSS_CU31":   PN = "CU31"  !CDS_PN = "CU31";
"VSS_CU34":   PN = "CU34"  !CDS_PN = "CU34";
"VSS_CU42":   PN = "CU42"  !CDS_PN = "CU42";
"VSS_CU45":   PN = "CU45"  !CDS_PN = "CU45";
"VSS_CU48":   PN = "CU48"  !CDS_PN = "CU48";
"VSS_CU51":   PN = "CU51"  !CDS_PN = "CU51";
"VSS_CU54":   PN = "CU54"  !CDS_PN = "CU54";
"VSS_CU56":   PN = "CU56"  !CDS_PN = "CU56";
"VSS_CU61":   PN = "CU61"  !CDS_PN = "CU61";
"VSS_CU63":   PN = "CU63"  !CDS_PN = "CU63";
"VSS_CU65":   PN = "CU65"  !CDS_PN = "CU65";
"VSS_CU68":   PN = "CU68"  !CDS_PN = "CU68";
"VSS_CU70":   PN = "CU70"  !CDS_PN = "CU70";
"VSS_CU72":   PN = "CU72"  !CDS_PN = "CU72";
"VSS_CU75":   PN = "CU75"  !CDS_PN = "CU75";
"VSS_CV3":   PN = "CV3"  !CDS_PN = "CV3";
"VSS_CV5":   PN = "CV5"  !CDS_PN = "CV5";
"VSS_CV8":   PN = "CV8"  !CDS_PN = "CV8";
"VSS_CV10":   PN = "CV10"  !CDS_PN = "CV10";
"VSS_CV12":   PN = "CV12"  !CDS_PN = "CV12";
"VSS_CV15":   PN = "CV15"  !CDS_PN = "CV15";
"VSS_CV17":   PN = "CV17"  !CDS_PN = "CV17";
"VSS_CV19":   PN = "CV19"  !CDS_PN = "CV19";
"VSS_CV22":   PN = "CV22"  !CDS_PN = "CV22";
"VSS_CV25":   PN = "CV25"  !CDS_PN = "CV25";
"VSS_CV28":   PN = "CV28"  !CDS_PN = "CV28";
"VSS_CV31":   PN = "CV31"  !CDS_PN = "CV31";
"VSS_CV34":   PN = "CV34"  !CDS_PN = "CV34";
"VSS_CV37":   PN = "CV37"  !CDS_PN = "CV37";
"VSS_CV39":   PN = "CV39"  !CDS_PN = "CV39";
"VSS_CV42":   PN = "CV42"  !CDS_PN = "CV42";
"VSS_CV45":   PN = "CV45"  !CDS_PN = "CV45";
"VSS_CV48":   PN = "CV48"  !CDS_PN = "CV48";
"VSS_CV51":   PN = "CV51"  !CDS_PN = "CV51";
"VSS_CV54":   PN = "CV54"  !CDS_PN = "CV54";
"VSS_CV57":   PN = "CV57"  !CDS_PN = "CV57";
"VSS_CV59":   PN = "CV59"  !CDS_PN = "CV59";
"VSS_CV61":   PN = "CV61"  !CDS_PN = "CV61";
"VSS_CV64":   PN = "CV64"  !CDS_PN = "CV64";
"VSS_CV66":   PN = "CV66"  !CDS_PN = "CV66";
"VSS_CV68":   PN = "CV68"  !CDS_PN = "CV68";
"VSS_CV71":   PN = "CV71"  !CDS_PN = "CV71";
"VSS_CV73":   PN = "CV73"  !CDS_PN = "CV73";
"VSS_CW1":   PN = "CW1"  !CDS_PN = "CW1";
"VSS_CW6":   PN = "CW6"  !CDS_PN = "CW6";
"VSS_CW8":   PN = "CW8"  !CDS_PN = "CW8";
"VSS_CW13":   PN = "CW13"  !CDS_PN = "CW13";
"VSS_CW15":   PN = "CW15"  !CDS_PN = "CW15";
"VSS_CW20":   PN = "CW20"  !CDS_PN = "CW20";
"VSS_CW22":   PN = "CW22"  !CDS_PN = "CW22";
"VSS_CW25":   PN = "CW25"  !CDS_PN = "CW25";
"VSS_CW28":   PN = "CW28"  !CDS_PN = "CW28";
"VSS_CW31":   PN = "CW31"  !CDS_PN = "CW31";
"VSS_CW34":   PN = "CW34"  !CDS_PN = "CW34";
"VSS_CW35":   PN = "CW35"  !CDS_PN = "CW35";
"VSS_CW36":   PN = "CW36"  !CDS_PN = "CW36";
"VSS_CW40":   PN = "CW40"  !CDS_PN = "CW40";
"VSS_CW41":   PN = "CW41"  !CDS_PN = "CW41";
"VSS_CW42":   PN = "CW42"  !CDS_PN = "CW42";
"VSS_CW45":   PN = "CW45"  !CDS_PN = "CW45";
"VSS_CW48":   PN = "CW48"  !CDS_PN = "CW48";
"VSS_CW51":   PN = "CW51"  !CDS_PN = "CW51";
"VSS_CW54":   PN = "CW54"  !CDS_PN = "CW54";
"VSS_CW56":   PN = "CW56"  !CDS_PN = "CW56";
"VSS_CW61":   PN = "CW61"  !CDS_PN = "CW61";
"VSS_CW63":   PN = "CW63"  !CDS_PN = "CW63";
"VSS_CW68":   PN = "CW68"  !CDS_PN = "CW68";
"VSS_CW70":   PN = "CW70"  !CDS_PN = "CW70";
"VSS_CW75":   PN = "CW75"  !CDS_PN = "CW75";
"VSS_CY3":   PN = "CY3"  !CDS_PN = "CY3";
"VSS_CY5":   PN = "CY5"  !CDS_PN = "CY5";
"VSS_CY8":   PN = "CY8"  !CDS_PN = "CY8";
"VSS_CY10":   PN = "CY10"  !CDS_PN = "CY10";
"VSS_CY12":   PN = "CY12"  !CDS_PN = "CY12";
"VSS_CY15":   PN = "CY15"  !CDS_PN = "CY15";
"VSS_CY17":   PN = "CY17"  !CDS_PN = "CY17";
"VSS_CY19":   PN = "CY19"  !CDS_PN = "CY19";
"VSS_CY23":   PN = "CY23"  !CDS_PN = "CY23";
"VSS_CY24":   PN = "CY24"  !CDS_PN = "CY24";
"VSS_CY25":   PN = "CY25"  !CDS_PN = "CY25";
"VSS_CY26":   PN = "CY26"  !CDS_PN = "CY26";
"VSS_CY27":   PN = "CY27"  !CDS_PN = "CY27";
"VSS_CY28":   PN = "CY28"  !CDS_PN = "CY28";
"VSS_CY29":   PN = "CY29"  !CDS_PN = "CY29";
"VSS_CY30":   PN = "CY30"  !CDS_PN = "CY30";
"VSS_CY31":   PN = "CY31"  !CDS_PN = "CY31";
"VSS_CY32":   PN = "CY32"  !CDS_PN = "CY32";
"VSS_CY33":   PN = "CY33"  !CDS_PN = "CY33";
"VSS_CY34":   PN = "CY34"  !CDS_PN = "CY34";
"VSS_CY37":   PN = "CY37"  !CDS_PN = "CY37";
"VSS_CY39":   PN = "CY39"  !CDS_PN = "CY39";
"VSS_CY42":   PN = "CY42"  !CDS_PN = "CY42";
"VSS_CY43":   PN = "CY43"  !CDS_PN = "CY43";
"VSS_CY44":   PN = "CY44"  !CDS_PN = "CY44";
"VSS_CY45":   PN = "CY45"  !CDS_PN = "CY45";
"VSS_CY46":   PN = "CY46"  !CDS_PN = "CY46";
"VSS_CY47":   PN = "CY47"  !CDS_PN = "CY47";
"VSS_CY48":   PN = "CY48"  !CDS_PN = "CY48";
"VSS_CY49":   PN = "CY49"  !CDS_PN = "CY49";
"VSS_CY50":   PN = "CY50"  !CDS_PN = "CY50";
"VSS_CY51":   PN = "CY51"  !CDS_PN = "CY51";
"VSS_CY52":   PN = "CY52"  !CDS_PN = "CY52";
"VSS_CY53":   PN = "CY53"  !CDS_PN = "CY53";
"VSS_CY59":   PN = "CY59"  !CDS_PN = "CY59";
"VSS_CY61":   PN = "CY61"  !CDS_PN = "CY61";
"VSS_CY64":   PN = "CY64"  !CDS_PN = "CY64";
"VSS_CY66":   PN = "CY66"  !CDS_PN = "CY66";
"VSS_CY68":   PN = "CY68"  !CDS_PN = "CY68";
"VSS_CY71":   PN = "CY71"  !CDS_PN = "CY71";
"VSS_CY73":   PN = "CY73"  !CDS_PN = "CY73";
"VSS_DA1":   PN = "DA1"  !CDS_PN = "DA1";
"VSS_DA4":   PN = "DA4"  !CDS_PN = "DA4";
"VSS_DA6":   PN = "DA6"  !CDS_PN = "DA6";
"VSS_DA8":   PN = "DA8"  !CDS_PN = "DA8";
"VSS_DA11":   PN = "DA11"  !CDS_PN = "DA11";
"VSS_DA13":   PN = "DA13"  !CDS_PN = "DA13";
"VSS_DA15":   PN = "DA15"  !CDS_PN = "DA15";
"VSS_DA18":   PN = "DA18"  !CDS_PN = "DA18";
"VSS_DA20":   PN = "DA20"  !CDS_PN = "DA20";
"VSS_DA22":   PN = "DA22"  !CDS_PN = "DA22";
"VSS_DA25":   PN = "DA25"  !CDS_PN = "DA25";
"VSS_DA28":   PN = "DA28"  !CDS_PN = "DA28";
"VSS_DA31":   PN = "DA31"  !CDS_PN = "DA31";
"VSS_DA34":   PN = "DA34"  !CDS_PN = "DA34";
"VSS_DA42":   PN = "DA42"  !CDS_PN = "DA42";
"VSS_DA45":   PN = "DA45"  !CDS_PN = "DA45";
"VSS_DA48":   PN = "DA48"  !CDS_PN = "DA48";
"VSS_DA51":   PN = "DA51"  !CDS_PN = "DA51";
"VSS_DA54":   PN = "DA54"  !CDS_PN = "DA54";
"VSS_DA58":   PN = "DA58"  !CDS_PN = "DA58";
"VSS_DA61":   PN = "DA61"  !CDS_PN = "DA61";
"VSS_DA63":   PN = "DA63"  !CDS_PN = "DA63";
"VSS_DA65":   PN = "DA65"  !CDS_PN = "DA65";
"VSS_DA68":   PN = "DA68"  !CDS_PN = "DA68";
"VSS_DA70":   PN = "DA70"  !CDS_PN = "DA70";
DRAWING = "@t6g_mb_lib.t6g(sch_1):page33";
BODY = "GENOA_SP5","I4": #LOCATION = "U25" !CDS_LOCATION = "U25" &SEC = "40" #&CDS_SEC = "40";
"VSS_AA42":   PN = "AA42"  !CDS_PN = "AA42";
"VSS_AA72":   PN = "AA72"  !CDS_PN = "AA72";
"VSS_AD31":   PN = "AD31"  !CDS_PN = "AD31";
"VSS_AE4":   PN = "AE4"  !CDS_PN = "AE4";
"VSS_AH33":   PN = "AH33"  !CDS_PN = "AH33";
"VSS_AJ13":   PN = "AJ13"  !CDS_PN = "AJ13";
"VSS_AM37":   PN = "AM37"  !CDS_PN = "AM37";
"VSS_AN20":   PN = "AN20"  !CDS_PN = "AN20";
"VSS_BV42":   PN = "BV42"  !CDS_PN = "BV42";
"VSS_BW25":   PN = "BW25"  !CDS_PN = "BW25";
"VSS_CB44":   PN = "CB44"  !CDS_PN = "CB44";
"VSS_CC22":   PN = "CC22"  !CDS_PN = "CC22";
"VSS_CF46":   PN = "CF46"  !CDS_PN = "CF46";
"VSS_CG42":   PN = "CG42"  !CDS_PN = "CG42";
"VSS_CK10":   PN = "CK10"  !CDS_PN = "CK10";
"VSS_CK31":   PN = "CK31"  !CDS_PN = "CK31";
"VSS_CM50":   PN = "CM50"  !CDS_PN = "CM50";
"VSS_CN54":   PN = "CN54"  !CDS_PN = "CN54";
"VSS_CT52":   PN = "CT52"  !CDS_PN = "CT52";
"VSS_CU58":   PN = "CU58"  !CDS_PN = "CU58";
"VSS_CY57":   PN = "CY57"  !CDS_PN = "CY57";
"VSS_DA56":   PN = "DA56"  !CDS_PN = "DA56";
"VSS_DA72":   PN = "DA72"  !CDS_PN = "DA72";
"VSS_DA75":   PN = "DA75"  !CDS_PN = "DA75";
"VSS_DB3":   PN = "DB3"  !CDS_PN = "DB3";
"VSS_DB8":   PN = "DB8"  !CDS_PN = "DB8";
"VSS_DB10":   PN = "DB10"  !CDS_PN = "DB10";
"VSS_DB15":   PN = "DB15"  !CDS_PN = "DB15";
"VSS_DB17":   PN = "DB17"  !CDS_PN = "DB17";
"VSS_DB22":   PN = "DB22"  !CDS_PN = "DB22";
"VSS_DB25":   PN = "DB25"  !CDS_PN = "DB25";
"VSS_DB28":   PN = "DB28"  !CDS_PN = "DB28";
"VSS_DB31":   PN = "DB31"  !CDS_PN = "DB31";
"VSS_DB34":   PN = "DB34"  !CDS_PN = "DB34";
"VSS_DB37":   PN = "DB37"  !CDS_PN = "DB37";
"VSS_DB39":   PN = "DB39"  !CDS_PN = "DB39";
"VSS_DB42":   PN = "DB42"  !CDS_PN = "DB42";
"VSS_DB45":   PN = "DB45"  !CDS_PN = "DB45";
"VSS_DB48":   PN = "DB48"  !CDS_PN = "DB48";
"VSS_DB51":   PN = "DB51"  !CDS_PN = "DB51";
"VSS_DB54":   PN = "DB54"  !CDS_PN = "DB54";
"VSS_DB59":   PN = "DB59"  !CDS_PN = "DB59";
"VSS_DB61":   PN = "DB61"  !CDS_PN = "DB61";
"VSS_DB66":   PN = "DB66"  !CDS_PN = "DB66";
"VSS_DB68":   PN = "DB68"  !CDS_PN = "DB68";
"VSS_DB73":   PN = "DB73"  !CDS_PN = "DB73";
"VSS_DC1":   PN = "DC1"  !CDS_PN = "DC1";
"VSS_DC4":   PN = "DC4"  !CDS_PN = "DC4";
"VSS_DC6":   PN = "DC6"  !CDS_PN = "DC6";
"VSS_DC8":   PN = "DC8"  !CDS_PN = "DC8";
"VSS_DC11":   PN = "DC11"  !CDS_PN = "DC11";
"VSS_DC13":   PN = "DC13"  !CDS_PN = "DC13";
"VSS_DC15":   PN = "DC15"  !CDS_PN = "DC15";
"VSS_DC18":   PN = "DC18"  !CDS_PN = "DC18";
"VSS_DC20":   PN = "DC20"  !CDS_PN = "DC20";
"VSS_DC22":   PN = "DC22"  !CDS_PN = "DC22";
"VSS_DC25":   PN = "DC25"  !CDS_PN = "DC25";
"VSS_DC28":   PN = "DC28"  !CDS_PN = "DC28";
"VSS_DC31":   PN = "DC31"  !CDS_PN = "DC31";
"VSS_DC34":   PN = "DC34"  !CDS_PN = "DC34";
"VSS_DC42":   PN = "DC42"  !CDS_PN = "DC42";
"VSS_DC45":   PN = "DC45"  !CDS_PN = "DC45";
"VSS_DC48":   PN = "DC48"  !CDS_PN = "DC48";
"VSS_DC51":   PN = "DC51"  !CDS_PN = "DC51";
"VSS_DC54":   PN = "DC54"  !CDS_PN = "DC54";
"VSS_DC56":   PN = "DC56"  !CDS_PN = "DC56";
"VSS_DC58":   PN = "DC58"  !CDS_PN = "DC58";
"VSS_DC61":   PN = "DC61"  !CDS_PN = "DC61";
"VSS_DC63":   PN = "DC63"  !CDS_PN = "DC63";
"VSS_DC65":   PN = "DC65"  !CDS_PN = "DC65";
"VSS_DC68":   PN = "DC68"  !CDS_PN = "DC68";
"VSS_DC70":   PN = "DC70"  !CDS_PN = "DC70";
"VSS_DC72":   PN = "DC72"  !CDS_PN = "DC72";
"VSS_DC75":   PN = "DC75"  !CDS_PN = "DC75";
"VSS_DD3":   PN = "DD3"  !CDS_PN = "DD3";
"VSS_DD5":   PN = "DD5"  !CDS_PN = "DD5";
"VSS_DD8":   PN = "DD8"  !CDS_PN = "DD8";
"VSS_DD10":   PN = "DD10"  !CDS_PN = "DD10";
"VSS_DD12":   PN = "DD12"  !CDS_PN = "DD12";
"VSS_DD15":   PN = "DD15"  !CDS_PN = "DD15";
"VSS_DD17":   PN = "DD17"  !CDS_PN = "DD17";
"VSS_DD19":   PN = "DD19"  !CDS_PN = "DD19";
"VSS_DD23":   PN = "DD23"  !CDS_PN = "DD23";
"VSS_DD24":   PN = "DD24"  !CDS_PN = "DD24";
"VSS_DD26":   PN = "DD26"  !CDS_PN = "DD26";
"VSS_DD27":   PN = "DD27"  !CDS_PN = "DD27";
"VSS_DD29":   PN = "DD29"  !CDS_PN = "DD29";
"VSS_DD30":   PN = "DD30"  !CDS_PN = "DD30";
"VSS_DD32":   PN = "DD32"  !CDS_PN = "DD32";
"VSS_DD33":   PN = "DD33"  !CDS_PN = "DD33";
"VSS_DD35":   PN = "DD35"  !CDS_PN = "DD35";
"VSS_DD36":   PN = "DD36"  !CDS_PN = "DD36";
"VSS_DD37":   PN = "DD37"  !CDS_PN = "DD37";
"VSS_DD39":   PN = "DD39"  !CDS_PN = "DD39";
"VSS_DD40":   PN = "DD40"  !CDS_PN = "DD40";
"VSS_DD41":   PN = "DD41"  !CDS_PN = "DD41";
"VSS_DD43":   PN = "DD43"  !CDS_PN = "DD43";
"VSS_DD44":   PN = "DD44"  !CDS_PN = "DD44";
"VSS_DD46":   PN = "DD46"  !CDS_PN = "DD46";
"VSS_DD47":   PN = "DD47"  !CDS_PN = "DD47";
"VSS_DD49":   PN = "DD49"  !CDS_PN = "DD49";
"VSS_DD50":   PN = "DD50"  !CDS_PN = "DD50";
"VSS_DD52":   PN = "DD52"  !CDS_PN = "DD52";
"VSS_DD53":   PN = "DD53"  !CDS_PN = "DD53";
"VSS_DD57":   PN = "DD57"  !CDS_PN = "DD57";
"VSS_DD59":   PN = "DD59"  !CDS_PN = "DD59";
"VSS_DD61":   PN = "DD61"  !CDS_PN = "DD61";
"VSS_DD64":   PN = "DD64"  !CDS_PN = "DD64";
"VSS_DD66":   PN = "DD66"  !CDS_PN = "DD66";
"VSS_DD68":   PN = "DD68"  !CDS_PN = "DD68";
"VSS_DD71":   PN = "DD71"  !CDS_PN = "DD71";
"VSS_DD73":   PN = "DD73"  !CDS_PN = "DD73";
"VSS_DE1":   PN = "DE1"  !CDS_PN = "DE1";
"VSS_DE6":   PN = "DE6"  !CDS_PN = "DE6";
"VSS_DE8":   PN = "DE8"  !CDS_PN = "DE8";
"VSS_DE13":   PN = "DE13"  !CDS_PN = "DE13";
"VSS_DE15":   PN = "DE15"  !CDS_PN = "DE15";
"VSS_DE20":   PN = "DE20"  !CDS_PN = "DE20";
"VSS_DE23":   PN = "DE23"  !CDS_PN = "DE23";
"VSS_DE26":   PN = "DE26"  !CDS_PN = "DE26";
"VSS_DE29":   PN = "DE29"  !CDS_PN = "DE29";
"VSS_DE33":   PN = "DE33"  !CDS_PN = "DE33";
"VSS_DE56":   PN = "DE56"  !CDS_PN = "DE56";
"VSS_DE61":   PN = "DE61"  !CDS_PN = "DE61";
"VSS_DE63":   PN = "DE63"  !CDS_PN = "DE63";
"VSS_DE68":   PN = "DE68"  !CDS_PN = "DE68";
"VSS_DE70":   PN = "DE70"  !CDS_PN = "DE70";
"VSS_DE75":   PN = "DE75"  !CDS_PN = "DE75";
"VSS_DF3":   PN = "DF3"  !CDS_PN = "DF3";
"VSS_DF4":   PN = "DF4"  !CDS_PN = "DF4";
"VSS_DF5":   PN = "DF5"  !CDS_PN = "DF5";
"VSS_DF6":   PN = "DF6"  !CDS_PN = "DF6";
"VSS_DF8":   PN = "DF8"  !CDS_PN = "DF8";
"VSS_DF10":   PN = "DF10"  !CDS_PN = "DF10";
"VSS_DF11":   PN = "DF11"  !CDS_PN = "DF11";
"VSS_DF12":   PN = "DF12"  !CDS_PN = "DF12";
"VSS_DF13":   PN = "DF13"  !CDS_PN = "DF13";
"VSS_DF15":   PN = "DF15"  !CDS_PN = "DF15";
"VSS_DF17":   PN = "DF17"  !CDS_PN = "DF17";
"VSS_DF18":   PN = "DF18"  !CDS_PN = "DF18";
"VSS_DF19":   PN = "DF19"  !CDS_PN = "DF19";
"VSS_DF20":   PN = "DF20"  !CDS_PN = "DF20";
"VSS_DF22":   PN = "DF22"  !CDS_PN = "DF22";
"VSS_DF23":   PN = "DF23"  !CDS_PN = "DF23";
"VSS_DF26":   PN = "DF26"  !CDS_PN = "DF26";
"VSS_DF29":   PN = "DF29"  !CDS_PN = "DF29";
"VSS_DF32":   PN = "DF32"  !CDS_PN = "DF32";
"VSS_DF35":   PN = "DF35"  !CDS_PN = "DF35";
"VSS_DF37":   PN = "DF37"  !CDS_PN = "DF37";
"VSS_DF39":   PN = "DF39"  !CDS_PN = "DF39";
"VSS_DF42":   PN = "DF42"  !CDS_PN = "DF42";
"VSS_DF43":   PN = "DF43"  !CDS_PN = "DF43";
"VSS_DF44":   PN = "DF44"  !CDS_PN = "DF44";
"VSS_DF45":   PN = "DF45"  !CDS_PN = "DF45";
"VSS_DF46":   PN = "DF46"  !CDS_PN = "DF46";
"VSS_DF47":   PN = "DF47"  !CDS_PN = "DF47";
"VSS_DF48":   PN = "DF48"  !CDS_PN = "DF48";
"VSS_DF49":   PN = "DF49"  !CDS_PN = "DF49";
"VSS_DF50":   PN = "DF50"  !CDS_PN = "DF50";
"VSS_DF51":   PN = "DF51"  !CDS_PN = "DF51";
"VSS_DF52":   PN = "DF52"  !CDS_PN = "DF52";
"VSS_DF53":   PN = "DF53"  !CDS_PN = "DF53";
"VSS_DF54":   PN = "DF54"  !CDS_PN = "DF54";
"VSS_DF56":   PN = "DF56"  !CDS_PN = "DF56";
"VSS_DF57":   PN = "DF57"  !CDS_PN = "DF57";
"VSS_DF58":   PN = "DF58"  !CDS_PN = "DF58";
"VSS_DF59":   PN = "DF59"  !CDS_PN = "DF59";
"VSS_DF61":   PN = "DF61"  !CDS_PN = "DF61";
"VSS_DF63":   PN = "DF63"  !CDS_PN = "DF63";
"VSS_DF64":   PN = "DF64"  !CDS_PN = "DF64";
"VSS_DF65":   PN = "DF65"  !CDS_PN = "DF65";
"VSS_DF66":   PN = "DF66"  !CDS_PN = "DF66";
"VSS_DF68":   PN = "DF68"  !CDS_PN = "DF68";
"VSS_DF70":   PN = "DF70"  !CDS_PN = "DF70";
"VSS_DF71":   PN = "DF71"  !CDS_PN = "DF71";
"VSS_DF72":   PN = "DF72"  !CDS_PN = "DF72";
"VSS_DF73":   PN = "DF73"  !CDS_PN = "DF73";
"VSS_DG1":   PN = "DG1"  !CDS_PN = "DG1";
"VSS_DG2":   PN = "DG2"  !CDS_PN = "DG2";
"VSS_DG6":   PN = "DG6"  !CDS_PN = "DG6";
"VSS_DG7":   PN = "DG7"  !CDS_PN = "DG7";
"VSS_DG8":   PN = "DG8"  !CDS_PN = "DG8";
"VSS_DG9":   PN = "DG9"  !CDS_PN = "DG9";
"VSS_DG13":   PN = "DG13"  !CDS_PN = "DG13";
"VSS_DG14":   PN = "DG14"  !CDS_PN = "DG14";
"VSS_DG15":   PN = "DG15"  !CDS_PN = "DG15";
"VSS_DG16":   PN = "DG16"  !CDS_PN = "DG16";
"VSS_DG18":   PN = "DG18"  !CDS_PN = "DG18";
"VSS_DG20":   PN = "DG20"  !CDS_PN = "DG20";
"VSS_DG21":   PN = "DG21"  !CDS_PN = "DG21";
"VSS_DG24":   PN = "DG24"  !CDS_PN = "DG24";
"VSS_DG27":   PN = "DG27"  !CDS_PN = "DG27";
"VSS_DG30":   PN = "DG30"  !CDS_PN = "DG30";
"VSS_DG33":   PN = "DG33"  !CDS_PN = "DG33";
"VSS_DG41":   PN = "DG41"  !CDS_PN = "DG41";
"VSS_DG43":   PN = "DG43"  !CDS_PN = "DG43";
"VSS_DG46":   PN = "DG46"  !CDS_PN = "DG46";
"VSS_DG49":   PN = "DG49"  !CDS_PN = "DG49";
"VSS_DG52":   PN = "DG52"  !CDS_PN = "DG52";
"VSS_DG55":   PN = "DG55"  !CDS_PN = "DG55";
"VSS_DG56":   PN = "DG56"  !CDS_PN = "DG56";
"VSS_DG59":   PN = "DG59"  !CDS_PN = "DG59";
"VSS_DG60":   PN = "DG60"  !CDS_PN = "DG60";
"VSS_DG61":   PN = "DG61"  !CDS_PN = "DG61";
"VSS_DG62":   PN = "DG62"  !CDS_PN = "DG62";
"VSS_DG63":   PN = "DG63"  !CDS_PN = "DG63";
"VSS_DG65":   PN = "DG65"  !CDS_PN = "DG65";
"VSS_DG66":   PN = "DG66"  !CDS_PN = "DG66";
"VSS_DG67":   PN = "DG67"  !CDS_PN = "DG67";
"VSS_DG68":   PN = "DG68"  !CDS_PN = "DG68";
"VSS_DG69":   PN = "DG69"  !CDS_PN = "DG69";
"VSS_DG70":   PN = "DG70"  !CDS_PN = "DG70";
"VSS_DG74":   PN = "DG74"  !CDS_PN = "DG74";
"VSS_DG75":   PN = "DG75"  !CDS_PN = "DG75";
"VSS_DH5":   PN = "DH5"  !CDS_PN = "DH5";
"VSS_DH11":   PN = "DH11"  !CDS_PN = "DH11";
"VSS_DH18":   PN = "DH18"  !CDS_PN = "DH18";
"VSS_DH37":   PN = "DH37"  !CDS_PN = "DH37";
"VSS_DH39":   PN = "DH39"  !CDS_PN = "DH39";
"VSS_DH43":   PN = "DH43"  !CDS_PN = "DH43";
"VSS_DH46":   PN = "DH46"  !CDS_PN = "DH46";
"VSS_DH49":   PN = "DH49"  !CDS_PN = "DH49";
"VSS_DH52":   PN = "DH52"  !CDS_PN = "DH52";
"VSS_DH55":   PN = "DH55"  !CDS_PN = "DH55";
"VSS_DH59":   PN = "DH59"  !CDS_PN = "DH59";
"VSS_DH61":   PN = "DH61"  !CDS_PN = "DH61";
"VSS_DH63":   PN = "DH63"  !CDS_PN = "DH63";
"VSS_DH64":   PN = "DH64"  !CDS_PN = "DH64";
"VSS_DH66":   PN = "DH66"  !CDS_PN = "DH66";
"VSS_DH68":   PN = "DH68"  !CDS_PN = "DH68";
"VSS_DH70":   PN = "DH70"  !CDS_PN = "DH70";
"VSS_DJ7":   PN = "DJ7"  !CDS_PN = "DJ7";
"VSS_DJ15":   PN = "DJ15"  !CDS_PN = "DJ15";
"VSS_DJ19":   PN = "DJ19"  !CDS_PN = "DJ19";
"VSS_DJ43":   PN = "DJ43"  !CDS_PN = "DJ43";
"VSS_DJ49":   PN = "DJ49"  !CDS_PN = "DJ49";
"VSS_DJ59":   PN = "DJ59"  !CDS_PN = "DJ59";
"VSS_DJ61":   PN = "DJ61"  !CDS_PN = "DJ61";
"VSS_DJ63":   PN = "DJ63"  !CDS_PN = "DJ63";
"VSS_DJ66":   PN = "DJ66"  !CDS_PN = "DJ66";
"VSS_DJ68":   PN = "DJ68"  !CDS_PN = "DJ68";
"VSS_DJ73":   PN = "DJ73"  !CDS_PN = "DJ73";
"VSS_K23":   PN = "K23"  !CDS_PN = "K23";
"VSS_K59":   PN = "K59"  !CDS_PN = "K59";
"VSS_P25":   PN = "P25"  !CDS_PN = "P25";
"VSS_P68":   PN = "P68"  !CDS_PN = "P68";
"VSS_V27":   PN = "V27"  !CDS_PN = "V27";
"VSS_V68":   PN = "V68"  !CDS_PN = "V68";
DRAWING = "@t6g_mb_lib.t6g(sch_1):page34";
BODY = "Q_RES","I4": #LOCATION = "R499" !CDS_LOCATION = "R499" &SEC = "1" #&CDS_SEC = "1";
"A":   PN = "1"  !CDS_PN = "1";
"B":   PN = "2"  !CDS_PN = "2";
BODY = "Q_RES","I5": #LOCATION = "R590" !CDS_LOCATION = "R590" &SEC = "1" #&CDS_SEC = "1";
"A":   PN = "1"  !CDS_PN = "1";
"B":   PN = "2"  !CDS_PN = "2";
BODY = "PCA9617ADP","I18": #LOCATION = "U27" !CDS_LOCATION = "U27" &SEC = "1" #&CDS_SEC = "1";
"EN":   PN = "5"  !CDS_PN = "5";
"GND":   PN = "4"  !CDS_PN = "4";
"SCLA":   PN = "2"  !CDS_PN = "2";
"SCLB":   PN = "7"  !CDS_PN = "7";
"SDAA":   PN = "3"  !CDS_PN = "3";
"SDAB":   PN = "6"  !CDS_PN = "6";
"VCCA":   PN = "1"  !CDS_PN = "1";
"VCCB":   PN = "8"  !CDS_PN = "8";
BODY = "Q_CAP","I44": #LOCATION = "C42" !CDS_LOCATION = "C42" &SEC = "1" #&CDS_SEC = "1";
"A":   PN = "1"  !CDS_PN = "1";
"B":   PN = "2"  !CDS_PN = "2";
BODY = "Q_CAP","I47": #LOCATION = "C43" !CDS_LOCATION = "C43" &SEC = "1" #&CDS_SEC = "1";
"A":   PN = "1"  !CDS_PN = "1";
"B":   PN = "2"  !CDS_PN = "2";
BODY = "Q_RES","I53": #LOCATION = "R943" !CDS_LOCATION = "R943" &SEC = "1" #&CDS_SEC = "1";
"A":   PN = "1"  !CDS_PN = "1";
"B":   PN = "2"  !CDS_PN = "2";
BODY = "SN74LVC1G07DBVR","I55": #LOCATION = "U101" !CDS_LOCATION = "U101" &SEC = "1" #&CDS_SEC = "1";
"A":   PN = "2"  !CDS_PN = "2";
"GND":   PN = "3"  !CDS_PN = "3";
"NC":   PN = "1"  !CDS_PN = "1";
"VCC":   PN = "5"  !CDS_PN = "5";
"Y":   PN = "4"  !CDS_PN = "4";
BODY = "Q_CAP","I59": #LOCATION = "C226" !CDS_LOCATION = "C226" &SEC = "1" #&CDS_SEC = "1";
"A":   PN = "1"  !CDS_PN = "1";
"B":   PN = "2"  !CDS_PN = "2";
BODY = "Q_RES","I60": #LOCATION = "R942" !CDS_LOCATION = "R942" &SEC = "1" #&CDS_SEC = "1";
"A":   PN = "1"  !CDS_PN = "1";
"B":   PN = "2"  !CDS_PN = "2";
BODY = "Q_RES","I106": #LOCATION = "R495" !CDS_LOCATION = "R495" &SEC = "1" #&CDS_SEC = "1";
"A":   PN = "1"  !CDS_PN = "1";
"B":   PN = "2"  !CDS_PN = "2";
BODY = "Q_RES","I107": #LOCATION = "R498" !CDS_LOCATION = "R498" &SEC = "1" #&CDS_SEC = "1";
"A":   PN = "1"  !CDS_PN = "1";
"B":   PN = "2"  !CDS_PN = "2";
BODY = "Q_CAP","I124": #LOCATION = "C5000" !CDS_LOCATION = "C5000" &SEC = "1" #&CDS_SEC = "1";
"A":   PN = "1"  !CDS_PN = "1";
"B":   PN = "2"  !CDS_PN = "2";
BODY = "Q_RES","I125": #LOCATION = "R6100" !CDS_LOCATION = "R6100" &SEC = "1" #&CDS_SEC = "1";
"A":   PN = "1"  !CDS_PN = "1";
"B":   PN = "2"  !CDS_PN = "2";
DRAWING = "@t6g_mb_lib.t6g(sch_1):page37";
BODY = "GENOA_SP5","I167": #LOCATION = "U26" !CDS_LOCATION = "U26" &SEC = "1" #&CDS_SEC = "1";
"MA0_CLK_H":   PN = "BC74"  !CDS_PN = "BC74";
"MA0_CLK_L":   PN = "BD74"  !CDS_PN = "BD74";
"MA1_CLK_H":   PN = "BF74"  !CDS_PN = "BF74";
"MA1_CLK_L":   PN = "BG74"  !CDS_PN = "BG74";
"MA_ALERT_L":   PN = "AR74"  !CDS_PN = "AR74";
"MA_RESET_L":   PN = "AT74"  !CDS_PN = "AT74";
"MAA0_CS_L0":   PN = "AV74"  !CDS_PN = "AV74";
"MAA0_CS_L1":   PN = "AW73"  !CDS_PN = "AW73";
"MAA0_RSP_L":   PN = "BN73"  !CDS_PN = "BN73";
"MAA1_CS_L0":   PN = "AU74"  !CDS_PN = "AU74";
"MAA1_CS_L1":   PN = "AV72"  !CDS_PN = "AV72";
"MAA1_RSP_L":   PN = "BP72"  !CDS_PN = "BP72";
"MAA_CA0":   PN = "AW74"  !CDS_PN = "AW74";
"MAA_CA1":   PN = "AY74"  !CDS_PN = "AY74";
"MAA_CA2":   PN = "AY72"  !CDS_PN = "AY72";
"MAA_CA3":   PN = "BA73"  !CDS_PN = "BA73";
"MAA_CA4":   PN = "BA74"  !CDS_PN = "BA74";
"MAA_CA5":   PN = "BB74"  !CDS_PN = "BB74";
"MAA_CA6":   PN = "BB72"  !CDS_PN = "BB72";
"MAA_CHECK0":   PN = "AJ74"  !CDS_PN = "AJ74";
"MAA_CHECK1":   PN = "AK72"  !CDS_PN = "AK72";
"MAA_CHECK2":   PN = "AK74"  !CDS_PN = "AK74";
"MAA_CHECK3":   PN = "AL73"  !CDS_PN = "AL73";
"MAA_CHECK4":   PN = "AN74"  !CDS_PN = "AN74";
"MAA_CHECK5":   PN = "AP72"  !CDS_PN = "AP72";
"MAA_CHECK6":   PN = "AP74"  !CDS_PN = "AP74";
"MAA_CHECK7":   PN = "AR73"  !CDS_PN = "AR73";
"MAA_DATA0":   PN = "E74"  !CDS_PN = "E74";
"MAA_DATA1":   PN = "F72"  !CDS_PN = "F72";
"MAA_DATA2":   PN = "F74"  !CDS_PN = "F74";
"MAA_DATA3":   PN = "G73"  !CDS_PN = "G73";
"MAA_DATA4":   PN = "J74"  !CDS_PN = "J74";
"MAA_DATA5":   PN = "K72"  !CDS_PN = "K72";
"MAA_DATA6":   PN = "K74"  !CDS_PN = "K74";
"MAA_DATA7":   PN = "L73"  !CDS_PN = "L73";
"MAA_DATA8":   PN = "L74"  !CDS_PN = "L74";
"MAA_DATA9":   PN = "M72"  !CDS_PN = "M72";
"MAA_DATA10":   PN = "M74"  !CDS_PN = "M74";
"MAA_DATA11":   PN = "N73"  !CDS_PN = "N73";
"MAA_DATA12":   PN = "R74"  !CDS_PN = "R74";
"MAA_DATA13":   PN = "T72"  !CDS_PN = "T72";
"MAA_DATA14":   PN = "T74"  !CDS_PN = "T74";
"MAA_DATA15":   PN = "U73"  !CDS_PN = "U73";
"MAA_DATA16":   PN = "U74"  !CDS_PN = "U74";
"MAA_DATA17":   PN = "V72"  !CDS_PN = "V72";
"MAA_DATA18":   PN = "V74"  !CDS_PN = "V74";
"MAA_DATA19":   PN = "W73"  !CDS_PN = "W73";
"MAA_DATA20":   PN = "AA74"  !CDS_PN = "AA74";
"MAA_DATA21":   PN = "AB72"  !CDS_PN = "AB72";
"MAA_DATA22":   PN = "AB74"  !CDS_PN = "AB74";
"MAA_DATA23":   PN = "AC73"  !CDS_PN = "AC73";
"MAA_DATA24":   PN = "AC74"  !CDS_PN = "AC74";
"MAA_DATA25":   PN = "AD72"  !CDS_PN = "AD72";
"MAA_DATA26":   PN = "AD74"  !CDS_PN = "AD74";
"MAA_DATA27":   PN = "AE73"  !CDS_PN = "AE73";
"MAA_DATA28":   PN = "AG74"  !CDS_PN = "AG74";
"MAA_DATA29":   PN = "AH72"  !CDS_PN = "AH72";
"MAA_DATA30":   PN = "AH74"  !CDS_PN = "AH74";
"MAA_DATA31":   PN = "AJ73"  !CDS_PN = "AJ73";
"MAA_DQS_H0":   PN = "G74"  !CDS_PN = "G74";
"MAA_DQS_H1":   PN = "N74"  !CDS_PN = "N74";
"MAA_DQS_H2":   PN = "W74"  !CDS_PN = "W74";
"MAA_DQS_H3":   PN = "AE74"  !CDS_PN = "AE74";
"MAA_DQS_H4":   PN = "AL74"  !CDS_PN = "AL74";
"MAA_DQS_H5":   PN = "J73"  !CDS_PN = "J73";
"MAA_DQS_H6":   PN = "R73"  !CDS_PN = "R73";
"MAA_DQS_H7":   PN = "AA73"  !CDS_PN = "AA73";
"MAA_DQS_H8":   PN = "AG73"  !CDS_PN = "AG73";
"MAA_DQS_H9":   PN = "AN73"  !CDS_PN = "AN73";
"MAA_DQS_L0":   PN = "H74"  !CDS_PN = "H74";
"MAA_DQS_L1":   PN = "P74"  !CDS_PN = "P74";
"MAA_DQS_L2":   PN = "Y74"  !CDS_PN = "Y74";
"MAA_DQS_L3":   PN = "AF74"  !CDS_PN = "AF74";
"MAA_DQS_L4":   PN = "AM74"  !CDS_PN = "AM74";
"MAA_DQS_L5":   PN = "H72"  !CDS_PN = "H72";
"MAA_DQS_L6":   PN = "P72"  !CDS_PN = "P72";
"MAA_DQS_L7":   PN = "Y72"  !CDS_PN = "Y72";
"MAA_DQS_L8":   PN = "AF72"  !CDS_PN = "AF72";
"MAA_DQS_L9":   PN = "AM72"  !CDS_PN = "AM72";
"MAA_PAR":   PN = "BC73"  !CDS_PN = "BC73";
"MAB0_CS_L0":   PN = "BM72"  !CDS_PN = "BM72";
"MAB0_CS_L1":   PN = "BN74"  !CDS_PN = "BN74";
"MAB0_RSP_L":   PN = "BP74"  !CDS_PN = "BP74";
"MAB1_CS_L0":   PN = "BL73"  !CDS_PN = "BL73";
"MAB1_CS_L1":   PN = "BM74"  !CDS_PN = "BM74";
"MAB1_RSP_L":   PN = "BR74"  !CDS_PN = "BR74";
"MAB_CA0":   PN = "BG73"  !CDS_PN = "BG73";
"MAB_CA1":   PN = "BH72"  !CDS_PN = "BH72";
"MAB_CA2":   PN = "BH74"  !CDS_PN = "BH74";
"MAB_CA3":   PN = "BJ74"  !CDS_PN = "BJ74";
"MAB_CA4":   PN = "BJ73"  !CDS_PN = "BJ73";
"MAB_CA5":   PN = "BK72"  !CDS_PN = "BK72";
"MAB_CA6":   PN = "BK74"  !CDS_PN = "BK74";
"MAB_CHECK0":   PN = "BY74"  !CDS_PN = "BY74";
"MAB_CHECK1":   PN = "CA73"  !CDS_PN = "CA73";
"MAB_CHECK2":   PN = "CA74"  !CDS_PN = "CA74";
"MAB_CHECK3":   PN = "CB72"  !CDS_PN = "CB72";
"MAB_CHECK4":   PN = "BT74"  !CDS_PN = "BT74";
"MAB_CHECK5":   PN = "BU73"  !CDS_PN = "BU73";
"MAB_CHECK6":   PN = "BU74"  !CDS_PN = "BU74";
"MAB_CHECK7":   PN = "BV72"  !CDS_PN = "BV72";
"MAB_DATA0":   PN = "CB74"  !CDS_PN = "CB74";
"MAB_DATA1":   PN = "CC73"  !CDS_PN = "CC73";
"MAB_DATA2":   PN = "CC74"  !CDS_PN = "CC74";
"MAB_DATA3":   PN = "CD72"  !CDS_PN = "CD72";
"MAB_DATA4":   PN = "CF74"  !CDS_PN = "CF74";
"MAB_DATA5":   PN = "CG73"  !CDS_PN = "CG73";
"MAB_DATA6":   PN = "CG74"  !CDS_PN = "CG74";
"MAB_DATA7":   PN = "CH72"  !CDS_PN = "CH72";
"MAB_DATA8":   PN = "CH74"  !CDS_PN = "CH74";
"MAB_DATA9":   PN = "CJ73"  !CDS_PN = "CJ73";
"MAB_DATA10":   PN = "CJ74"  !CDS_PN = "CJ74";
"MAB_DATA11":   PN = "CK72"  !CDS_PN = "CK72";
"MAB_DATA12":   PN = "CM74"  !CDS_PN = "CM74";
"MAB_DATA13":   PN = "CN73"  !CDS_PN = "CN73";
"MAB_DATA14":   PN = "CN74"  !CDS_PN = "CN74";
"MAB_DATA15":   PN = "CP72"  !CDS_PN = "CP72";
"MAB_DATA16":   PN = "CP74"  !CDS_PN = "CP74";
"MAB_DATA17":   PN = "CR73"  !CDS_PN = "CR73";
"MAB_DATA18":   PN = "CR74"  !CDS_PN = "CR74";
"MAB_DATA19":   PN = "CT72"  !CDS_PN = "CT72";
"MAB_DATA20":   PN = "CV74"  !CDS_PN = "CV74";
"MAB_DATA21":   PN = "CW73"  !CDS_PN = "CW73";
"MAB_DATA22":   PN = "CW74"  !CDS_PN = "CW74";
"MAB_DATA23":   PN = "CY72"  !CDS_PN = "CY72";
"MAB_DATA24":   PN = "CY74"  !CDS_PN = "CY74";
"MAB_DATA25":   PN = "DA73"  !CDS_PN = "DA73";
"MAB_DATA26":   PN = "DA74"  !CDS_PN = "DA74";
"MAB_DATA27":   PN = "DB72"  !CDS_PN = "DB72";
"MAB_DATA28":   PN = "DD74"  !CDS_PN = "DD74";
"MAB_DATA29":   PN = "DE73"  !CDS_PN = "DE73";
"MAB_DATA30":   PN = "DE74"  !CDS_PN = "DE74";
"MAB_DATA31":   PN = "DF74"  !CDS_PN = "DF74";
"MAB_DQS_H0":   PN = "CD74"  !CDS_PN = "CD74";
"MAB_DQS_H1":   PN = "CK74"  !CDS_PN = "CK74";
"MAB_DQS_H2":   PN = "CT74"  !CDS_PN = "CT74";
"MAB_DQS_H3":   PN = "DB74"  !CDS_PN = "DB74";
"MAB_DQS_H4":   PN = "BY72"  !CDS_PN = "BY72";
"MAB_DQS_H5":   PN = "CF72"  !CDS_PN = "CF72";
"MAB_DQS_H6":   PN = "CM72"  !CDS_PN = "CM72";
"MAB_DQS_H7":   PN = "CV72"  !CDS_PN = "CV72";
"MAB_DQS_H8":   PN = "DD72"  !CDS_PN = "DD72";
"MAB_DQS_H9":   PN = "BV74"  !CDS_PN = "BV74";
"MAB_DQS_L0":   PN = "CE74"  !CDS_PN = "CE74";
"MAB_DQS_L1":   PN = "CL74"  !CDS_PN = "CL74";
"MAB_DQS_L2":   PN = "CU74"  !CDS_PN = "CU74";
"MAB_DQS_L3":   PN = "DC74"  !CDS_PN = "DC74";
"MAB_DQS_L4":   PN = "BW73"  !CDS_PN = "BW73";
"MAB_DQS_L5":   PN = "CE73"  !CDS_PN = "CE73";
"MAB_DQS_L6":   PN = "CL73"  !CDS_PN = "CL73";
"MAB_DQS_L7":   PN = "CU73"  !CDS_PN = "CU73";
"MAB_DQS_L8":   PN = "DC73"  !CDS_PN = "DC73";
"MAB_DQS_L9":   PN = "BW74"  !CDS_PN = "BW74";
"MAB_PAR":   PN = "BL74"  !CDS_PN = "BL74";
"TEST39A":   PN = "BF72"  !CDS_PN = "BF72";
"TEST40":   PN = "C60"  !CDS_PN = "C60";
BODY = "Q_RES","I322": #LOCATION = "R500" !CDS_LOCATION = "R500" &SEC = "1" #&CDS_SEC = "1";
"A":   PN = "1"  !CDS_PN = "1";
"B":   PN = "2"  !CDS_PN = "2";
DRAWING = "@t6g_mb_lib.t6g(sch_1):page38";
BODY = "GENOA_SP5","I159": #LOCATION = "U26" !CDS_LOCATION = "U26" &SEC = "2" #&CDS_SEC = "2";
"MB0_CLK_H":   PN = "BC64"  !CDS_PN = "BC64";
"MB0_CLK_L":   PN = "BD63"  !CDS_PN = "BD63";
"MB1_CLK_H":   PN = "BF63"  !CDS_PN = "BF63";
"MB1_CLK_L":   PN = "BG64"  !CDS_PN = "BG64";
"MB_ALERT_L":   PN = "AT62"  !CDS_PN = "AT62";
"MB_RESET_L":   PN = "AU62"  !CDS_PN = "AU62";
"MBA0_CS_L0":   PN = "AV63"  !CDS_PN = "AV63";
"MBA0_CS_L1":   PN = "AW62"  !CDS_PN = "AW62";
"MBA0_RSP_L":   PN = "BN62"  !CDS_PN = "BN62";
"MBA1_CS_L0":   PN = "AU64"  !CDS_PN = "AU64";
"MBA1_CS_L1":   PN = "AV62"  !CDS_PN = "AV62";
"MBA1_RSP_L":   PN = "BP62"  !CDS_PN = "BP62";
"MBA_CA0":   PN = "AW64"  !CDS_PN = "AW64";
"MBA_CA1":   PN = "AY63"  !CDS_PN = "AY63";
"MBA_CA2":   PN = "AY62"  !CDS_PN = "AY62";
"MBA_CA3":   PN = "BA62"  !CDS_PN = "BA62";
"MBA_CA4":   PN = "BA64"  !CDS_PN = "BA64";
"MBA_CA5":   PN = "BB63"  !CDS_PN = "BB63";
"MBA_CA6":   PN = "BB62"  !CDS_PN = "BB62";
"MBA_CHECK0":   PN = "AJ64"  !CDS_PN = "AJ64";
"MBA_CHECK1":   PN = "AK62"  !CDS_PN = "AK62";
"MBA_CHECK2":   PN = "AK63"  !CDS_PN = "AK63";
"MBA_CHECK3":   PN = "AL62"  !CDS_PN = "AL62";
"MBA_CHECK4":   PN = "AN64"  !CDS_PN = "AN64";
"MBA_CHECK5":   PN = "AP62"  !CDS_PN = "AP62";
"MBA_CHECK6":   PN = "AP63"  !CDS_PN = "AP63";
"MBA_CHECK7":   PN = "AR62"  !CDS_PN = "AR62";
"MBA_DATA0":   PN = "E64"  !CDS_PN = "E64";
"MBA_DATA1":   PN = "F62"  !CDS_PN = "F62";
"MBA_DATA2":   PN = "F63"  !CDS_PN = "F63";
"MBA_DATA3":   PN = "G62"  !CDS_PN = "G62";
"MBA_DATA4":   PN = "J64"  !CDS_PN = "J64";
"MBA_DATA5":   PN = "K62"  !CDS_PN = "K62";
"MBA_DATA6":   PN = "K63"  !CDS_PN = "K63";
"MBA_DATA7":   PN = "L62"  !CDS_PN = "L62";
"MBA_DATA8":   PN = "L64"  !CDS_PN = "L64";
"MBA_DATA9":   PN = "M62"  !CDS_PN = "M62";
"MBA_DATA10":   PN = "M63"  !CDS_PN = "M63";
"MBA_DATA11":   PN = "N62"  !CDS_PN = "N62";
"MBA_DATA12":   PN = "R64"  !CDS_PN = "R64";
"MBA_DATA13":   PN = "T62"  !CDS_PN = "T62";
"MBA_DATA14":   PN = "T63"  !CDS_PN = "T63";
"MBA_DATA15":   PN = "U62"  !CDS_PN = "U62";
"MBA_DATA16":   PN = "U64"  !CDS_PN = "U64";
"MBA_DATA17":   PN = "V62"  !CDS_PN = "V62";
"MBA_DATA18":   PN = "V63"  !CDS_PN = "V63";
"MBA_DATA19":   PN = "W62"  !CDS_PN = "W62";
"MBA_DATA20":   PN = "AA64"  !CDS_PN = "AA64";
"MBA_DATA21":   PN = "AB62"  !CDS_PN = "AB62";
"MBA_DATA22":   PN = "AB63"  !CDS_PN = "AB63";
"MBA_DATA23":   PN = "AC62"  !CDS_PN = "AC62";
"MBA_DATA24":   PN = "AC64"  !CDS_PN = "AC64";
"MBA_DATA25":   PN = "AD62"  !CDS_PN = "AD62";
"MBA_DATA26":   PN = "AD63"  !CDS_PN = "AD63";
"MBA_DATA27":   PN = "AE62"  !CDS_PN = "AE62";
"MBA_DATA28":   PN = "AG64"  !CDS_PN = "AG64";
"MBA_DATA29":   PN = "AH62"  !CDS_PN = "AH62";
"MBA_DATA30":   PN = "AH63"  !CDS_PN = "AH63";
"MBA_DATA31":   PN = "AJ62"  !CDS_PN = "AJ62";
"MBA_DQS_H0":   PN = "G64"  !CDS_PN = "G64";
"MBA_DQS_H1":   PN = "N64"  !CDS_PN = "N64";
"MBA_DQS_H2":   PN = "W64"  !CDS_PN = "W64";
"MBA_DQS_H3":   PN = "AE64"  !CDS_PN = "AE64";
"MBA_DQS_H4":   PN = "AL64"  !CDS_PN = "AL64";
"MBA_DQS_H5":   PN = "J62"  !CDS_PN = "J62";
"MBA_DQS_H6":   PN = "R62"  !CDS_PN = "R62";
"MBA_DQS_H7":   PN = "AA62"  !CDS_PN = "AA62";
"MBA_DQS_H8":   PN = "AG62"  !CDS_PN = "AG62";
"MBA_DQS_H9":   PN = "AN62"  !CDS_PN = "AN62";
"MBA_DQS_L0":   PN = "H63"  !CDS_PN = "H63";
"MBA_DQS_L1":   PN = "P63"  !CDS_PN = "P63";
"MBA_DQS_L2":   PN = "Y63"  !CDS_PN = "Y63";
"MBA_DQS_L3":   PN = "AF63"  !CDS_PN = "AF63";
"MBA_DQS_L4":   PN = "AM63"  !CDS_PN = "AM63";
"MBA_DQS_L5":   PN = "H62"  !CDS_PN = "H62";
"MBA_DQS_L6":   PN = "P62"  !CDS_PN = "P62";
"MBA_DQS_L7":   PN = "Y62"  !CDS_PN = "Y62";
"MBA_DQS_L8":   PN = "AF62"  !CDS_PN = "AF62";
"MBA_DQS_L9":   PN = "AM62"  !CDS_PN = "AM62";
"MBA_PAR":   PN = "BC62"  !CDS_PN = "BC62";
"MBB0_CS_L0":   PN = "BM62"  !CDS_PN = "BM62";
"MBB0_CS_L1":   PN = "BN64"  !CDS_PN = "BN64";
"MBB0_RSP_L":   PN = "BP63"  !CDS_PN = "BP63";
"MBB1_CS_L0":   PN = "BL62"  !CDS_PN = "BL62";
"MBB1_CS_L1":   PN = "BM63"  !CDS_PN = "BM63";
"MBB1_RSP_L":   PN = "BR64"  !CDS_PN = "BR64";
"MBB_CA0":   PN = "BG62"  !CDS_PN = "BG62";
"MBB_CA1":   PN = "BH62"  !CDS_PN = "BH62";
"MBB_CA2":   PN = "BH63"  !CDS_PN = "BH63";
"MBB_CA3":   PN = "BJ64"  !CDS_PN = "BJ64";
"MBB_CA4":   PN = "BJ62"  !CDS_PN = "BJ62";
"MBB_CA5":   PN = "BK62"  !CDS_PN = "BK62";
"MBB_CA6":   PN = "BK63"  !CDS_PN = "BK63";
"MBB_CHECK0":   PN = "BY63"  !CDS_PN = "BY63";
"MBB_CHECK1":   PN = "CA62"  !CDS_PN = "CA62";
"MBB_CHECK2":   PN = "CA64"  !CDS_PN = "CA64";
"MBB_CHECK3":   PN = "CB62"  !CDS_PN = "CB62";
"MBB_CHECK4":   PN = "BT63"  !CDS_PN = "BT63";
"MBB_CHECK5":   PN = "BU62"  !CDS_PN = "BU62";
"MBB_CHECK6":   PN = "BU64"  !CDS_PN = "BU64";
"MBB_CHECK7":   PN = "BV62"  !CDS_PN = "BV62";
"MBB_DATA0":   PN = "CB63"  !CDS_PN = "CB63";
"MBB_DATA1":   PN = "CC62"  !CDS_PN = "CC62";
"MBB_DATA2":   PN = "CC64"  !CDS_PN = "CC64";
"MBB_DATA3":   PN = "CD62"  !CDS_PN = "CD62";
"MBB_DATA4":   PN = "CF63"  !CDS_PN = "CF63";
"MBB_DATA5":   PN = "CG62"  !CDS_PN = "CG62";
"MBB_DATA6":   PN = "CG64"  !CDS_PN = "CG64";
"MBB_DATA7":   PN = "CH62"  !CDS_PN = "CH62";
"MBB_DATA8":   PN = "CH63"  !CDS_PN = "CH63";
"MBB_DATA9":   PN = "CJ62"  !CDS_PN = "CJ62";
"MBB_DATA10":   PN = "CJ64"  !CDS_PN = "CJ64";
"MBB_DATA11":   PN = "CK62"  !CDS_PN = "CK62";
"MBB_DATA12":   PN = "CM63"  !CDS_PN = "CM63";
"MBB_DATA13":   PN = "CN62"  !CDS_PN = "CN62";
"MBB_DATA14":   PN = "CN64"  !CDS_PN = "CN64";
"MBB_DATA15":   PN = "CP62"  !CDS_PN = "CP62";
"MBB_DATA16":   PN = "CP63"  !CDS_PN = "CP63";
"MBB_DATA17":   PN = "CR62"  !CDS_PN = "CR62";
"MBB_DATA18":   PN = "CR64"  !CDS_PN = "CR64";
"MBB_DATA19":   PN = "CT62"  !CDS_PN = "CT62";
"MBB_DATA20":   PN = "CV63"  !CDS_PN = "CV63";
"MBB_DATA21":   PN = "CW62"  !CDS_PN = "CW62";
"MBB_DATA22":   PN = "CW64"  !CDS_PN = "CW64";
"MBB_DATA23":   PN = "CY62"  !CDS_PN = "CY62";
"MBB_DATA24":   PN = "CY63"  !CDS_PN = "CY63";
"MBB_DATA25":   PN = "DA62"  !CDS_PN = "DA62";
"MBB_DATA26":   PN = "DA64"  !CDS_PN = "DA64";
"MBB_DATA27":   PN = "DB62"  !CDS_PN = "DB62";
"MBB_DATA28":   PN = "DD63"  !CDS_PN = "DD63";
"MBB_DATA29":   PN = "DE62"  !CDS_PN = "DE62";
"MBB_DATA30":   PN = "DE64"  !CDS_PN = "DE64";
"MBB_DATA31":   PN = "DF62"  !CDS_PN = "DF62";
"MBB_DQS_H0":   PN = "CD63"  !CDS_PN = "CD63";
"MBB_DQS_H1":   PN = "CK63"  !CDS_PN = "CK63";
"MBB_DQS_H2":   PN = "CT63"  !CDS_PN = "CT63";
"MBB_DQS_H3":   PN = "DB63"  !CDS_PN = "DB63";
"MBB_DQS_H4":   PN = "BY62"  !CDS_PN = "BY62";
"MBB_DQS_H5":   PN = "CF62"  !CDS_PN = "CF62";
"MBB_DQS_H6":   PN = "CM62"  !CDS_PN = "CM62";
"MBB_DQS_H7":   PN = "CV62"  !CDS_PN = "CV62";
"MBB_DQS_H8":   PN = "DD62"  !CDS_PN = "DD62";
"MBB_DQS_H9":   PN = "BV63"  !CDS_PN = "BV63";
"MBB_DQS_L0":   PN = "CE64"  !CDS_PN = "CE64";
"MBB_DQS_L1":   PN = "CL64"  !CDS_PN = "CL64";
"MBB_DQS_L2":   PN = "CU64"  !CDS_PN = "CU64";
"MBB_DQS_L3":   PN = "DC64"  !CDS_PN = "DC64";
"MBB_DQS_L4":   PN = "BW62"  !CDS_PN = "BW62";
"MBB_DQS_L5":   PN = "CE62"  !CDS_PN = "CE62";
"MBB_DQS_L6":   PN = "CL62"  !CDS_PN = "CL62";
"MBB_DQS_L7":   PN = "CU62"  !CDS_PN = "CU62";
"MBB_DQS_L8":   PN = "DC62"  !CDS_PN = "DC62";
"MBB_DQS_L9":   PN = "BW64"  !CDS_PN = "BW64";
"MBB_PAR":   PN = "BL64"  !CDS_PN = "BL64";
"TEST39B":   PN = "BF62"  !CDS_PN = "BF62";
BODY = "Q_RES","I314": #LOCATION = "R501" !CDS_LOCATION = "R501" &SEC = "1" #&CDS_SEC = "1";
"A":   PN = "1"  !CDS_PN = "1";
"B":   PN = "2"  !CDS_PN = "2";
DRAWING = "@t6g_mb_lib.t6g(sch_1):page39";
BODY = "GENOA_SP5","I159": #LOCATION = "U26" !CDS_LOCATION = "U26" &SEC = "3" #&CDS_SEC = "3";
"MC0_CLK_H":   PN = "BC57"  !CDS_PN = "BC57";
"MC0_CLK_L":   PN = "BD56"  !CDS_PN = "BD56";
"MC1_CLK_H":   PN = "BF56"  !CDS_PN = "BF56";
"MC1_CLK_L":   PN = "BG57"  !CDS_PN = "BG57";
"MC_ALERT_L":   PN = "AT55"  !CDS_PN = "AT55";
"MC_RESET_L":   PN = "AU55"  !CDS_PN = "AU55";
"MCA0_CS_L0":   PN = "AV56"  !CDS_PN = "AV56";
"MCA0_CS_L1":   PN = "AW55"  !CDS_PN = "AW55";
"MCA0_RSP_L":   PN = "BN55"  !CDS_PN = "BN55";
"MCA1_CS_L0":   PN = "AU57"  !CDS_PN = "AU57";
"MCA1_CS_L1":   PN = "AV55"  !CDS_PN = "AV55";
"MCA1_RSP_L":   PN = "BP55"  !CDS_PN = "BP55";
"MCA_CA0":   PN = "AW57"  !CDS_PN = "AW57";
"MCA_CA1":   PN = "AY56"  !CDS_PN = "AY56";
"MCA_CA2":   PN = "AY55"  !CDS_PN = "AY55";
"MCA_CA3":   PN = "BA55"  !CDS_PN = "BA55";
"MCA_CA4":   PN = "BA57"  !CDS_PN = "BA57";
"MCA_CA5":   PN = "BB56"  !CDS_PN = "BB56";
"MCA_CA6":   PN = "BB55"  !CDS_PN = "BB55";
"MCA_CHECK0":   PN = "AJ57"  !CDS_PN = "AJ57";
"MCA_CHECK1":   PN = "AK55"  !CDS_PN = "AK55";
"MCA_CHECK2":   PN = "AK56"  !CDS_PN = "AK56";
"MCA_CHECK3":   PN = "AL55"  !CDS_PN = "AL55";
"MCA_CHECK4":   PN = "AN57"  !CDS_PN = "AN57";
"MCA_CHECK5":   PN = "AP55"  !CDS_PN = "AP55";
"MCA_CHECK6":   PN = "AP56"  !CDS_PN = "AP56";
"MCA_CHECK7":   PN = "AR55"  !CDS_PN = "AR55";
"MCA_DATA0":   PN = "E57"  !CDS_PN = "E57";
"MCA_DATA1":   PN = "F55"  !CDS_PN = "F55";
"MCA_DATA2":   PN = "F56"  !CDS_PN = "F56";
"MCA_DATA3":   PN = "G55"  !CDS_PN = "G55";
"MCA_DATA4":   PN = "J57"  !CDS_PN = "J57";
"MCA_DATA5":   PN = "K55"  !CDS_PN = "K55";
"MCA_DATA6":   PN = "K56"  !CDS_PN = "K56";
"MCA_DATA7":   PN = "L55"  !CDS_PN = "L55";
"MCA_DATA8":   PN = "L57"  !CDS_PN = "L57";
"MCA_DATA9":   PN = "M55"  !CDS_PN = "M55";
"MCA_DATA10":   PN = "M56"  !CDS_PN = "M56";
"MCA_DATA11":   PN = "N55"  !CDS_PN = "N55";
"MCA_DATA12":   PN = "R57"  !CDS_PN = "R57";
"MCA_DATA13":   PN = "T55"  !CDS_PN = "T55";
"MCA_DATA14":   PN = "T56"  !CDS_PN = "T56";
"MCA_DATA15":   PN = "U55"  !CDS_PN = "U55";
"MCA_DATA16":   PN = "U57"  !CDS_PN = "U57";
"MCA_DATA17":   PN = "V55"  !CDS_PN = "V55";
"MCA_DATA18":   PN = "V56"  !CDS_PN = "V56";
"MCA_DATA19":   PN = "W55"  !CDS_PN = "W55";
"MCA_DATA20":   PN = "AA57"  !CDS_PN = "AA57";
"MCA_DATA21":   PN = "AB55"  !CDS_PN = "AB55";
"MCA_DATA22":   PN = "AB56"  !CDS_PN = "AB56";
"MCA_DATA23":   PN = "AC55"  !CDS_PN = "AC55";
"MCA_DATA24":   PN = "AC57"  !CDS_PN = "AC57";
"MCA_DATA25":   PN = "AD55"  !CDS_PN = "AD55";
"MCA_DATA26":   PN = "AD56"  !CDS_PN = "AD56";
"MCA_DATA27":   PN = "AE55"  !CDS_PN = "AE55";
"MCA_DATA28":   PN = "AG57"  !CDS_PN = "AG57";
"MCA_DATA29":   PN = "AH55"  !CDS_PN = "AH55";
"MCA_DATA30":   PN = "AH56"  !CDS_PN = "AH56";
"MCA_DATA31":   PN = "AJ55"  !CDS_PN = "AJ55";
"MCA_DQS_H0":   PN = "G57"  !CDS_PN = "G57";
"MCA_DQS_H1":   PN = "N57"  !CDS_PN = "N57";
"MCA_DQS_H2":   PN = "W57"  !CDS_PN = "W57";
"MCA_DQS_H3":   PN = "AE57"  !CDS_PN = "AE57";
"MCA_DQS_H4":   PN = "AL57"  !CDS_PN = "AL57";
"MCA_DQS_H5":   PN = "J55"  !CDS_PN = "J55";
"MCA_DQS_H6":   PN = "R55"  !CDS_PN = "R55";
"MCA_DQS_H7":   PN = "AA55"  !CDS_PN = "AA55";
"MCA_DQS_H8":   PN = "AG55"  !CDS_PN = "AG55";
"MCA_DQS_H9":   PN = "AN55"  !CDS_PN = "AN55";
"MCA_DQS_L0":   PN = "H56"  !CDS_PN = "H56";
"MCA_DQS_L1":   PN = "P56"  !CDS_PN = "P56";
"MCA_DQS_L2":   PN = "Y56"  !CDS_PN = "Y56";
"MCA_DQS_L3":   PN = "AF56"  !CDS_PN = "AF56";
"MCA_DQS_L4":   PN = "AM56"  !CDS_PN = "AM56";
"MCA_DQS_L5":   PN = "H55"  !CDS_PN = "H55";
"MCA_DQS_L6":   PN = "P55"  !CDS_PN = "P55";
"MCA_DQS_L7":   PN = "Y55"  !CDS_PN = "Y55";
"MCA_DQS_L8":   PN = "AF55"  !CDS_PN = "AF55";
"MCA_DQS_L9":   PN = "AM55"  !CDS_PN = "AM55";
"MCA_PAR":   PN = "BC55"  !CDS_PN = "BC55";
"MCB0_CS_L0":   PN = "BM55"  !CDS_PN = "BM55";
"MCB0_CS_L1":   PN = "BN57"  !CDS_PN = "BN57";
"MCB0_RSP_L":   PN = "BP56"  !CDS_PN = "BP56";
"MCB1_CS_L0":   PN = "BL55"  !CDS_PN = "BL55";
"MCB1_CS_L1":   PN = "BM56"  !CDS_PN = "BM56";
"MCB1_RSP_L":   PN = "BR57"  !CDS_PN = "BR57";
"MCB_CA0":   PN = "BG55"  !CDS_PN = "BG55";
"MCB_CA1":   PN = "BH55"  !CDS_PN = "BH55";
"MCB_CA2":   PN = "BH56"  !CDS_PN = "BH56";
"MCB_CA3":   PN = "BJ57"  !CDS_PN = "BJ57";
"MCB_CA4":   PN = "BJ55"  !CDS_PN = "BJ55";
"MCB_CA5":   PN = "BK55"  !CDS_PN = "BK55";
"MCB_CA6":   PN = "BK56"  !CDS_PN = "BK56";
"MCB_CHECK0":   PN = "BY56"  !CDS_PN = "BY56";
"MCB_CHECK1":   PN = "CA55"  !CDS_PN = "CA55";
"MCB_CHECK2":   PN = "CA57"  !CDS_PN = "CA57";
"MCB_CHECK3":   PN = "CB55"  !CDS_PN = "CB55";
"MCB_CHECK4":   PN = "BT56"  !CDS_PN = "BT56";
"MCB_CHECK5":   PN = "BU55"  !CDS_PN = "BU55";
"MCB_CHECK6":   PN = "BU57"  !CDS_PN = "BU57";
"MCB_CHECK7":   PN = "BV55"  !CDS_PN = "BV55";
"MCB_DATA0":   PN = "CB56"  !CDS_PN = "CB56";
"MCB_DATA1":   PN = "CC55"  !CDS_PN = "CC55";
"MCB_DATA2":   PN = "CC57"  !CDS_PN = "CC57";
"MCB_DATA3":   PN = "CD55"  !CDS_PN = "CD55";
"MCB_DATA4":   PN = "CF56"  !CDS_PN = "CF56";
"MCB_DATA5":   PN = "CG55"  !CDS_PN = "CG55";
"MCB_DATA6":   PN = "CG57"  !CDS_PN = "CG57";
"MCB_DATA7":   PN = "CH55"  !CDS_PN = "CH55";
"MCB_DATA8":   PN = "CH56"  !CDS_PN = "CH56";
"MCB_DATA9":   PN = "CJ55"  !CDS_PN = "CJ55";
"MCB_DATA10":   PN = "CJ57"  !CDS_PN = "CJ57";
"MCB_DATA11":   PN = "CK55"  !CDS_PN = "CK55";
"MCB_DATA12":   PN = "CM56"  !CDS_PN = "CM56";
"MCB_DATA13":   PN = "CN55"  !CDS_PN = "CN55";
"MCB_DATA14":   PN = "CN57"  !CDS_PN = "CN57";
"MCB_DATA15":   PN = "CP55"  !CDS_PN = "CP55";
"MCB_DATA16":   PN = "CP56"  !CDS_PN = "CP56";
"MCB_DATA17":   PN = "CR55"  !CDS_PN = "CR55";
"MCB_DATA18":   PN = "CR57"  !CDS_PN = "CR57";
"MCB_DATA19":   PN = "CT55"  !CDS_PN = "CT55";
"MCB_DATA20":   PN = "CV56"  !CDS_PN = "CV56";
"MCB_DATA21":   PN = "CW55"  !CDS_PN = "CW55";
"MCB_DATA22":   PN = "CW57"  !CDS_PN = "CW57";
"MCB_DATA23":   PN = "CY55"  !CDS_PN = "CY55";
"MCB_DATA24":   PN = "CY56"  !CDS_PN = "CY56";
"MCB_DATA25":   PN = "DA55"  !CDS_PN = "DA55";
"MCB_DATA26":   PN = "DA57"  !CDS_PN = "DA57";
"MCB_DATA27":   PN = "DB55"  !CDS_PN = "DB55";
"MCB_DATA28":   PN = "DD56"  !CDS_PN = "DD56";
"MCB_DATA29":   PN = "DE55"  !CDS_PN = "DE55";
"MCB_DATA30":   PN = "DE57"  !CDS_PN = "DE57";
"MCB_DATA31":   PN = "DF55"  !CDS_PN = "DF55";
"MCB_DQS_H0":   PN = "CD56"  !CDS_PN = "CD56";
"MCB_DQS_H1":   PN = "CK56"  !CDS_PN = "CK56";
"MCB_DQS_H2":   PN = "CT56"  !CDS_PN = "CT56";
"MCB_DQS_H3":   PN = "DB56"  !CDS_PN = "DB56";
"MCB_DQS_H4":   PN = "BY55"  !CDS_PN = "BY55";
"MCB_DQS_H5":   PN = "CF55"  !CDS_PN = "CF55";
"MCB_DQS_H6":   PN = "CM55"  !CDS_PN = "CM55";
"MCB_DQS_H7":   PN = "CV55"  !CDS_PN = "CV55";
"MCB_DQS_H8":   PN = "DD55"  !CDS_PN = "DD55";
"MCB_DQS_H9":   PN = "BV56"  !CDS_PN = "BV56";
"MCB_DQS_L0":   PN = "CE57"  !CDS_PN = "CE57";
"MCB_DQS_L1":   PN = "CL57"  !CDS_PN = "CL57";
"MCB_DQS_L2":   PN = "CU57"  !CDS_PN = "CU57";
"MCB_DQS_L3":   PN = "DC57"  !CDS_PN = "DC57";
"MCB_DQS_L4":   PN = "BW55"  !CDS_PN = "BW55";
"MCB_DQS_L5":   PN = "CE55"  !CDS_PN = "CE55";
"MCB_DQS_L6":   PN = "CL55"  !CDS_PN = "CL55";
"MCB_DQS_L7":   PN = "CU55"  !CDS_PN = "CU55";
"MCB_DQS_L8":   PN = "DC55"  !CDS_PN = "DC55";
"MCB_DQS_L9":   PN = "BW57"  !CDS_PN = "BW57";
"MCB_PAR":   PN = "BL57"  !CDS_PN = "BL57";
"TEST39C":   PN = "BF55"  !CDS_PN = "BF55";
BODY = "Q_RES","I313": #LOCATION = "R502" !CDS_LOCATION = "R502" &SEC = "1" #&CDS_SEC = "1";
"A":   PN = "1"  !CDS_PN = "1";
"B":   PN = "2"  !CDS_PN = "2";
DRAWING = "@t6g_mb_lib.t6g(sch_1):page40";
BODY = "GENOA_SP5","I159": #LOCATION = "U26" !CDS_LOCATION = "U26" &SEC = "4" #&CDS_SEC = "4";
"MD0_CLK_H":   PN = "BC60"  !CDS_PN = "BC60";
"MD0_CLK_L":   PN = "BD60"  !CDS_PN = "BD60";
"MD1_CLK_H":   PN = "BF60"  !CDS_PN = "BF60";
"MD1_CLK_L":   PN = "BG60"  !CDS_PN = "BG60";
"MD_ALERT_L":   PN = "AT58"  !CDS_PN = "AT58";
"MD_RESET_L":   PN = "AU59"  !CDS_PN = "AU59";
"MDA0_CS_L0":   PN = "AV60"  !CDS_PN = "AV60";
"MDA0_CS_L1":   PN = "AW59"  !CDS_PN = "AW59";
"MDA0_RSP_L":   PN = "BN59"  !CDS_PN = "BN59";
"MDA1_CS_L0":   PN = "AU60"  !CDS_PN = "AU60";
"MDA1_CS_L1":   PN = "AV58"  !CDS_PN = "AV58";
"MDA1_RSP_L":   PN = "BP58"  !CDS_PN = "BP58";
"MDA_CA0":   PN = "AW60"  !CDS_PN = "AW60";
"MDA_CA1":   PN = "AY60"  !CDS_PN = "AY60";
"MDA_CA2":   PN = "AY58"  !CDS_PN = "AY58";
"MDA_CA3":   PN = "BA59"  !CDS_PN = "BA59";
"MDA_CA4":   PN = "BA60"  !CDS_PN = "BA60";
"MDA_CA5":   PN = "BB60"  !CDS_PN = "BB60";
"MDA_CA6":   PN = "BB58"  !CDS_PN = "BB58";
"MDA_CHECK0":   PN = "AJ60"  !CDS_PN = "AJ60";
"MDA_CHECK1":   PN = "AK58"  !CDS_PN = "AK58";
"MDA_CHECK2":   PN = "AK60"  !CDS_PN = "AK60";
"MDA_CHECK3":   PN = "AL59"  !CDS_PN = "AL59";
"MDA_CHECK4":   PN = "AN60"  !CDS_PN = "AN60";
"MDA_CHECK5":   PN = "AP58"  !CDS_PN = "AP58";
"MDA_CHECK6":   PN = "AP60"  !CDS_PN = "AP60";
"MDA_CHECK7":   PN = "AR59"  !CDS_PN = "AR59";
"MDA_DATA0":   PN = "E60"  !CDS_PN = "E60";
"MDA_DATA1":   PN = "F58"  !CDS_PN = "F58";
"MDA_DATA2":   PN = "F60"  !CDS_PN = "F60";
"MDA_DATA3":   PN = "G59"  !CDS_PN = "G59";
"MDA_DATA4":   PN = "J60"  !CDS_PN = "J60";
"MDA_DATA5":   PN = "K58"  !CDS_PN = "K58";
"MDA_DATA6":   PN = "K60"  !CDS_PN = "K60";
"MDA_DATA7":   PN = "L59"  !CDS_PN = "L59";
"MDA_DATA8":   PN = "L60"  !CDS_PN = "L60";
"MDA_DATA9":   PN = "M58"  !CDS_PN = "M58";
"MDA_DATA10":   PN = "M60"  !CDS_PN = "M60";
"MDA_DATA11":   PN = "N59"  !CDS_PN = "N59";
"MDA_DATA12":   PN = "R60"  !CDS_PN = "R60";
"MDA_DATA13":   PN = "T58"  !CDS_PN = "T58";
"MDA_DATA14":   PN = "T60"  !CDS_PN = "T60";
"MDA_DATA15":   PN = "U59"  !CDS_PN = "U59";
"MDA_DATA16":   PN = "U60"  !CDS_PN = "U60";
"MDA_DATA17":   PN = "V58"  !CDS_PN = "V58";
"MDA_DATA18":   PN = "V60"  !CDS_PN = "V60";
"MDA_DATA19":   PN = "W59"  !CDS_PN = "W59";
"MDA_DATA20":   PN = "AA60"  !CDS_PN = "AA60";
"MDA_DATA21":   PN = "AB58"  !CDS_PN = "AB58";
"MDA_DATA22":   PN = "AB60"  !CDS_PN = "AB60";
"MDA_DATA23":   PN = "AC59"  !CDS_PN = "AC59";
"MDA_DATA24":   PN = "AC60"  !CDS_PN = "AC60";
"MDA_DATA25":   PN = "AD58"  !CDS_PN = "AD58";
"MDA_DATA26":   PN = "AD60"  !CDS_PN = "AD60";
"MDA_DATA27":   PN = "AE59"  !CDS_PN = "AE59";
"MDA_DATA28":   PN = "AG60"  !CDS_PN = "AG60";
"MDA_DATA29":   PN = "AH58"  !CDS_PN = "AH58";
"MDA_DATA30":   PN = "AH60"  !CDS_PN = "AH60";
"MDA_DATA31":   PN = "AJ59"  !CDS_PN = "AJ59";
"MDA_DQS_H0":   PN = "G60"  !CDS_PN = "G60";
"MDA_DQS_H1":   PN = "N60"  !CDS_PN = "N60";
"MDA_DQS_H2":   PN = "W60"  !CDS_PN = "W60";
"MDA_DQS_H3":   PN = "AE60"  !CDS_PN = "AE60";
"MDA_DQS_H4":   PN = "AL60"  !CDS_PN = "AL60";
"MDA_DQS_H5":   PN = "J59"  !CDS_PN = "J59";
"MDA_DQS_H6":   PN = "R59"  !CDS_PN = "R59";
"MDA_DQS_H7":   PN = "AA59"  !CDS_PN = "AA59";
"MDA_DQS_H8":   PN = "AG59"  !CDS_PN = "AG59";
"MDA_DQS_H9":   PN = "AN59"  !CDS_PN = "AN59";
"MDA_DQS_L0":   PN = "H60"  !CDS_PN = "H60";
"MDA_DQS_L1":   PN = "P60"  !CDS_PN = "P60";
"MDA_DQS_L2":   PN = "Y60"  !CDS_PN = "Y60";
"MDA_DQS_L3":   PN = "AF60"  !CDS_PN = "AF60";
"MDA_DQS_L4":   PN = "AM60"  !CDS_PN = "AM60";
"MDA_DQS_L5":   PN = "H58"  !CDS_PN = "H58";
"MDA_DQS_L6":   PN = "P58"  !CDS_PN = "P58";
"MDA_DQS_L7":   PN = "Y58"  !CDS_PN = "Y58";
"MDA_DQS_L8":   PN = "AF58"  !CDS_PN = "AF58";
"MDA_DQS_L9":   PN = "AM58"  !CDS_PN = "AM58";
"MDA_PAR":   PN = "BC59"  !CDS_PN = "BC59";
"MDB0_CS_L0":   PN = "BM58"  !CDS_PN = "BM58";
"MDB0_CS_L1":   PN = "BN60"  !CDS_PN = "BN60";
"MDB0_RSP_L":   PN = "BP60"  !CDS_PN = "BP60";
"MDB1_CS_L0":   PN = "BL59"  !CDS_PN = "BL59";
"MDB1_CS_L1":   PN = "BM60"  !CDS_PN = "BM60";
"MDB1_RSP_L":   PN = "BR60"  !CDS_PN = "BR60";
"MDB_CA0":   PN = "BG59"  !CDS_PN = "BG59";
"MDB_CA1":   PN = "BH58"  !CDS_PN = "BH58";
"MDB_CA2":   PN = "BH60"  !CDS_PN = "BH60";
"MDB_CA3":   PN = "BJ60"  !CDS_PN = "BJ60";
"MDB_CA4":   PN = "BJ59"  !CDS_PN = "BJ59";
"MDB_CA5":   PN = "BK58"  !CDS_PN = "BK58";
"MDB_CA6":   PN = "BK60"  !CDS_PN = "BK60";
"MDB_CHECK0":   PN = "BY60"  !CDS_PN = "BY60";
"MDB_CHECK1":   PN = "CA59"  !CDS_PN = "CA59";
"MDB_CHECK2":   PN = "CA60"  !CDS_PN = "CA60";
"MDB_CHECK3":   PN = "CB58"  !CDS_PN = "CB58";
"MDB_CHECK4":   PN = "BT60"  !CDS_PN = "BT60";
"MDB_CHECK5":   PN = "BU59"  !CDS_PN = "BU59";
"MDB_CHECK6":   PN = "BU60"  !CDS_PN = "BU60";
"MDB_CHECK7":   PN = "BV58"  !CDS_PN = "BV58";
"MDB_DATA0":   PN = "CB60"  !CDS_PN = "CB60";
"MDB_DATA1":   PN = "CC59"  !CDS_PN = "CC59";
"MDB_DATA2":   PN = "CC60"  !CDS_PN = "CC60";
"MDB_DATA3":   PN = "CD58"  !CDS_PN = "CD58";
"MDB_DATA4":   PN = "CF60"  !CDS_PN = "CF60";
"MDB_DATA5":   PN = "CG59"  !CDS_PN = "CG59";
"MDB_DATA6":   PN = "CG60"  !CDS_PN = "CG60";
"MDB_DATA7":   PN = "CH58"  !CDS_PN = "CH58";
"MDB_DATA8":   PN = "CH60"  !CDS_PN = "CH60";
"MDB_DATA9":   PN = "CJ59"  !CDS_PN = "CJ59";
"MDB_DATA10":   PN = "CJ60"  !CDS_PN = "CJ60";
"MDB_DATA11":   PN = "CK58"  !CDS_PN = "CK58";
"MDB_DATA12":   PN = "CM60"  !CDS_PN = "CM60";
"MDB_DATA13":   PN = "CN59"  !CDS_PN = "CN59";
"MDB_DATA14":   PN = "CN60"  !CDS_PN = "CN60";
"MDB_DATA15":   PN = "CP58"  !CDS_PN = "CP58";
"MDB_DATA16":   PN = "CP60"  !CDS_PN = "CP60";
"MDB_DATA17":   PN = "CR59"  !CDS_PN = "CR59";
"MDB_DATA18":   PN = "CR60"  !CDS_PN = "CR60";
"MDB_DATA19":   PN = "CT58"  !CDS_PN = "CT58";
"MDB_DATA20":   PN = "CV60"  !CDS_PN = "CV60";
"MDB_DATA21":   PN = "CW59"  !CDS_PN = "CW59";
"MDB_DATA22":   PN = "CW60"  !CDS_PN = "CW60";
"MDB_DATA23":   PN = "CY58"  !CDS_PN = "CY58";
"MDB_DATA24":   PN = "CY60"  !CDS_PN = "CY60";
"MDB_DATA25":   PN = "DA59"  !CDS_PN = "DA59";
"MDB_DATA26":   PN = "DA60"  !CDS_PN = "DA60";
"MDB_DATA27":   PN = "DB58"  !CDS_PN = "DB58";
"MDB_DATA28":   PN = "DD60"  !CDS_PN = "DD60";
"MDB_DATA29":   PN = "DE59"  !CDS_PN = "DE59";
"MDB_DATA30":   PN = "DE60"  !CDS_PN = "DE60";
"MDB_DATA31":   PN = "DF60"  !CDS_PN = "DF60";
"MDB_DQS_H0":   PN = "CD60"  !CDS_PN = "CD60";
"MDB_DQS_H1":   PN = "CK60"  !CDS_PN = "CK60";
"MDB_DQS_H2":   PN = "CT60"  !CDS_PN = "CT60";
"MDB_DQS_H3":   PN = "DB60"  !CDS_PN = "DB60";
"MDB_DQS_H4":   PN = "BY58"  !CDS_PN = "BY58";
"MDB_DQS_H5":   PN = "CF58"  !CDS_PN = "CF58";
"MDB_DQS_H6":   PN = "CM58"  !CDS_PN = "CM58";
"MDB_DQS_H7":   PN = "CV58"  !CDS_PN = "CV58";
"MDB_DQS_H8":   PN = "DD58"  !CDS_PN = "DD58";
"MDB_DQS_H9":   PN = "BV60"  !CDS_PN = "BV60";
"MDB_DQS_L0":   PN = "CE60"  !CDS_PN = "CE60";
"MDB_DQS_L1":   PN = "CL60"  !CDS_PN = "CL60";
"MDB_DQS_L2":   PN = "CU60"  !CDS_PN = "CU60";
"MDB_DQS_L3":   PN = "DC60"  !CDS_PN = "DC60";
"MDB_DQS_L4":   PN = "BW59"  !CDS_PN = "BW59";
"MDB_DQS_L5":   PN = "CE59"  !CDS_PN = "CE59";
"MDB_DQS_L6":   PN = "CL59"  !CDS_PN = "CL59";
"MDB_DQS_L7":   PN = "CU59"  !CDS_PN = "CU59";
"MDB_DQS_L8":   PN = "DC59"  !CDS_PN = "DC59";
"MDB_DQS_L9":   PN = "BW60"  !CDS_PN = "BW60";
"MDB_PAR":   PN = "BL60"  !CDS_PN = "BL60";
"TEST39D":   PN = "BF58"  !CDS_PN = "BF58";
BODY = "Q_RES","I314": #LOCATION = "R503" !CDS_LOCATION = "R503" &SEC = "1" #&CDS_SEC = "1";
"A":   PN = "1"  !CDS_PN = "1";
"B":   PN = "2"  !CDS_PN = "2";
DRAWING = "@t6g_mb_lib.t6g(sch_1):page41";
BODY = "GENOA_SP5","I159": #LOCATION = "U26" !CDS_LOCATION = "U26" &SEC = "5" #&CDS_SEC = "5";
"ME0_CLK_H":   PN = "BC71"  !CDS_PN = "BC71";
"ME0_CLK_L":   PN = "BD70"  !CDS_PN = "BD70";
"ME1_CLK_H":   PN = "BF70"  !CDS_PN = "BF70";
"ME1_CLK_L":   PN = "BG71"  !CDS_PN = "BG71";
"ME_ALERT_L":   PN = "AT69"  !CDS_PN = "AT69";
"ME_RESET_L":   PN = "AU69"  !CDS_PN = "AU69";
"MEA0_CS_L0":   PN = "AV70"  !CDS_PN = "AV70";
"MEA0_CS_L1":   PN = "AW69"  !CDS_PN = "AW69";
"MEA0_RSP_L":   PN = "BN69"  !CDS_PN = "BN69";
"MEA1_CS_L0":   PN = "AU71"  !CDS_PN = "AU71";
"MEA1_CS_L1":   PN = "AV69"  !CDS_PN = "AV69";
"MEA1_RSP_L":   PN = "BP69"  !CDS_PN = "BP69";
"MEA_CA0":   PN = "AW71"  !CDS_PN = "AW71";
"MEA_CA1":   PN = "AY70"  !CDS_PN = "AY70";
"MEA_CA2":   PN = "AY69"  !CDS_PN = "AY69";
"MEA_CA3":   PN = "BA69"  !CDS_PN = "BA69";
"MEA_CA4":   PN = "BA71"  !CDS_PN = "BA71";
"MEA_CA5":   PN = "BB70"  !CDS_PN = "BB70";
"MEA_CA6":   PN = "BB69"  !CDS_PN = "BB69";
"MEA_CHECK0":   PN = "AJ71"  !CDS_PN = "AJ71";
"MEA_CHECK1":   PN = "AK69"  !CDS_PN = "AK69";
"MEA_CHECK2":   PN = "AK70"  !CDS_PN = "AK70";
"MEA_CHECK3":   PN = "AL69"  !CDS_PN = "AL69";
"MEA_CHECK4":   PN = "AN71"  !CDS_PN = "AN71";
"MEA_CHECK5":   PN = "AP69"  !CDS_PN = "AP69";
"MEA_CHECK6":   PN = "AP70"  !CDS_PN = "AP70";
"MEA_CHECK7":   PN = "AR69"  !CDS_PN = "AR69";
"MEA_DATA0":   PN = "E71"  !CDS_PN = "E71";
"MEA_DATA1":   PN = "F69"  !CDS_PN = "F69";
"MEA_DATA2":   PN = "F70"  !CDS_PN = "F70";
"MEA_DATA3":   PN = "G69"  !CDS_PN = "G69";
"MEA_DATA4":   PN = "J71"  !CDS_PN = "J71";
"MEA_DATA5":   PN = "K69"  !CDS_PN = "K69";
"MEA_DATA6":   PN = "K70"  !CDS_PN = "K70";
"MEA_DATA7":   PN = "L69"  !CDS_PN = "L69";
"MEA_DATA8":   PN = "L71"  !CDS_PN = "L71";
"MEA_DATA9":   PN = "M69"  !CDS_PN = "M69";
"MEA_DATA10":   PN = "M70"  !CDS_PN = "M70";
"MEA_DATA11":   PN = "N69"  !CDS_PN = "N69";
"MEA_DATA12":   PN = "R71"  !CDS_PN = "R71";
"MEA_DATA13":   PN = "T69"  !CDS_PN = "T69";
"MEA_DATA14":   PN = "T70"  !CDS_PN = "T70";
"MEA_DATA15":   PN = "U69"  !CDS_PN = "U69";
"MEA_DATA16":   PN = "U71"  !CDS_PN = "U71";
"MEA_DATA17":   PN = "V69"  !CDS_PN = "V69";
"MEA_DATA18":   PN = "V70"  !CDS_PN = "V70";
"MEA_DATA19":   PN = "W69"  !CDS_PN = "W69";
"MEA_DATA20":   PN = "AA71"  !CDS_PN = "AA71";
"MEA_DATA21":   PN = "AB69"  !CDS_PN = "AB69";
"MEA_DATA22":   PN = "AB70"  !CDS_PN = "AB70";
"MEA_DATA23":   PN = "AC69"  !CDS_PN = "AC69";
"MEA_DATA24":   PN = "AC71"  !CDS_PN = "AC71";
"MEA_DATA25":   PN = "AD69"  !CDS_PN = "AD69";
"MEA_DATA26":   PN = "AD70"  !CDS_PN = "AD70";
"MEA_DATA27":   PN = "AE69"  !CDS_PN = "AE69";
"MEA_DATA28":   PN = "AG71"  !CDS_PN = "AG71";
"MEA_DATA29":   PN = "AH69"  !CDS_PN = "AH69";
"MEA_DATA30":   PN = "AH70"  !CDS_PN = "AH70";
"MEA_DATA31":   PN = "AJ69"  !CDS_PN = "AJ69";
"MEA_DQS_H0":   PN = "G71"  !CDS_PN = "G71";
"MEA_DQS_H1":   PN = "N71"  !CDS_PN = "N71";
"MEA_DQS_H2":   PN = "W71"  !CDS_PN = "W71";
"MEA_DQS_H3":   PN = "AE71"  !CDS_PN = "AE71";
"MEA_DQS_H4":   PN = "AL71"  !CDS_PN = "AL71";
"MEA_DQS_H5":   PN = "J69"  !CDS_PN = "J69";
"MEA_DQS_H6":   PN = "R69"  !CDS_PN = "R69";
"MEA_DQS_H7":   PN = "AA69"  !CDS_PN = "AA69";
"MEA_DQS_H8":   PN = "AG69"  !CDS_PN = "AG69";
"MEA_DQS_H9":   PN = "AN69"  !CDS_PN = "AN69";
"MEA_DQS_L0":   PN = "H70"  !CDS_PN = "H70";
"MEA_DQS_L1":   PN = "P70"  !CDS_PN = "P70";
"MEA_DQS_L2":   PN = "Y70"  !CDS_PN = "Y70";
"MEA_DQS_L3":   PN = "AF70"  !CDS_PN = "AF70";
"MEA_DQS_L4":   PN = "AM70"  !CDS_PN = "AM70";
"MEA_DQS_L5":   PN = "H69"  !CDS_PN = "H69";
"MEA_DQS_L6":   PN = "P69"  !CDS_PN = "P69";
"MEA_DQS_L7":   PN = "Y69"  !CDS_PN = "Y69";
"MEA_DQS_L8":   PN = "AF69"  !CDS_PN = "AF69";
"MEA_DQS_L9":   PN = "AM69"  !CDS_PN = "AM69";
"MEA_PAR":   PN = "BC69"  !CDS_PN = "BC69";
"MEB0_CS_L0":   PN = "BM69"  !CDS_PN = "BM69";
"MEB0_CS_L1":   PN = "BN71"  !CDS_PN = "BN71";
"MEB0_RSP_L":   PN = "BP70"  !CDS_PN = "BP70";
"MEB1_CS_L0":   PN = "BL69"  !CDS_PN = "BL69";
"MEB1_CS_L1":   PN = "BM70"  !CDS_PN = "BM70";
"MEB1_RSP_L":   PN = "BR71"  !CDS_PN = "BR71";
"MEB_CA0":   PN = "BG69"  !CDS_PN = "BG69";
"MEB_CA1":   PN = "BH69"  !CDS_PN = "BH69";
"MEB_CA2":   PN = "BH70"  !CDS_PN = "BH70";
"MEB_CA3":   PN = "BJ71"  !CDS_PN = "BJ71";
"MEB_CA4":   PN = "BJ69"  !CDS_PN = "BJ69";
"MEB_CA5":   PN = "BK69"  !CDS_PN = "BK69";
"MEB_CA6":   PN = "BK70"  !CDS_PN = "BK70";
"MEB_CHECK0":   PN = "BY70"  !CDS_PN = "BY70";
"MEB_CHECK1":   PN = "CA69"  !CDS_PN = "CA69";
"MEB_CHECK2":   PN = "CA71"  !CDS_PN = "CA71";
"MEB_CHECK3":   PN = "CB69"  !CDS_PN = "CB69";
"MEB_CHECK4":   PN = "BT70"  !CDS_PN = "BT70";
"MEB_CHECK5":   PN = "BU69"  !CDS_PN = "BU69";
"MEB_CHECK6":   PN = "BU71"  !CDS_PN = "BU71";
"MEB_CHECK7":   PN = "BV69"  !CDS_PN = "BV69";
"MEB_DATA0":   PN = "CB70"  !CDS_PN = "CB70";
"MEB_DATA1":   PN = "CC69"  !CDS_PN = "CC69";
"MEB_DATA2":   PN = "CC71"  !CDS_PN = "CC71";
"MEB_DATA3":   PN = "CD69"  !CDS_PN = "CD69";
"MEB_DATA4":   PN = "CF70"  !CDS_PN = "CF70";
"MEB_DATA5":   PN = "CG69"  !CDS_PN = "CG69";
"MEB_DATA6":   PN = "CG71"  !CDS_PN = "CG71";
"MEB_DATA7":   PN = "CH69"  !CDS_PN = "CH69";
"MEB_DATA8":   PN = "CH70"  !CDS_PN = "CH70";
"MEB_DATA9":   PN = "CJ69"  !CDS_PN = "CJ69";
"MEB_DATA10":   PN = "CJ71"  !CDS_PN = "CJ71";
"MEB_DATA11":   PN = "CK69"  !CDS_PN = "CK69";
"MEB_DATA12":   PN = "CM70"  !CDS_PN = "CM70";
"MEB_DATA13":   PN = "CN69"  !CDS_PN = "CN69";
"MEB_DATA14":   PN = "CN71"  !CDS_PN = "CN71";
"MEB_DATA15":   PN = "CP69"  !CDS_PN = "CP69";
"MEB_DATA16":   PN = "CP70"  !CDS_PN = "CP70";
"MEB_DATA17":   PN = "CR69"  !CDS_PN = "CR69";
"MEB_DATA18":   PN = "CR71"  !CDS_PN = "CR71";
"MEB_DATA19":   PN = "CT69"  !CDS_PN = "CT69";
"MEB_DATA20":   PN = "CV70"  !CDS_PN = "CV70";
"MEB_DATA21":   PN = "CW69"  !CDS_PN = "CW69";
"MEB_DATA22":   PN = "CW71"  !CDS_PN = "CW71";
"MEB_DATA23":   PN = "CY69"  !CDS_PN = "CY69";
"MEB_DATA24":   PN = "CY70"  !CDS_PN = "CY70";
"MEB_DATA25":   PN = "DA69"  !CDS_PN = "DA69";
"MEB_DATA26":   PN = "DA71"  !CDS_PN = "DA71";
"MEB_DATA27":   PN = "DB69"  !CDS_PN = "DB69";
"MEB_DATA28":   PN = "DD70"  !CDS_PN = "DD70";
"MEB_DATA29":   PN = "DE69"  !CDS_PN = "DE69";
"MEB_DATA30":   PN = "DE71"  !CDS_PN = "DE71";
"MEB_DATA31":   PN = "DF69"  !CDS_PN = "DF69";
"MEB_DQS_H0":   PN = "CD70"  !CDS_PN = "CD70";
"MEB_DQS_H1":   PN = "CK70"  !CDS_PN = "CK70";
"MEB_DQS_H2":   PN = "CT70"  !CDS_PN = "CT70";
"MEB_DQS_H3":   PN = "DB70"  !CDS_PN = "DB70";
"MEB_DQS_H4":   PN = "BY69"  !CDS_PN = "BY69";
"MEB_DQS_H5":   PN = "CF69"  !CDS_PN = "CF69";
"MEB_DQS_H6":   PN = "CM69"  !CDS_PN = "CM69";
"MEB_DQS_H7":   PN = "CV69"  !CDS_PN = "CV69";
"MEB_DQS_H8":   PN = "DD69"  !CDS_PN = "DD69";
"MEB_DQS_H9":   PN = "BV70"  !CDS_PN = "BV70";
"MEB_DQS_L0":   PN = "CE71"  !CDS_PN = "CE71";
"MEB_DQS_L1":   PN = "CL71"  !CDS_PN = "CL71";
"MEB_DQS_L2":   PN = "CU71"  !CDS_PN = "CU71";
"MEB_DQS_L3":   PN = "DC71"  !CDS_PN = "DC71";
"MEB_DQS_L4":   PN = "BW69"  !CDS_PN = "BW69";
"MEB_DQS_L5":   PN = "CE69"  !CDS_PN = "CE69";
"MEB_DQS_L6":   PN = "CL69"  !CDS_PN = "CL69";
"MEB_DQS_L7":   PN = "CU69"  !CDS_PN = "CU69";
"MEB_DQS_L8":   PN = "DC69"  !CDS_PN = "DC69";
"MEB_DQS_L9":   PN = "BW71"  !CDS_PN = "BW71";
"MEB_PAR":   PN = "BL71"  !CDS_PN = "BL71";
"TEST39E":   PN = "BF69"  !CDS_PN = "BF69";
BODY = "Q_RES","I314": #LOCATION = "R504" !CDS_LOCATION = "R504" &SEC = "1" #&CDS_SEC = "1";
"A":   PN = "1"  !CDS_PN = "1";
"B":   PN = "2"  !CDS_PN = "2";
DRAWING = "@t6g_mb_lib.t6g(sch_1):page42";
BODY = "GENOA_SP5","I159": #LOCATION = "U26" !CDS_LOCATION = "U26" &SEC = "6" #&CDS_SEC = "6";
"MF0_CLK_H":   PN = "BC67"  !CDS_PN = "BC67";
"MF0_CLK_L":   PN = "BD67"  !CDS_PN = "BD67";
"MF1_CLK_H":   PN = "BF67"  !CDS_PN = "BF67";
"MF1_CLK_L":   PN = "BG67"  !CDS_PN = "BG67";
"MF_ALERT_L":   PN = "AT65"  !CDS_PN = "AT65";
"MF_RESET_L":   PN = "AU66"  !CDS_PN = "AU66";
"MFA0_CS_L0":   PN = "AV67"  !CDS_PN = "AV67";
"MFA0_CS_L1":   PN = "AW66"  !CDS_PN = "AW66";
"MFA0_RSP_L":   PN = "BN66"  !CDS_PN = "BN66";
"MFA1_CS_L0":   PN = "AU67"  !CDS_PN = "AU67";
"MFA1_CS_L1":   PN = "AV65"  !CDS_PN = "AV65";
"MFA1_RSP_L":   PN = "BP65"  !CDS_PN = "BP65";
"MFA_CA0":   PN = "AW67"  !CDS_PN = "AW67";
"MFA_CA1":   PN = "AY67"  !CDS_PN = "AY67";
"MFA_CA2":   PN = "AY65"  !CDS_PN = "AY65";
"MFA_CA3":   PN = "BA66"  !CDS_PN = "BA66";
"MFA_CA4":   PN = "BA67"  !CDS_PN = "BA67";
"MFA_CA5":   PN = "BB67"  !CDS_PN = "BB67";
"MFA_CA6":   PN = "BB65"  !CDS_PN = "BB65";
"MFA_CHECK0":   PN = "AJ67"  !CDS_PN = "AJ67";
"MFA_CHECK1":   PN = "AK65"  !CDS_PN = "AK65";
"MFA_CHECK2":   PN = "AK67"  !CDS_PN = "AK67";
"MFA_CHECK3":   PN = "AL66"  !CDS_PN = "AL66";
"MFA_CHECK4":   PN = "AN67"  !CDS_PN = "AN67";
"MFA_CHECK5":   PN = "AP65"  !CDS_PN = "AP65";
"MFA_CHECK6":   PN = "AP67"  !CDS_PN = "AP67";
"MFA_CHECK7":   PN = "AR66"  !CDS_PN = "AR66";
"MFA_DATA0":   PN = "E67"  !CDS_PN = "E67";
"MFA_DATA1":   PN = "F65"  !CDS_PN = "F65";
"MFA_DATA2":   PN = "F67"  !CDS_PN = "F67";
"MFA_DATA3":   PN = "G66"  !CDS_PN = "G66";
"MFA_DATA4":   PN = "J67"  !CDS_PN = "J67";
"MFA_DATA5":   PN = "K65"  !CDS_PN = "K65";
"MFA_DATA6":   PN = "K67"  !CDS_PN = "K67";
"MFA_DATA7":   PN = "L66"  !CDS_PN = "L66";
"MFA_DATA8":   PN = "L67"  !CDS_PN = "L67";
"MFA_DATA9":   PN = "M65"  !CDS_PN = "M65";
"MFA_DATA10":   PN = "M67"  !CDS_PN = "M67";
"MFA_DATA11":   PN = "N66"  !CDS_PN = "N66";
"MFA_DATA12":   PN = "R67"  !CDS_PN = "R67";
"MFA_DATA13":   PN = "T65"  !CDS_PN = "T65";
"MFA_DATA14":   PN = "T67"  !CDS_PN = "T67";
"MFA_DATA15":   PN = "U66"  !CDS_PN = "U66";
"MFA_DATA16":   PN = "U67"  !CDS_PN = "U67";
"MFA_DATA17":   PN = "V65"  !CDS_PN = "V65";
"MFA_DATA18":   PN = "V67"  !CDS_PN = "V67";
"MFA_DATA19":   PN = "W66"  !CDS_PN = "W66";
"MFA_DATA20":   PN = "AA67"  !CDS_PN = "AA67";
"MFA_DATA21":   PN = "AB65"  !CDS_PN = "AB65";
"MFA_DATA22":   PN = "AB67"  !CDS_PN = "AB67";
"MFA_DATA23":   PN = "AC66"  !CDS_PN = "AC66";
"MFA_DATA24":   PN = "AC67"  !CDS_PN = "AC67";
"MFA_DATA25":   PN = "AD65"  !CDS_PN = "AD65";
"MFA_DATA26":   PN = "AD67"  !CDS_PN = "AD67";
"MFA_DATA27":   PN = "AE66"  !CDS_PN = "AE66";
"MFA_DATA28":   PN = "AG67"  !CDS_PN = "AG67";
"MFA_DATA29":   PN = "AH65"  !CDS_PN = "AH65";
"MFA_DATA30":   PN = "AH67"  !CDS_PN = "AH67";
"MFA_DATA31":   PN = "AJ66"  !CDS_PN = "AJ66";
"MFA_DQS_H0":   PN = "G67"  !CDS_PN = "G67";
"MFA_DQS_H1":   PN = "N67"  !CDS_PN = "N67";
"MFA_DQS_H2":   PN = "W67"  !CDS_PN = "W67";
"MFA_DQS_H3":   PN = "AE67"  !CDS_PN = "AE67";
"MFA_DQS_H4":   PN = "AL67"  !CDS_PN = "AL67";
"MFA_DQS_H5":   PN = "J66"  !CDS_PN = "J66";
"MFA_DQS_H6":   PN = "R66"  !CDS_PN = "R66";
"MFA_DQS_H7":   PN = "AA66"  !CDS_PN = "AA66";
"MFA_DQS_H8":   PN = "AG66"  !CDS_PN = "AG66";
"MFA_DQS_H9":   PN = "AN66"  !CDS_PN = "AN66";
"MFA_DQS_L0":   PN = "H67"  !CDS_PN = "H67";
"MFA_DQS_L1":   PN = "P67"  !CDS_PN = "P67";
"MFA_DQS_L2":   PN = "Y67"  !CDS_PN = "Y67";
"MFA_DQS_L3":   PN = "AF67"  !CDS_PN = "AF67";
"MFA_DQS_L4":   PN = "AM67"  !CDS_PN = "AM67";
"MFA_DQS_L5":   PN = "H65"  !CDS_PN = "H65";
"MFA_DQS_L6":   PN = "P65"  !CDS_PN = "P65";
"MFA_DQS_L7":   PN = "Y65"  !CDS_PN = "Y65";
"MFA_DQS_L8":   PN = "AF65"  !CDS_PN = "AF65";
"MFA_DQS_L9":   PN = "AM65"  !CDS_PN = "AM65";
"MFA_PAR":   PN = "BC66"  !CDS_PN = "BC66";
"MFB0_CS_L0":   PN = "BM65"  !CDS_PN = "BM65";
"MFB0_CS_L1":   PN = "BN67"  !CDS_PN = "BN67";
"MFB0_RSP_L":   PN = "BP67"  !CDS_PN = "BP67";
"MFB1_CS_L0":   PN = "BL66"  !CDS_PN = "BL66";
"MFB1_CS_L1":   PN = "BM67"  !CDS_PN = "BM67";
"MFB1_RSP_L":   PN = "BR67"  !CDS_PN = "BR67";
"MFB_CA0":   PN = "BG66"  !CDS_PN = "BG66";
"MFB_CA1":   PN = "BH65"  !CDS_PN = "BH65";
"MFB_CA2":   PN = "BH67"  !CDS_PN = "BH67";
"MFB_CA3":   PN = "BJ67"  !CDS_PN = "BJ67";
"MFB_CA4":   PN = "BJ66"  !CDS_PN = "BJ66";
"MFB_CA5":   PN = "BK65"  !CDS_PN = "BK65";
"MFB_CA6":   PN = "BK67"  !CDS_PN = "BK67";
"MFB_CHECK0":   PN = "BY67"  !CDS_PN = "BY67";
"MFB_CHECK1":   PN = "CA66"  !CDS_PN = "CA66";
"MFB_CHECK2":   PN = "CA67"  !CDS_PN = "CA67";
"MFB_CHECK3":   PN = "CB65"  !CDS_PN = "CB65";
"MFB_CHECK4":   PN = "BT67"  !CDS_PN = "BT67";
"MFB_CHECK5":   PN = "BU66"  !CDS_PN = "BU66";
"MFB_CHECK6":   PN = "BU67"  !CDS_PN = "BU67";
"MFB_CHECK7":   PN = "BV65"  !CDS_PN = "BV65";
"MFB_DATA0":   PN = "CB67"  !CDS_PN = "CB67";
"MFB_DATA1":   PN = "CC66"  !CDS_PN = "CC66";
"MFB_DATA2":   PN = "CC67"  !CDS_PN = "CC67";
"MFB_DATA3":   PN = "CD65"  !CDS_PN = "CD65";
"MFB_DATA4":   PN = "CF67"  !CDS_PN = "CF67";
"MFB_DATA5":   PN = "CG66"  !CDS_PN = "CG66";
"MFB_DATA6":   PN = "CG67"  !CDS_PN = "CG67";
"MFB_DATA7":   PN = "CH65"  !CDS_PN = "CH65";
"MFB_DATA8":   PN = "CH67"  !CDS_PN = "CH67";
"MFB_DATA9":   PN = "CJ66"  !CDS_PN = "CJ66";
"MFB_DATA10":   PN = "CJ67"  !CDS_PN = "CJ67";
"MFB_DATA11":   PN = "CK65"  !CDS_PN = "CK65";
"MFB_DATA12":   PN = "CM67"  !CDS_PN = "CM67";
"MFB_DATA13":   PN = "CN66"  !CDS_PN = "CN66";
"MFB_DATA14":   PN = "CN67"  !CDS_PN = "CN67";
"MFB_DATA15":   PN = "CP65"  !CDS_PN = "CP65";
"MFB_DATA16":   PN = "CP67"  !CDS_PN = "CP67";
"MFB_DATA17":   PN = "CR66"  !CDS_PN = "CR66";
"MFB_DATA18":   PN = "CR67"  !CDS_PN = "CR67";
"MFB_DATA19":   PN = "CT65"  !CDS_PN = "CT65";
"MFB_DATA20":   PN = "CV67"  !CDS_PN = "CV67";
"MFB_DATA21":   PN = "CW66"  !CDS_PN = "CW66";
"MFB_DATA22":   PN = "CW67"  !CDS_PN = "CW67";
"MFB_DATA23":   PN = "CY65"  !CDS_PN = "CY65";
"MFB_DATA24":   PN = "CY67"  !CDS_PN = "CY67";
"MFB_DATA25":   PN = "DA66"  !CDS_PN = "DA66";
"MFB_DATA26":   PN = "DA67"  !CDS_PN = "DA67";
"MFB_DATA27":   PN = "DB65"  !CDS_PN = "DB65";
"MFB_DATA28":   PN = "DD67"  !CDS_PN = "DD67";
"MFB_DATA29":   PN = "DE66"  !CDS_PN = "DE66";
"MFB_DATA30":   PN = "DE67"  !CDS_PN = "DE67";
"MFB_DATA31":   PN = "DF67"  !CDS_PN = "DF67";
"MFB_DQS_H0":   PN = "CD67"  !CDS_PN = "CD67";
"MFB_DQS_H1":   PN = "CK67"  !CDS_PN = "CK67";
"MFB_DQS_H2":   PN = "CT67"  !CDS_PN = "CT67";
"MFB_DQS_H3":   PN = "DB67"  !CDS_PN = "DB67";
"MFB_DQS_H4":   PN = "BY65"  !CDS_PN = "BY65";
"MFB_DQS_H5":   PN = "CF65"  !CDS_PN = "CF65";
"MFB_DQS_H6":   PN = "CM65"  !CDS_PN = "CM65";
"MFB_DQS_H7":   PN = "CV65"  !CDS_PN = "CV65";
"MFB_DQS_H8":   PN = "DD65"  !CDS_PN = "DD65";
"MFB_DQS_H9":   PN = "BV67"  !CDS_PN = "BV67";
"MFB_DQS_L0":   PN = "CE67"  !CDS_PN = "CE67";
"MFB_DQS_L1":   PN = "CL67"  !CDS_PN = "CL67";
"MFB_DQS_L2":   PN = "CU67"  !CDS_PN = "CU67";
"MFB_DQS_L3":   PN = "DC67"  !CDS_PN = "DC67";
"MFB_DQS_L4":   PN = "BW66"  !CDS_PN = "BW66";
"MFB_DQS_L5":   PN = "CE66"  !CDS_PN = "CE66";
"MFB_DQS_L6":   PN = "CL66"  !CDS_PN = "CL66";
"MFB_DQS_L7":   PN = "CU66"  !CDS_PN = "CU66";
"MFB_DQS_L8":   PN = "DC66"  !CDS_PN = "DC66";
"MFB_DQS_L9":   PN = "BW67"  !CDS_PN = "BW67";
"MFB_PAR":   PN = "BL67"  !CDS_PN = "BL67";
"TEST39F":   PN = "BF65"  !CDS_PN = "BF65";
BODY = "Q_RES","I314": #LOCATION = "R505" !CDS_LOCATION = "R505" &SEC = "1" #&CDS_SEC = "1";
"A":   PN = "1"  !CDS_PN = "1";
"B":   PN = "2"  !CDS_PN = "2";
DRAWING = "@t6g_mb_lib.t6g(sch_1):page43";
BODY = "GENOA_SP5","I167": #LOCATION = "U26" !CDS_LOCATION = "U26" &SEC = "7" #&CDS_SEC = "7";
"MG0_CLK_H":   PN = "BC2"  !CDS_PN = "BC2";
"MG0_CLK_L":   PN = "BD2"  !CDS_PN = "BD2";
"MG1_CLK_H":   PN = "BF2"  !CDS_PN = "BF2";
"MG1_CLK_L":   PN = "BG2"  !CDS_PN = "BG2";
"MG_ALERT_L":   PN = "AR2"  !CDS_PN = "AR2";
"MG_RESET_L":   PN = "AT2"  !CDS_PN = "AT2";
"MGA0_CS_L0":   PN = "AU2"  !CDS_PN = "AU2";
"MGA0_CS_L1":   PN = "AV4"  !CDS_PN = "AV4";
"MGA0_RSP_L":   PN = "BN3"  !CDS_PN = "BN3";
"MGA1_CS_L0":   PN = "AV2"  !CDS_PN = "AV2";
"MGA1_CS_L1":   PN = "AW3"  !CDS_PN = "AW3";
"MGA1_RSP_L":   PN = "BP4"  !CDS_PN = "BP4";
"MGA_CA0":   PN = "AW2"  !CDS_PN = "AW2";
"MGA_CA1":   PN = "AY2"  !CDS_PN = "AY2";
"MGA_CA2":   PN = "AY4"  !CDS_PN = "AY4";
"MGA_CA3":   PN = "BA3"  !CDS_PN = "BA3";
"MGA_CA4":   PN = "BA2"  !CDS_PN = "BA2";
"MGA_CA5":   PN = "BB2"  !CDS_PN = "BB2";
"MGA_CA6":   PN = "BB4"  !CDS_PN = "BB4";
"MGA_CHECK0":   PN = "AJ2"  !CDS_PN = "AJ2";
"MGA_CHECK1":   PN = "AK4"  !CDS_PN = "AK4";
"MGA_CHECK2":   PN = "AK2"  !CDS_PN = "AK2";
"MGA_CHECK3":   PN = "AL3"  !CDS_PN = "AL3";
"MGA_CHECK4":   PN = "AN2"  !CDS_PN = "AN2";
"MGA_CHECK5":   PN = "AP4"  !CDS_PN = "AP4";
"MGA_CHECK6":   PN = "AP2"  !CDS_PN = "AP2";
"MGA_CHECK7":   PN = "AR3"  !CDS_PN = "AR3";
"MGA_DATA0":   PN = "E2"  !CDS_PN = "E2";
"MGA_DATA1":   PN = "F4"  !CDS_PN = "F4";
"MGA_DATA2":   PN = "F2"  !CDS_PN = "F2";
"MGA_DATA3":   PN = "G3"  !CDS_PN = "G3";
"MGA_DATA4":   PN = "J2"  !CDS_PN = "J2";
"MGA_DATA5":   PN = "K4"  !CDS_PN = "K4";
"MGA_DATA6":   PN = "K2"  !CDS_PN = "K2";
"MGA_DATA7":   PN = "L3"  !CDS_PN = "L3";
"MGA_DATA8":   PN = "L2"  !CDS_PN = "L2";
"MGA_DATA9":   PN = "M4"  !CDS_PN = "M4";
"MGA_DATA10":   PN = "M2"  !CDS_PN = "M2";
"MGA_DATA11":   PN = "N3"  !CDS_PN = "N3";
"MGA_DATA12":   PN = "R2"  !CDS_PN = "R2";
"MGA_DATA13":   PN = "T4"  !CDS_PN = "T4";
"MGA_DATA14":   PN = "T2"  !CDS_PN = "T2";
"MGA_DATA15":   PN = "U3"  !CDS_PN = "U3";
"MGA_DATA16":   PN = "U2"  !CDS_PN = "U2";
"MGA_DATA17":   PN = "V4"  !CDS_PN = "V4";
"MGA_DATA18":   PN = "V2"  !CDS_PN = "V2";
"MGA_DATA19":   PN = "W3"  !CDS_PN = "W3";
"MGA_DATA20":   PN = "AA2"  !CDS_PN = "AA2";
"MGA_DATA21":   PN = "AB4"  !CDS_PN = "AB4";
"MGA_DATA22":   PN = "AB2"  !CDS_PN = "AB2";
"MGA_DATA23":   PN = "AC3"  !CDS_PN = "AC3";
"MGA_DATA24":   PN = "AC2"  !CDS_PN = "AC2";
"MGA_DATA25":   PN = "AD4"  !CDS_PN = "AD4";
"MGA_DATA26":   PN = "AD2"  !CDS_PN = "AD2";
"MGA_DATA27":   PN = "AE3"  !CDS_PN = "AE3";
"MGA_DATA28":   PN = "AG2"  !CDS_PN = "AG2";
"MGA_DATA29":   PN = "AH4"  !CDS_PN = "AH4";
"MGA_DATA30":   PN = "AH2"  !CDS_PN = "AH2";
"MGA_DATA31":   PN = "AJ3"  !CDS_PN = "AJ3";
"MGA_DQS_H0":   PN = "G2"  !CDS_PN = "G2";
"MGA_DQS_H1":   PN = "N2"  !CDS_PN = "N2";
"MGA_DQS_H2":   PN = "W2"  !CDS_PN = "W2";
"MGA_DQS_H3":   PN = "AE2"  !CDS_PN = "AE2";
"MGA_DQS_H4":   PN = "AL2"  !CDS_PN = "AL2";
"MGA_DQS_H5":   PN = "J3"  !CDS_PN = "J3";
"MGA_DQS_H6":   PN = "R3"  !CDS_PN = "R3";
"MGA_DQS_H7":   PN = "AA3"  !CDS_PN = "AA3";
"MGA_DQS_H8":   PN = "AG3"  !CDS_PN = "AG3";
"MGA_DQS_H9":   PN = "AN3"  !CDS_PN = "AN3";
"MGA_DQS_L0":   PN = "H2"  !CDS_PN = "H2";
"MGA_DQS_L1":   PN = "P2"  !CDS_PN = "P2";
"MGA_DQS_L2":   PN = "Y2"  !CDS_PN = "Y2";
"MGA_DQS_L3":   PN = "AF2"  !CDS_PN = "AF2";
"MGA_DQS_L4":   PN = "AM2"  !CDS_PN = "AM2";
"MGA_DQS_L5":   PN = "H4"  !CDS_PN = "H4";
"MGA_DQS_L6":   PN = "P4"  !CDS_PN = "P4";
"MGA_DQS_L7":   PN = "Y4"  !CDS_PN = "Y4";
"MGA_DQS_L8":   PN = "AF4"  !CDS_PN = "AF4";
"MGA_DQS_L9":   PN = "AM4"  !CDS_PN = "AM4";
"MGA_PAR":   PN = "BC3"  !CDS_PN = "BC3";
"MGB0_CS_L0":   PN = "BM4"  !CDS_PN = "BM4";
"MGB0_CS_L1":   PN = "BN2"  !CDS_PN = "BN2";
"MGB0_RSP_L":   PN = "BP2"  !CDS_PN = "BP2";
"MGB1_CS_L0":   PN = "BL2"  !CDS_PN = "BL2";
"MGB1_CS_L1":   PN = "BM2"  !CDS_PN = "BM2";
"MGB1_RSP_L":   PN = "BR2"  !CDS_PN = "BR2";
"MGB_CA0":   PN = "BG3"  !CDS_PN = "BG3";
"MGB_CA1":   PN = "BH4"  !CDS_PN = "BH4";
"MGB_CA2":   PN = "BH2"  !CDS_PN = "BH2";
"MGB_CA3":   PN = "BJ2"  !CDS_PN = "BJ2";
"MGB_CA4":   PN = "BJ3"  !CDS_PN = "BJ3";
"MGB_CA5":   PN = "BK4"  !CDS_PN = "BK4";
"MGB_CA6":   PN = "BK2"  !CDS_PN = "BK2";
"MGB_CHECK0":   PN = "BY2"  !CDS_PN = "BY2";
"MGB_CHECK1":   PN = "CA3"  !CDS_PN = "CA3";
"MGB_CHECK2":   PN = "CA2"  !CDS_PN = "CA2";
"MGB_CHECK3":   PN = "CB4"  !CDS_PN = "CB4";
"MGB_CHECK4":   PN = "BT2"  !CDS_PN = "BT2";
"MGB_CHECK5":   PN = "BU3"  !CDS_PN = "BU3";
"MGB_CHECK6":   PN = "BU2"  !CDS_PN = "BU2";
"MGB_CHECK7":   PN = "BV4"  !CDS_PN = "BV4";
"MGB_DATA0":   PN = "CB2"  !CDS_PN = "CB2";
"MGB_DATA1":   PN = "CC3"  !CDS_PN = "CC3";
"MGB_DATA2":   PN = "CC2"  !CDS_PN = "CC2";
"MGB_DATA3":   PN = "CD4"  !CDS_PN = "CD4";
"MGB_DATA4":   PN = "CF2"  !CDS_PN = "CF2";
"MGB_DATA5":   PN = "CG3"  !CDS_PN = "CG3";
"MGB_DATA6":   PN = "CG2"  !CDS_PN = "CG2";
"MGB_DATA7":   PN = "CH4"  !CDS_PN = "CH4";
"MGB_DATA8":   PN = "CH2"  !CDS_PN = "CH2";
"MGB_DATA9":   PN = "CJ3"  !CDS_PN = "CJ3";
"MGB_DATA10":   PN = "CJ2"  !CDS_PN = "CJ2";
"MGB_DATA11":   PN = "CK4"  !CDS_PN = "CK4";
"MGB_DATA12":   PN = "CM2"  !CDS_PN = "CM2";
"MGB_DATA13":   PN = "CN3"  !CDS_PN = "CN3";
"MGB_DATA14":   PN = "CN2"  !CDS_PN = "CN2";
"MGB_DATA15":   PN = "CP4"  !CDS_PN = "CP4";
"MGB_DATA16":   PN = "CP2"  !CDS_PN = "CP2";
"MGB_DATA17":   PN = "CR3"  !CDS_PN = "CR3";
"MGB_DATA18":   PN = "CR2"  !CDS_PN = "CR2";
"MGB_DATA19":   PN = "CT4"  !CDS_PN = "CT4";
"MGB_DATA20":   PN = "CV2"  !CDS_PN = "CV2";
"MGB_DATA21":   PN = "CW3"  !CDS_PN = "CW3";
"MGB_DATA22":   PN = "CW2"  !CDS_PN = "CW2";
"MGB_DATA23":   PN = "CY4"  !CDS_PN = "CY4";
"MGB_DATA24":   PN = "CY2"  !CDS_PN = "CY2";
"MGB_DATA25":   PN = "DA3"  !CDS_PN = "DA3";
"MGB_DATA26":   PN = "DA2"  !CDS_PN = "DA2";
"MGB_DATA27":   PN = "DB4"  !CDS_PN = "DB4";
"MGB_DATA28":   PN = "DD2"  !CDS_PN = "DD2";
"MGB_DATA29":   PN = "DE3"  !CDS_PN = "DE3";
"MGB_DATA30":   PN = "DE2"  !CDS_PN = "DE2";
"MGB_DATA31":   PN = "DF2"  !CDS_PN = "DF2";
"MGB_DQS_H0":   PN = "CD2"  !CDS_PN = "CD2";
"MGB_DQS_H1":   PN = "CK2"  !CDS_PN = "CK2";
"MGB_DQS_H2":   PN = "CT2"  !CDS_PN = "CT2";
"MGB_DQS_H3":   PN = "DB2"  !CDS_PN = "DB2";
"MGB_DQS_H4":   PN = "BY4"  !CDS_PN = "BY4";
"MGB_DQS_H5":   PN = "CF4"  !CDS_PN = "CF4";
"MGB_DQS_H6":   PN = "CM4"  !CDS_PN = "CM4";
"MGB_DQS_H7":   PN = "CV4"  !CDS_PN = "CV4";
"MGB_DQS_H8":   PN = "DD4"  !CDS_PN = "DD4";
"MGB_DQS_H9":   PN = "BV2"  !CDS_PN = "BV2";
"MGB_DQS_L0":   PN = "CE2"  !CDS_PN = "CE2";
"MGB_DQS_L1":   PN = "CL2"  !CDS_PN = "CL2";
"MGB_DQS_L2":   PN = "CU2"  !CDS_PN = "CU2";
"MGB_DQS_L3":   PN = "DC2"  !CDS_PN = "DC2";
"MGB_DQS_L4":   PN = "BW3"  !CDS_PN = "BW3";
"MGB_DQS_L5":   PN = "CE3"  !CDS_PN = "CE3";
"MGB_DQS_L6":   PN = "CL3"  !CDS_PN = "CL3";
"MGB_DQS_L7":   PN = "CU3"  !CDS_PN = "CU3";
"MGB_DQS_L8":   PN = "DC3"  !CDS_PN = "DC3";
"MGB_DQS_L9":   PN = "BW2"  !CDS_PN = "BW2";
"MGB_PAR":   PN = "BL3"  !CDS_PN = "BL3";
"TEST39G":   PN = "BF4"  !CDS_PN = "BF4";
BODY = "Q_RES","I322": #LOCATION = "R506" !CDS_LOCATION = "R506" &SEC = "1" #&CDS_SEC = "1";
"A":   PN = "1"  !CDS_PN = "1";
"B":   PN = "2"  !CDS_PN = "2";
DRAWING = "@t6g_mb_lib.t6g(sch_1):page44";
BODY = "GENOA_SP5","I159": #LOCATION = "U26" !CDS_LOCATION = "U26" &SEC = "8" #&CDS_SEC = "8";
"MH0_CLK_H":   PN = "BC12"  !CDS_PN = "BC12";
"MH0_CLK_L":   PN = "BD13"  !CDS_PN = "BD13";
"MH1_CLK_H":   PN = "BF13"  !CDS_PN = "BF13";
"MH1_CLK_L":   PN = "BG12"  !CDS_PN = "BG12";
"MH_ALERT_L":   PN = "AT14"  !CDS_PN = "AT14";
"MH_RESET_L":   PN = "AU14"  !CDS_PN = "AU14";
"MHA0_CS_L0":   PN = "AU12"  !CDS_PN = "AU12";
"MHA0_CS_L1":   PN = "AV14"  !CDS_PN = "AV14";
"MHA0_RSP_L":   PN = "BN14"  !CDS_PN = "BN14";
"MHA1_CS_L0":   PN = "AV13"  !CDS_PN = "AV13";
"MHA1_CS_L1":   PN = "AW14"  !CDS_PN = "AW14";
"MHA1_RSP_L":   PN = "BP14"  !CDS_PN = "BP14";
"MHA_CA0":   PN = "AW12"  !CDS_PN = "AW12";
"MHA_CA1":   PN = "AY13"  !CDS_PN = "AY13";
"MHA_CA2":   PN = "AY14"  !CDS_PN = "AY14";
"MHA_CA3":   PN = "BA14"  !CDS_PN = "BA14";
"MHA_CA4":   PN = "BA12"  !CDS_PN = "BA12";
"MHA_CA5":   PN = "BB13"  !CDS_PN = "BB13";
"MHA_CA6":   PN = "BB14"  !CDS_PN = "BB14";
"MHA_CHECK0":   PN = "AJ12"  !CDS_PN = "AJ12";
"MHA_CHECK1":   PN = "AK14"  !CDS_PN = "AK14";
"MHA_CHECK2":   PN = "AK13"  !CDS_PN = "AK13";
"MHA_CHECK3":   PN = "AL14"  !CDS_PN = "AL14";
"MHA_CHECK4":   PN = "AN12"  !CDS_PN = "AN12";
"MHA_CHECK5":   PN = "AP14"  !CDS_PN = "AP14";
"MHA_CHECK6":   PN = "AP13"  !CDS_PN = "AP13";
"MHA_CHECK7":   PN = "AR14"  !CDS_PN = "AR14";
"MHA_DATA0":   PN = "E12"  !CDS_PN = "E12";
"MHA_DATA1":   PN = "F14"  !CDS_PN = "F14";
"MHA_DATA2":   PN = "F13"  !CDS_PN = "F13";
"MHA_DATA3":   PN = "G14"  !CDS_PN = "G14";
"MHA_DATA4":   PN = "J12"  !CDS_PN = "J12";
"MHA_DATA5":   PN = "K14"  !CDS_PN = "K14";
"MHA_DATA6":   PN = "K13"  !CDS_PN = "K13";
"MHA_DATA7":   PN = "L14"  !CDS_PN = "L14";
"MHA_DATA8":   PN = "L12"  !CDS_PN = "L12";
"MHA_DATA9":   PN = "M14"  !CDS_PN = "M14";
"MHA_DATA10":   PN = "M13"  !CDS_PN = "M13";
"MHA_DATA11":   PN = "N14"  !CDS_PN = "N14";
"MHA_DATA12":   PN = "R12"  !CDS_PN = "R12";
"MHA_DATA13":   PN = "T14"  !CDS_PN = "T14";
"MHA_DATA14":   PN = "T13"  !CDS_PN = "T13";
"MHA_DATA15":   PN = "U14"  !CDS_PN = "U14";
"MHA_DATA16":   PN = "U12"  !CDS_PN = "U12";
"MHA_DATA17":   PN = "V14"  !CDS_PN = "V14";
"MHA_DATA18":   PN = "V13"  !CDS_PN = "V13";
"MHA_DATA19":   PN = "W14"  !CDS_PN = "W14";
"MHA_DATA20":   PN = "AA12"  !CDS_PN = "AA12";
"MHA_DATA21":   PN = "AB14"  !CDS_PN = "AB14";
"MHA_DATA22":   PN = "AB13"  !CDS_PN = "AB13";
"MHA_DATA23":   PN = "AC14"  !CDS_PN = "AC14";
"MHA_DATA24":   PN = "AC12"  !CDS_PN = "AC12";
"MHA_DATA25":   PN = "AD14"  !CDS_PN = "AD14";
"MHA_DATA26":   PN = "AD13"  !CDS_PN = "AD13";
"MHA_DATA27":   PN = "AE14"  !CDS_PN = "AE14";
"MHA_DATA28":   PN = "AG12"  !CDS_PN = "AG12";
"MHA_DATA29":   PN = "AH14"  !CDS_PN = "AH14";
"MHA_DATA30":   PN = "AH13"  !CDS_PN = "AH13";
"MHA_DATA31":   PN = "AJ14"  !CDS_PN = "AJ14";
"MHA_DQS_H0":   PN = "G12"  !CDS_PN = "G12";
"MHA_DQS_H1":   PN = "N12"  !CDS_PN = "N12";
"MHA_DQS_H2":   PN = "W12"  !CDS_PN = "W12";
"MHA_DQS_H3":   PN = "AE12"  !CDS_PN = "AE12";
"MHA_DQS_H4":   PN = "AL12"  !CDS_PN = "AL12";
"MHA_DQS_H5":   PN = "J14"  !CDS_PN = "J14";
"MHA_DQS_H6":   PN = "R14"  !CDS_PN = "R14";
"MHA_DQS_H7":   PN = "AA14"  !CDS_PN = "AA14";
"MHA_DQS_H8":   PN = "AG14"  !CDS_PN = "AG14";
"MHA_DQS_H9":   PN = "AN14"  !CDS_PN = "AN14";
"MHA_DQS_L0":   PN = "H13"  !CDS_PN = "H13";
"MHA_DQS_L1":   PN = "P13"  !CDS_PN = "P13";
"MHA_DQS_L2":   PN = "Y13"  !CDS_PN = "Y13";
"MHA_DQS_L3":   PN = "AF13"  !CDS_PN = "AF13";
"MHA_DQS_L4":   PN = "AM13"  !CDS_PN = "AM13";
"MHA_DQS_L5":   PN = "H14"  !CDS_PN = "H14";
"MHA_DQS_L6":   PN = "P14"  !CDS_PN = "P14";
"MHA_DQS_L7":   PN = "Y14"  !CDS_PN = "Y14";
"MHA_DQS_L8":   PN = "AF14"  !CDS_PN = "AF14";
"MHA_DQS_L9":   PN = "AM14"  !CDS_PN = "AM14";
"MHA_PAR":   PN = "BC14"  !CDS_PN = "BC14";
"MHB0_CS_L0":   PN = "BM14"  !CDS_PN = "BM14";
"MHB0_CS_L1":   PN = "BN12"  !CDS_PN = "BN12";
"MHB0_RSP_L":   PN = "BP13"  !CDS_PN = "BP13";
"MHB1_CS_L0":   PN = "BL12"  !CDS_PN = "BL12";
"MHB1_CS_L1":   PN = "BM13"  !CDS_PN = "BM13";
"MHB1_RSP_L":   PN = "BR12"  !CDS_PN = "BR12";
"MHB_CA0":   PN = "BG14"  !CDS_PN = "BG14";
"MHB_CA1":   PN = "BH14"  !CDS_PN = "BH14";
"MHB_CA2":   PN = "BH13"  !CDS_PN = "BH13";
"MHB_CA3":   PN = "BJ12"  !CDS_PN = "BJ12";
"MHB_CA4":   PN = "BJ14"  !CDS_PN = "BJ14";
"MHB_CA5":   PN = "BK14"  !CDS_PN = "BK14";
"MHB_CA6":   PN = "BK13"  !CDS_PN = "BK13";
"MHB_CHECK0":   PN = "BY13"  !CDS_PN = "BY13";
"MHB_CHECK1":   PN = "CA14"  !CDS_PN = "CA14";
"MHB_CHECK2":   PN = "CA12"  !CDS_PN = "CA12";
"MHB_CHECK3":   PN = "CB14"  !CDS_PN = "CB14";
"MHB_CHECK4":   PN = "BT13"  !CDS_PN = "BT13";
"MHB_CHECK5":   PN = "BU14"  !CDS_PN = "BU14";
"MHB_CHECK6":   PN = "BU12"  !CDS_PN = "BU12";
"MHB_CHECK7":   PN = "BV14"  !CDS_PN = "BV14";
"MHB_DATA0":   PN = "CB13"  !CDS_PN = "CB13";
"MHB_DATA1":   PN = "CC14"  !CDS_PN = "CC14";
"MHB_DATA2":   PN = "CC12"  !CDS_PN = "CC12";
"MHB_DATA3":   PN = "CD14"  !CDS_PN = "CD14";
"MHB_DATA4":   PN = "CF13"  !CDS_PN = "CF13";
"MHB_DATA5":   PN = "CG14"  !CDS_PN = "CG14";
"MHB_DATA6":   PN = "CG12"  !CDS_PN = "CG12";
"MHB_DATA7":   PN = "CH14"  !CDS_PN = "CH14";
"MHB_DATA8":   PN = "CH13"  !CDS_PN = "CH13";
"MHB_DATA9":   PN = "CJ14"  !CDS_PN = "CJ14";
"MHB_DATA10":   PN = "CJ12"  !CDS_PN = "CJ12";
"MHB_DATA11":   PN = "CK14"  !CDS_PN = "CK14";
"MHB_DATA12":   PN = "CM13"  !CDS_PN = "CM13";
"MHB_DATA13":   PN = "CN14"  !CDS_PN = "CN14";
"MHB_DATA14":   PN = "CN12"  !CDS_PN = "CN12";
"MHB_DATA15":   PN = "CP14"  !CDS_PN = "CP14";
"MHB_DATA16":   PN = "CP13"  !CDS_PN = "CP13";
"MHB_DATA17":   PN = "CR14"  !CDS_PN = "CR14";
"MHB_DATA18":   PN = "CR12"  !CDS_PN = "CR12";
"MHB_DATA19":   PN = "CT14"  !CDS_PN = "CT14";
"MHB_DATA20":   PN = "CV13"  !CDS_PN = "CV13";
"MHB_DATA21":   PN = "CW14"  !CDS_PN = "CW14";
"MHB_DATA22":   PN = "CW12"  !CDS_PN = "CW12";
"MHB_DATA23":   PN = "CY14"  !CDS_PN = "CY14";
"MHB_DATA24":   PN = "CY13"  !CDS_PN = "CY13";
"MHB_DATA25":   PN = "DA14"  !CDS_PN = "DA14";
"MHB_DATA26":   PN = "DA12"  !CDS_PN = "DA12";
"MHB_DATA27":   PN = "DB14"  !CDS_PN = "DB14";
"MHB_DATA28":   PN = "DD13"  !CDS_PN = "DD13";
"MHB_DATA29":   PN = "DE14"  !CDS_PN = "DE14";
"MHB_DATA30":   PN = "DE12"  !CDS_PN = "DE12";
"MHB_DATA31":   PN = "DF14"  !CDS_PN = "DF14";
"MHB_DQS_H0":   PN = "CD13"  !CDS_PN = "CD13";
"MHB_DQS_H1":   PN = "CK13"  !CDS_PN = "CK13";
"MHB_DQS_H2":   PN = "CT13"  !CDS_PN = "CT13";
"MHB_DQS_H3":   PN = "DB13"  !CDS_PN = "DB13";
"MHB_DQS_H4":   PN = "BY14"  !CDS_PN = "BY14";
"MHB_DQS_H5":   PN = "CF14"  !CDS_PN = "CF14";
"MHB_DQS_H6":   PN = "CM14"  !CDS_PN = "CM14";
"MHB_DQS_H7":   PN = "CV14"  !CDS_PN = "CV14";
"MHB_DQS_H8":   PN = "DD14"  !CDS_PN = "DD14";
"MHB_DQS_H9":   PN = "BV13"  !CDS_PN = "BV13";
"MHB_DQS_L0":   PN = "CE12"  !CDS_PN = "CE12";
"MHB_DQS_L1":   PN = "CL12"  !CDS_PN = "CL12";
"MHB_DQS_L2":   PN = "CU12"  !CDS_PN = "CU12";
"MHB_DQS_L3":   PN = "DC12"  !CDS_PN = "DC12";
"MHB_DQS_L4":   PN = "BW14"  !CDS_PN = "BW14";
"MHB_DQS_L5":   PN = "CE14"  !CDS_PN = "CE14";
"MHB_DQS_L6":   PN = "CL14"  !CDS_PN = "CL14";
"MHB_DQS_L7":   PN = "CU14"  !CDS_PN = "CU14";
"MHB_DQS_L8":   PN = "DC14"  !CDS_PN = "DC14";
"MHB_DQS_L9":   PN = "BW12"  !CDS_PN = "BW12";
"MHB_PAR":   PN = "BL14"  !CDS_PN = "BL14";
"TEST39H":   PN = "BF14"  !CDS_PN = "BF14";
BODY = "Q_RES","I314": #LOCATION = "R507" !CDS_LOCATION = "R507" &SEC = "1" #&CDS_SEC = "1";
"A":   PN = "1"  !CDS_PN = "1";
"B":   PN = "2"  !CDS_PN = "2";
DRAWING = "@t6g_mb_lib.t6g(sch_1):page45";
BODY = "GENOA_SP5","I159": #LOCATION = "U26" !CDS_LOCATION = "U26" &SEC = "9" #&CDS_SEC = "9";
"MI0_CLK_H":   PN = "BC19"  !CDS_PN = "BC19";
"MI0_CLK_L":   PN = "BD20"  !CDS_PN = "BD20";
"MI1_CLK_H":   PN = "BF20"  !CDS_PN = "BF20";
"MI1_CLK_L":   PN = "BG19"  !CDS_PN = "BG19";
"MI_ALERT_L":   PN = "AT21"  !CDS_PN = "AT21";
"MI_RESET_L":   PN = "AU21"  !CDS_PN = "AU21";
"MIA0_CS_L0":   PN = "AU19"  !CDS_PN = "AU19";
"MIA0_CS_L1":   PN = "AV21"  !CDS_PN = "AV21";
"MIA0_RSP_L":   PN = "BN21"  !CDS_PN = "BN21";
"MIA1_CS_L0":   PN = "AV20"  !CDS_PN = "AV20";
"MIA1_CS_L1":   PN = "AW21"  !CDS_PN = "AW21";
"MIA1_RSP_L":   PN = "BP21"  !CDS_PN = "BP21";
"MIA_CA0":   PN = "AW19"  !CDS_PN = "AW19";
"MIA_CA1":   PN = "AY20"  !CDS_PN = "AY20";
"MIA_CA2":   PN = "AY21"  !CDS_PN = "AY21";
"MIA_CA3":   PN = "BA21"  !CDS_PN = "BA21";
"MIA_CA4":   PN = "BA19"  !CDS_PN = "BA19";
"MIA_CA5":   PN = "BB20"  !CDS_PN = "BB20";
"MIA_CA6":   PN = "BB21"  !CDS_PN = "BB21";
"MIA_CHECK0":   PN = "AJ19"  !CDS_PN = "AJ19";
"MIA_CHECK1":   PN = "AK21"  !CDS_PN = "AK21";
"MIA_CHECK2":   PN = "AK20"  !CDS_PN = "AK20";
"MIA_CHECK3":   PN = "AL21"  !CDS_PN = "AL21";
"MIA_CHECK4":   PN = "AN19"  !CDS_PN = "AN19";
"MIA_CHECK5":   PN = "AP21"  !CDS_PN = "AP21";
"MIA_CHECK6":   PN = "AP20"  !CDS_PN = "AP20";
"MIA_CHECK7":   PN = "AR21"  !CDS_PN = "AR21";
"MIA_DATA0":   PN = "E19"  !CDS_PN = "E19";
"MIA_DATA1":   PN = "F21"  !CDS_PN = "F21";
"MIA_DATA2":   PN = "F20"  !CDS_PN = "F20";
"MIA_DATA3":   PN = "G21"  !CDS_PN = "G21";
"MIA_DATA4":   PN = "J19"  !CDS_PN = "J19";
"MIA_DATA5":   PN = "K21"  !CDS_PN = "K21";
"MIA_DATA6":   PN = "K20"  !CDS_PN = "K20";
"MIA_DATA7":   PN = "L21"  !CDS_PN = "L21";
"MIA_DATA8":   PN = "L19"  !CDS_PN = "L19";
"MIA_DATA9":   PN = "M21"  !CDS_PN = "M21";
"MIA_DATA10":   PN = "M20"  !CDS_PN = "M20";
"MIA_DATA11":   PN = "N21"  !CDS_PN = "N21";
"MIA_DATA12":   PN = "R19"  !CDS_PN = "R19";
"MIA_DATA13":   PN = "T21"  !CDS_PN = "T21";
"MIA_DATA14":   PN = "T20"  !CDS_PN = "T20";
"MIA_DATA15":   PN = "U21"  !CDS_PN = "U21";
"MIA_DATA16":   PN = "U19"  !CDS_PN = "U19";
"MIA_DATA17":   PN = "V21"  !CDS_PN = "V21";
"MIA_DATA18":   PN = "V20"  !CDS_PN = "V20";
"MIA_DATA19":   PN = "W21"  !CDS_PN = "W21";
"MIA_DATA20":   PN = "AA19"  !CDS_PN = "AA19";
"MIA_DATA21":   PN = "AB21"  !CDS_PN = "AB21";
"MIA_DATA22":   PN = "AB20"  !CDS_PN = "AB20";
"MIA_DATA23":   PN = "AC21"  !CDS_PN = "AC21";
"MIA_DATA24":   PN = "AC19"  !CDS_PN = "AC19";
"MIA_DATA25":   PN = "AD21"  !CDS_PN = "AD21";
"MIA_DATA26":   PN = "AD20"  !CDS_PN = "AD20";
"MIA_DATA27":   PN = "AE21"  !CDS_PN = "AE21";
"MIA_DATA28":   PN = "AG19"  !CDS_PN = "AG19";
"MIA_DATA29":   PN = "AH21"  !CDS_PN = "AH21";
"MIA_DATA30":   PN = "AH20"  !CDS_PN = "AH20";
"MIA_DATA31":   PN = "AJ21"  !CDS_PN = "AJ21";
"MIA_DQS_H0":   PN = "G19"  !CDS_PN = "G19";
"MIA_DQS_H1":   PN = "N19"  !CDS_PN = "N19";
"MIA_DQS_H2":   PN = "W19"  !CDS_PN = "W19";
"MIA_DQS_H3":   PN = "AE19"  !CDS_PN = "AE19";
"MIA_DQS_H4":   PN = "AL19"  !CDS_PN = "AL19";
"MIA_DQS_H5":   PN = "J21"  !CDS_PN = "J21";
"MIA_DQS_H6":   PN = "R21"  !CDS_PN = "R21";
"MIA_DQS_H7":   PN = "AA21"  !CDS_PN = "AA21";
"MIA_DQS_H8":   PN = "AG21"  !CDS_PN = "AG21";
"MIA_DQS_H9":   PN = "AN21"  !CDS_PN = "AN21";
"MIA_DQS_L0":   PN = "H20"  !CDS_PN = "H20";
"MIA_DQS_L1":   PN = "P20"  !CDS_PN = "P20";
"MIA_DQS_L2":   PN = "Y20"  !CDS_PN = "Y20";
"MIA_DQS_L3":   PN = "AF20"  !CDS_PN = "AF20";
"MIA_DQS_L4":   PN = "AM20"  !CDS_PN = "AM20";
"MIA_DQS_L5":   PN = "H21"  !CDS_PN = "H21";
"MIA_DQS_L6":   PN = "P21"  !CDS_PN = "P21";
"MIA_DQS_L7":   PN = "Y21"  !CDS_PN = "Y21";
"MIA_DQS_L8":   PN = "AF21"  !CDS_PN = "AF21";
"MIA_DQS_L9":   PN = "AM21"  !CDS_PN = "AM21";
"MIA_PAR":   PN = "BC21"  !CDS_PN = "BC21";
"MIB0_CS_L0":   PN = "BM21"  !CDS_PN = "BM21";
"MIB0_CS_L1":   PN = "BN19"  !CDS_PN = "BN19";
"MIB0_RSP_L":   PN = "BP20"  !CDS_PN = "BP20";
"MIB1_CS_L0":   PN = "BL19"  !CDS_PN = "BL19";
"MIB1_CS_L1":   PN = "BM20"  !CDS_PN = "BM20";
"MIB1_RSP_L":   PN = "BR19"  !CDS_PN = "BR19";
"MIB_CA0":   PN = "BG21"  !CDS_PN = "BG21";
"MIB_CA1":   PN = "BH21"  !CDS_PN = "BH21";
"MIB_CA2":   PN = "BH20"  !CDS_PN = "BH20";
"MIB_CA3":   PN = "BJ19"  !CDS_PN = "BJ19";
"MIB_CA4":   PN = "BJ21"  !CDS_PN = "BJ21";
"MIB_CA5":   PN = "BK21"  !CDS_PN = "BK21";
"MIB_CA6":   PN = "BK20"  !CDS_PN = "BK20";
"MIB_CHECK0":   PN = "BY20"  !CDS_PN = "BY20";
"MIB_CHECK1":   PN = "CA21"  !CDS_PN = "CA21";
"MIB_CHECK2":   PN = "CA19"  !CDS_PN = "CA19";
"MIB_CHECK3":   PN = "CB21"  !CDS_PN = "CB21";
"MIB_CHECK4":   PN = "BT20"  !CDS_PN = "BT20";
"MIB_CHECK5":   PN = "BU21"  !CDS_PN = "BU21";
"MIB_CHECK6":   PN = "BU19"  !CDS_PN = "BU19";
"MIB_CHECK7":   PN = "BV21"  !CDS_PN = "BV21";
"MIB_DATA0":   PN = "CB20"  !CDS_PN = "CB20";
"MIB_DATA1":   PN = "CC21"  !CDS_PN = "CC21";
"MIB_DATA2":   PN = "CC19"  !CDS_PN = "CC19";
"MIB_DATA3":   PN = "CD21"  !CDS_PN = "CD21";
"MIB_DATA4":   PN = "CF20"  !CDS_PN = "CF20";
"MIB_DATA5":   PN = "CG21"  !CDS_PN = "CG21";
"MIB_DATA6":   PN = "CG19"  !CDS_PN = "CG19";
"MIB_DATA7":   PN = "CH21"  !CDS_PN = "CH21";
"MIB_DATA8":   PN = "CH20"  !CDS_PN = "CH20";
"MIB_DATA9":   PN = "CJ21"  !CDS_PN = "CJ21";
"MIB_DATA10":   PN = "CJ19"  !CDS_PN = "CJ19";
"MIB_DATA11":   PN = "CK21"  !CDS_PN = "CK21";
"MIB_DATA12":   PN = "CM20"  !CDS_PN = "CM20";
"MIB_DATA13":   PN = "CN21"  !CDS_PN = "CN21";
"MIB_DATA14":   PN = "CN19"  !CDS_PN = "CN19";
"MIB_DATA15":   PN = "CP21"  !CDS_PN = "CP21";
"MIB_DATA16":   PN = "CP20"  !CDS_PN = "CP20";
"MIB_DATA17":   PN = "CR21"  !CDS_PN = "CR21";
"MIB_DATA18":   PN = "CR19"  !CDS_PN = "CR19";
"MIB_DATA19":   PN = "CT21"  !CDS_PN = "CT21";
"MIB_DATA20":   PN = "CV20"  !CDS_PN = "CV20";
"MIB_DATA21":   PN = "CW21"  !CDS_PN = "CW21";
"MIB_DATA22":   PN = "CW19"  !CDS_PN = "CW19";
"MIB_DATA23":   PN = "CY21"  !CDS_PN = "CY21";
"MIB_DATA24":   PN = "CY20"  !CDS_PN = "CY20";
"MIB_DATA25":   PN = "DA21"  !CDS_PN = "DA21";
"MIB_DATA26":   PN = "DA19"  !CDS_PN = "DA19";
"MIB_DATA27":   PN = "DB21"  !CDS_PN = "DB21";
"MIB_DATA28":   PN = "DD20"  !CDS_PN = "DD20";
"MIB_DATA29":   PN = "DE21"  !CDS_PN = "DE21";
"MIB_DATA30":   PN = "DE19"  !CDS_PN = "DE19";
"MIB_DATA31":   PN = "DF21"  !CDS_PN = "DF21";
"MIB_DQS_H0":   PN = "CD20"  !CDS_PN = "CD20";
"MIB_DQS_H1":   PN = "CK20"  !CDS_PN = "CK20";
"MIB_DQS_H2":   PN = "CT20"  !CDS_PN = "CT20";
"MIB_DQS_H3":   PN = "DB20"  !CDS_PN = "DB20";
"MIB_DQS_H4":   PN = "BY21"  !CDS_PN = "BY21";
"MIB_DQS_H5":   PN = "CF21"  !CDS_PN = "CF21";
"MIB_DQS_H6":   PN = "CM21"  !CDS_PN = "CM21";
"MIB_DQS_H7":   PN = "CV21"  !CDS_PN = "CV21";
"MIB_DQS_H8":   PN = "DD21"  !CDS_PN = "DD21";
"MIB_DQS_H9":   PN = "BV20"  !CDS_PN = "BV20";
"MIB_DQS_L0":   PN = "CE19"  !CDS_PN = "CE19";
"MIB_DQS_L1":   PN = "CL19"  !CDS_PN = "CL19";
"MIB_DQS_L2":   PN = "CU19"  !CDS_PN = "CU19";
"MIB_DQS_L3":   PN = "DC19"  !CDS_PN = "DC19";
"MIB_DQS_L4":   PN = "BW21"  !CDS_PN = "BW21";
"MIB_DQS_L5":   PN = "CE21"  !CDS_PN = "CE21";
"MIB_DQS_L6":   PN = "CL21"  !CDS_PN = "CL21";
"MIB_DQS_L7":   PN = "CU21"  !CDS_PN = "CU21";
"MIB_DQS_L8":   PN = "DC21"  !CDS_PN = "DC21";
"MIB_DQS_L9":   PN = "BW19"  !CDS_PN = "BW19";
"MIB_PAR":   PN = "BL21"  !CDS_PN = "BL21";
"TEST39I":   PN = "BF21"  !CDS_PN = "BF21";
BODY = "Q_RES","I314": #LOCATION = "R508" !CDS_LOCATION = "R508" &SEC = "1" #&CDS_SEC = "1";
"A":   PN = "1"  !CDS_PN = "1";
"B":   PN = "2"  !CDS_PN = "2";
DRAWING = "@t6g_mb_lib.t6g(sch_1):page46";
BODY = "GENOA_SP5","I159": #LOCATION = "U26" !CDS_LOCATION = "U26" &SEC = "10" #&CDS_SEC = "10";
"MJ0_CLK_H":   PN = "BC16"  !CDS_PN = "BC16";
"MJ0_CLK_L":   PN = "BD16"  !CDS_PN = "BD16";
"MJ1_CLK_H":   PN = "BF16"  !CDS_PN = "BF16";
"MJ1_CLK_L":   PN = "BG16"  !CDS_PN = "BG16";
"MJ_ALERT_L":   PN = "AT18"  !CDS_PN = "AT18";
"MJ_RESET_L":   PN = "AU17"  !CDS_PN = "AU17";
"MJA0_CS_L0":   PN = "AU16"  !CDS_PN = "AU16";
"MJA0_CS_L1":   PN = "AV18"  !CDS_PN = "AV18";
"MJA0_RSP_L":   PN = "BN17"  !CDS_PN = "BN17";
"MJA1_CS_L0":   PN = "AV16"  !CDS_PN = "AV16";
"MJA1_CS_L1":   PN = "AW17"  !CDS_PN = "AW17";
"MJA1_RSP_L":   PN = "BP18"  !CDS_PN = "BP18";
"MJA_CA0":   PN = "AW16"  !CDS_PN = "AW16";
"MJA_CA1":   PN = "AY16"  !CDS_PN = "AY16";
"MJA_CA2":   PN = "AY18"  !CDS_PN = "AY18";
"MJA_CA3":   PN = "BA17"  !CDS_PN = "BA17";
"MJA_CA4":   PN = "BA16"  !CDS_PN = "BA16";
"MJA_CA5":   PN = "BB16"  !CDS_PN = "BB16";
"MJA_CA6":   PN = "BB18"  !CDS_PN = "BB18";
"MJA_CHECK0":   PN = "AJ16"  !CDS_PN = "AJ16";
"MJA_CHECK1":   PN = "AK18"  !CDS_PN = "AK18";
"MJA_CHECK2":   PN = "AK16"  !CDS_PN = "AK16";
"MJA_CHECK3":   PN = "AL17"  !CDS_PN = "AL17";
"MJA_CHECK4":   PN = "AN16"  !CDS_PN = "AN16";
"MJA_CHECK5":   PN = "AP18"  !CDS_PN = "AP18";
"MJA_CHECK6":   PN = "AP16"  !CDS_PN = "AP16";
"MJA_CHECK7":   PN = "AR17"  !CDS_PN = "AR17";
"MJA_DATA0":   PN = "E16"  !CDS_PN = "E16";
"MJA_DATA1":   PN = "F18"  !CDS_PN = "F18";
"MJA_DATA2":   PN = "F16"  !CDS_PN = "F16";
"MJA_DATA3":   PN = "G17"  !CDS_PN = "G17";
"MJA_DATA4":   PN = "J16"  !CDS_PN = "J16";
"MJA_DATA5":   PN = "K18"  !CDS_PN = "K18";
"MJA_DATA6":   PN = "K16"  !CDS_PN = "K16";
"MJA_DATA7":   PN = "L17"  !CDS_PN = "L17";
"MJA_DATA8":   PN = "L16"  !CDS_PN = "L16";
"MJA_DATA9":   PN = "M18"  !CDS_PN = "M18";
"MJA_DATA10":   PN = "M16"  !CDS_PN = "M16";
"MJA_DATA11":   PN = "N17"  !CDS_PN = "N17";
"MJA_DATA12":   PN = "R16"  !CDS_PN = "R16";
"MJA_DATA13":   PN = "T18"  !CDS_PN = "T18";
"MJA_DATA14":   PN = "T16"  !CDS_PN = "T16";
"MJA_DATA15":   PN = "U17"  !CDS_PN = "U17";
"MJA_DATA16":   PN = "U16"  !CDS_PN = "U16";
"MJA_DATA17":   PN = "V18"  !CDS_PN = "V18";
"MJA_DATA18":   PN = "V16"  !CDS_PN = "V16";
"MJA_DATA19":   PN = "W17"  !CDS_PN = "W17";
"MJA_DATA20":   PN = "AA16"  !CDS_PN = "AA16";
"MJA_DATA21":   PN = "AB18"  !CDS_PN = "AB18";
"MJA_DATA22":   PN = "AB16"  !CDS_PN = "AB16";
"MJA_DATA23":   PN = "AC17"  !CDS_PN = "AC17";
"MJA_DATA24":   PN = "AC16"  !CDS_PN = "AC16";
"MJA_DATA25":   PN = "AD18"  !CDS_PN = "AD18";
"MJA_DATA26":   PN = "AD16"  !CDS_PN = "AD16";
"MJA_DATA27":   PN = "AE17"  !CDS_PN = "AE17";
"MJA_DATA28":   PN = "AG16"  !CDS_PN = "AG16";
"MJA_DATA29":   PN = "AH18"  !CDS_PN = "AH18";
"MJA_DATA30":   PN = "AH16"  !CDS_PN = "AH16";
"MJA_DATA31":   PN = "AJ17"  !CDS_PN = "AJ17";
"MJA_DQS_H0":   PN = "G16"  !CDS_PN = "G16";
"MJA_DQS_H1":   PN = "N16"  !CDS_PN = "N16";
"MJA_DQS_H2":   PN = "W16"  !CDS_PN = "W16";
"MJA_DQS_H3":   PN = "AE16"  !CDS_PN = "AE16";
"MJA_DQS_H4":   PN = "AL16"  !CDS_PN = "AL16";
"MJA_DQS_H5":   PN = "J17"  !CDS_PN = "J17";
"MJA_DQS_H6":   PN = "R17"  !CDS_PN = "R17";
"MJA_DQS_H7":   PN = "AA17"  !CDS_PN = "AA17";
"MJA_DQS_H8":   PN = "AG17"  !CDS_PN = "AG17";
"MJA_DQS_H9":   PN = "AN17"  !CDS_PN = "AN17";
"MJA_DQS_L0":   PN = "H16"  !CDS_PN = "H16";
"MJA_DQS_L1":   PN = "P16"  !CDS_PN = "P16";
"MJA_DQS_L2":   PN = "Y16"  !CDS_PN = "Y16";
"MJA_DQS_L3":   PN = "AF16"  !CDS_PN = "AF16";
"MJA_DQS_L4":   PN = "AM16"  !CDS_PN = "AM16";
"MJA_DQS_L5":   PN = "H18"  !CDS_PN = "H18";
"MJA_DQS_L6":   PN = "P18"  !CDS_PN = "P18";
"MJA_DQS_L7":   PN = "Y18"  !CDS_PN = "Y18";
"MJA_DQS_L8":   PN = "AF18"  !CDS_PN = "AF18";
"MJA_DQS_L9":   PN = "AM18"  !CDS_PN = "AM18";
"MJA_PAR":   PN = "BC17"  !CDS_PN = "BC17";
"MJB0_CS_L0":   PN = "BM18"  !CDS_PN = "BM18";
"MJB0_CS_L1":   PN = "BN16"  !CDS_PN = "BN16";
"MJB0_RSP_L":   PN = "BP16"  !CDS_PN = "BP16";
"MJB1_CS_L0":   PN = "BL16"  !CDS_PN = "BL16";
"MJB1_CS_L1":   PN = "BM16"  !CDS_PN = "BM16";
"MJB1_RSP_L":   PN = "BR16"  !CDS_PN = "BR16";
"MJB_CA0":   PN = "BG17"  !CDS_PN = "BG17";
"MJB_CA1":   PN = "BH18"  !CDS_PN = "BH18";
"MJB_CA2":   PN = "BH16"  !CDS_PN = "BH16";
"MJB_CA3":   PN = "BJ16"  !CDS_PN = "BJ16";
"MJB_CA4":   PN = "BJ17"  !CDS_PN = "BJ17";
"MJB_CA5":   PN = "BK18"  !CDS_PN = "BK18";
"MJB_CA6":   PN = "BK16"  !CDS_PN = "BK16";
"MJB_CHECK0":   PN = "BY16"  !CDS_PN = "BY16";
"MJB_CHECK1":   PN = "CA17"  !CDS_PN = "CA17";
"MJB_CHECK2":   PN = "CA16"  !CDS_PN = "CA16";
"MJB_CHECK3":   PN = "CB18"  !CDS_PN = "CB18";
"MJB_CHECK4":   PN = "BT16"  !CDS_PN = "BT16";
"MJB_CHECK5":   PN = "BU17"  !CDS_PN = "BU17";
"MJB_CHECK6":   PN = "BU16"  !CDS_PN = "BU16";
"MJB_CHECK7":   PN = "BV18"  !CDS_PN = "BV18";
"MJB_DATA0":   PN = "CB16"  !CDS_PN = "CB16";
"MJB_DATA1":   PN = "CC17"  !CDS_PN = "CC17";
"MJB_DATA2":   PN = "CC16"  !CDS_PN = "CC16";
"MJB_DATA3":   PN = "CD18"  !CDS_PN = "CD18";
"MJB_DATA4":   PN = "CF16"  !CDS_PN = "CF16";
"MJB_DATA5":   PN = "CG17"  !CDS_PN = "CG17";
"MJB_DATA6":   PN = "CG16"  !CDS_PN = "CG16";
"MJB_DATA7":   PN = "CH18"  !CDS_PN = "CH18";
"MJB_DATA8":   PN = "CH16"  !CDS_PN = "CH16";
"MJB_DATA9":   PN = "CJ17"  !CDS_PN = "CJ17";
"MJB_DATA10":   PN = "CJ16"  !CDS_PN = "CJ16";
"MJB_DATA11":   PN = "CK18"  !CDS_PN = "CK18";
"MJB_DATA12":   PN = "CM16"  !CDS_PN = "CM16";
"MJB_DATA13":   PN = "CN17"  !CDS_PN = "CN17";
"MJB_DATA14":   PN = "CN16"  !CDS_PN = "CN16";
"MJB_DATA15":   PN = "CP18"  !CDS_PN = "CP18";
"MJB_DATA16":   PN = "CP16"  !CDS_PN = "CP16";
"MJB_DATA17":   PN = "CR17"  !CDS_PN = "CR17";
"MJB_DATA18":   PN = "CR16"  !CDS_PN = "CR16";
"MJB_DATA19":   PN = "CT18"  !CDS_PN = "CT18";
"MJB_DATA20":   PN = "CV16"  !CDS_PN = "CV16";
"MJB_DATA21":   PN = "CW17"  !CDS_PN = "CW17";
"MJB_DATA22":   PN = "CW16"  !CDS_PN = "CW16";
"MJB_DATA23":   PN = "CY18"  !CDS_PN = "CY18";
"MJB_DATA24":   PN = "CY16"  !CDS_PN = "CY16";
"MJB_DATA25":   PN = "DA17"  !CDS_PN = "DA17";
"MJB_DATA26":   PN = "DA16"  !CDS_PN = "DA16";
"MJB_DATA27":   PN = "DB18"  !CDS_PN = "DB18";
"MJB_DATA28":   PN = "DD16"  !CDS_PN = "DD16";
"MJB_DATA29":   PN = "DE17"  !CDS_PN = "DE17";
"MJB_DATA30":   PN = "DE16"  !CDS_PN = "DE16";
"MJB_DATA31":   PN = "DF16"  !CDS_PN = "DF16";
"MJB_DQS_H0":   PN = "CD16"  !CDS_PN = "CD16";
"MJB_DQS_H1":   PN = "CK16"  !CDS_PN = "CK16";
"MJB_DQS_H2":   PN = "CT16"  !CDS_PN = "CT16";
"MJB_DQS_H3":   PN = "DB16"  !CDS_PN = "DB16";
"MJB_DQS_H4":   PN = "BY18"  !CDS_PN = "BY18";
"MJB_DQS_H5":   PN = "CF18"  !CDS_PN = "CF18";
"MJB_DQS_H6":   PN = "CM18"  !CDS_PN = "CM18";
"MJB_DQS_H7":   PN = "CV18"  !CDS_PN = "CV18";
"MJB_DQS_H8":   PN = "DD18"  !CDS_PN = "DD18";
"MJB_DQS_H9":   PN = "BV16"  !CDS_PN = "BV16";
"MJB_DQS_L0":   PN = "CE16"  !CDS_PN = "CE16";
"MJB_DQS_L1":   PN = "CL16"  !CDS_PN = "CL16";
"MJB_DQS_L2":   PN = "CU16"  !CDS_PN = "CU16";
"MJB_DQS_L3":   PN = "DC16"  !CDS_PN = "DC16";
"MJB_DQS_L4":   PN = "BW17"  !CDS_PN = "BW17";
"MJB_DQS_L5":   PN = "CE17"  !CDS_PN = "CE17";
"MJB_DQS_L6":   PN = "CL17"  !CDS_PN = "CL17";
"MJB_DQS_L7":   PN = "CU17"  !CDS_PN = "CU17";
"MJB_DQS_L8":   PN = "DC17"  !CDS_PN = "DC17";
"MJB_DQS_L9":   PN = "BW16"  !CDS_PN = "BW16";
"MJB_PAR":   PN = "BL17"  !CDS_PN = "BL17";
"TEST39J":   PN = "BF18"  !CDS_PN = "BF18";
BODY = "Q_RES","I314": #LOCATION = "R509" !CDS_LOCATION = "R509" &SEC = "1" #&CDS_SEC = "1";
"A":   PN = "1"  !CDS_PN = "1";
"B":   PN = "2"  !CDS_PN = "2";
DRAWING = "@t6g_mb_lib.t6g(sch_1):page47";
BODY = "GENOA_SP5","I159": #LOCATION = "U26" !CDS_LOCATION = "U26" &SEC = "36" #&CDS_SEC = "36";
"MK0_CLK_H":   PN = "BC5"  !CDS_PN = "BC5";
"MK0_CLK_L":   PN = "BD6"  !CDS_PN = "BD6";
"MK1_CLK_H":   PN = "BF6"  !CDS_PN = "BF6";
"MK1_CLK_L":   PN = "BG5"  !CDS_PN = "BG5";
"MK_ALERT_L":   PN = "AT7"  !CDS_PN = "AT7";
"MK_RESET_L":   PN = "AU7"  !CDS_PN = "AU7";
"MKA0_CS_L0":   PN = "AU5"  !CDS_PN = "AU5";
"MKA0_CS_L1":   PN = "AV7"  !CDS_PN = "AV7";
"MKA0_RSP_L":   PN = "BN7"  !CDS_PN = "BN7";
"MKA1_CS_L0":   PN = "AV6"  !CDS_PN = "AV6";
"MKA1_CS_L1":   PN = "AW7"  !CDS_PN = "AW7";
"MKA1_RSP_L":   PN = "BP7"  !CDS_PN = "BP7";
"MKA_CA0":   PN = "AW5"  !CDS_PN = "AW5";
"MKA_CA1":   PN = "AY6"  !CDS_PN = "AY6";
"MKA_CA2":   PN = "AY7"  !CDS_PN = "AY7";
"MKA_CA3":   PN = "BA7"  !CDS_PN = "BA7";
"MKA_CA4":   PN = "BA5"  !CDS_PN = "BA5";
"MKA_CA5":   PN = "BB6"  !CDS_PN = "BB6";
"MKA_CA6":   PN = "BB7"  !CDS_PN = "BB7";
"MKA_CHECK0":   PN = "AJ5"  !CDS_PN = "AJ5";
"MKA_CHECK1":   PN = "AK7"  !CDS_PN = "AK7";
"MKA_CHECK2":   PN = "AK6"  !CDS_PN = "AK6";
"MKA_CHECK3":   PN = "AL7"  !CDS_PN = "AL7";
"MKA_CHECK4":   PN = "AN5"  !CDS_PN = "AN5";
"MKA_CHECK5":   PN = "AP7"  !CDS_PN = "AP7";
"MKA_CHECK6":   PN = "AP6"  !CDS_PN = "AP6";
"MKA_CHECK7":   PN = "AR7"  !CDS_PN = "AR7";
"MKA_DATA0":   PN = "E5"  !CDS_PN = "E5";
"MKA_DATA1":   PN = "F7"  !CDS_PN = "F7";
"MKA_DATA2":   PN = "F6"  !CDS_PN = "F6";
"MKA_DATA3":   PN = "G7"  !CDS_PN = "G7";
"MKA_DATA4":   PN = "J5"  !CDS_PN = "J5";
"MKA_DATA5":   PN = "K7"  !CDS_PN = "K7";
"MKA_DATA6":   PN = "K6"  !CDS_PN = "K6";
"MKA_DATA7":   PN = "L7"  !CDS_PN = "L7";
"MKA_DATA8":   PN = "L5"  !CDS_PN = "L5";
"MKA_DATA9":   PN = "M7"  !CDS_PN = "M7";
"MKA_DATA10":   PN = "M6"  !CDS_PN = "M6";
"MKA_DATA11":   PN = "N7"  !CDS_PN = "N7";
"MKA_DATA12":   PN = "R5"  !CDS_PN = "R5";
"MKA_DATA13":   PN = "T7"  !CDS_PN = "T7";
"MKA_DATA14":   PN = "T6"  !CDS_PN = "T6";
"MKA_DATA15":   PN = "U7"  !CDS_PN = "U7";
"MKA_DATA16":   PN = "U5"  !CDS_PN = "U5";
"MKA_DATA17":   PN = "V7"  !CDS_PN = "V7";
"MKA_DATA18":   PN = "V6"  !CDS_PN = "V6";
"MKA_DATA19":   PN = "W7"  !CDS_PN = "W7";
"MKA_DATA20":   PN = "AA5"  !CDS_PN = "AA5";
"MKA_DATA21":   PN = "AB7"  !CDS_PN = "AB7";
"MKA_DATA22":   PN = "AB6"  !CDS_PN = "AB6";
"MKA_DATA23":   PN = "AC7"  !CDS_PN = "AC7";
"MKA_DATA24":   PN = "AC5"  !CDS_PN = "AC5";
"MKA_DATA25":   PN = "AD7"  !CDS_PN = "AD7";
"MKA_DATA26":   PN = "AD6"  !CDS_PN = "AD6";
"MKA_DATA27":   PN = "AE7"  !CDS_PN = "AE7";
"MKA_DATA28":   PN = "AG5"  !CDS_PN = "AG5";
"MKA_DATA29":   PN = "AH7"  !CDS_PN = "AH7";
"MKA_DATA30":   PN = "AH6"  !CDS_PN = "AH6";
"MKA_DATA31":   PN = "AJ7"  !CDS_PN = "AJ7";
"MKA_DQS_H0":   PN = "G5"  !CDS_PN = "G5";
"MKA_DQS_H1":   PN = "N5"  !CDS_PN = "N5";
"MKA_DQS_H2":   PN = "W5"  !CDS_PN = "W5";
"MKA_DQS_H3":   PN = "AE5"  !CDS_PN = "AE5";
"MKA_DQS_H4":   PN = "AL5"  !CDS_PN = "AL5";
"MKA_DQS_H5":   PN = "J7"  !CDS_PN = "J7";
"MKA_DQS_H6":   PN = "R7"  !CDS_PN = "R7";
"MKA_DQS_H7":   PN = "AA7"  !CDS_PN = "AA7";
"MKA_DQS_H8":   PN = "AG7"  !CDS_PN = "AG7";
"MKA_DQS_H9":   PN = "AN7"  !CDS_PN = "AN7";
"MKA_DQS_L0":   PN = "H6"  !CDS_PN = "H6";
"MKA_DQS_L1":   PN = "P6"  !CDS_PN = "P6";
"MKA_DQS_L2":   PN = "Y6"  !CDS_PN = "Y6";
"MKA_DQS_L3":   PN = "AF6"  !CDS_PN = "AF6";
"MKA_DQS_L4":   PN = "AM6"  !CDS_PN = "AM6";
"MKA_DQS_L5":   PN = "H7"  !CDS_PN = "H7";
"MKA_DQS_L6":   PN = "P7"  !CDS_PN = "P7";
"MKA_DQS_L7":   PN = "Y7"  !CDS_PN = "Y7";
"MKA_DQS_L8":   PN = "AF7"  !CDS_PN = "AF7";
"MKA_DQS_L9":   PN = "AM7"  !CDS_PN = "AM7";
"MKA_PAR":   PN = "BC7"  !CDS_PN = "BC7";
"MKB0_CS_L0":   PN = "BM7"  !CDS_PN = "BM7";
"MKB0_CS_L1":   PN = "BN5"  !CDS_PN = "BN5";
"MKB0_RSP_L":   PN = "BP6"  !CDS_PN = "BP6";
"MKB1_CS_L0":   PN = "BL5"  !CDS_PN = "BL5";
"MKB1_CS_L1":   PN = "BM6"  !CDS_PN = "BM6";
"MKB1_RSP_L":   PN = "BR5"  !CDS_PN = "BR5";
"MKB_CA0":   PN = "BG7"  !CDS_PN = "BG7";
"MKB_CA1":   PN = "BH7"  !CDS_PN = "BH7";
"MKB_CA2":   PN = "BH6"  !CDS_PN = "BH6";
"MKB_CA3":   PN = "BJ5"  !CDS_PN = "BJ5";
"MKB_CA4":   PN = "BJ7"  !CDS_PN = "BJ7";
"MKB_CA5":   PN = "BK7"  !CDS_PN = "BK7";
"MKB_CA6":   PN = "BK6"  !CDS_PN = "BK6";
"MKB_CHECK0":   PN = "BY6"  !CDS_PN = "BY6";
"MKB_CHECK1":   PN = "CA7"  !CDS_PN = "CA7";
"MKB_CHECK2":   PN = "CA5"  !CDS_PN = "CA5";
"MKB_CHECK3":   PN = "CB7"  !CDS_PN = "CB7";
"MKB_CHECK4":   PN = "BT6"  !CDS_PN = "BT6";
"MKB_CHECK5":   PN = "BU7"  !CDS_PN = "BU7";
"MKB_CHECK6":   PN = "BU5"  !CDS_PN = "BU5";
"MKB_CHECK7":   PN = "BV7"  !CDS_PN = "BV7";
"MKB_DATA0":   PN = "CB6"  !CDS_PN = "CB6";
"MKB_DATA1":   PN = "CC7"  !CDS_PN = "CC7";
"MKB_DATA2":   PN = "CC5"  !CDS_PN = "CC5";
"MKB_DATA3":   PN = "CD7"  !CDS_PN = "CD7";
"MKB_DATA4":   PN = "CF6"  !CDS_PN = "CF6";
"MKB_DATA5":   PN = "CG7"  !CDS_PN = "CG7";
"MKB_DATA6":   PN = "CG5"  !CDS_PN = "CG5";
"MKB_DATA7":   PN = "CH7"  !CDS_PN = "CH7";
"MKB_DATA8":   PN = "CH6"  !CDS_PN = "CH6";
"MKB_DATA9":   PN = "CJ7"  !CDS_PN = "CJ7";
"MKB_DATA10":   PN = "CJ5"  !CDS_PN = "CJ5";
"MKB_DATA11":   PN = "CK7"  !CDS_PN = "CK7";
"MKB_DATA12":   PN = "CM6"  !CDS_PN = "CM6";
"MKB_DATA13":   PN = "CN7"  !CDS_PN = "CN7";
"MKB_DATA14":   PN = "CN5"  !CDS_PN = "CN5";
"MKB_DATA15":   PN = "CP7"  !CDS_PN = "CP7";
"MKB_DATA16":   PN = "CP6"  !CDS_PN = "CP6";
"MKB_DATA17":   PN = "CR7"  !CDS_PN = "CR7";
"MKB_DATA18":   PN = "CR5"  !CDS_PN = "CR5";
"MKB_DATA19":   PN = "CT7"  !CDS_PN = "CT7";
"MKB_DATA20":   PN = "CV6"  !CDS_PN = "CV6";
"MKB_DATA21":   PN = "CW7"  !CDS_PN = "CW7";
"MKB_DATA22":   PN = "CW5"  !CDS_PN = "CW5";
"MKB_DATA23":   PN = "CY7"  !CDS_PN = "CY7";
"MKB_DATA24":   PN = "CY6"  !CDS_PN = "CY6";
"MKB_DATA25":   PN = "DA7"  !CDS_PN = "DA7";
"MKB_DATA26":   PN = "DA5"  !CDS_PN = "DA5";
"MKB_DATA27":   PN = "DB7"  !CDS_PN = "DB7";
"MKB_DATA28":   PN = "DD6"  !CDS_PN = "DD6";
"MKB_DATA29":   PN = "DE7"  !CDS_PN = "DE7";
"MKB_DATA30":   PN = "DE5"  !CDS_PN = "DE5";
"MKB_DATA31":   PN = "DF7"  !CDS_PN = "DF7";
"MKB_DQS_H0":   PN = "CD6"  !CDS_PN = "CD6";
"MKB_DQS_H1":   PN = "CK6"  !CDS_PN = "CK6";
"MKB_DQS_H2":   PN = "CT6"  !CDS_PN = "CT6";
"MKB_DQS_H3":   PN = "DB6"  !CDS_PN = "DB6";
"MKB_DQS_H4":   PN = "BY7"  !CDS_PN = "BY7";
"MKB_DQS_H5":   PN = "CF7"  !CDS_PN = "CF7";
"MKB_DQS_H6":   PN = "CM7"  !CDS_PN = "CM7";
"MKB_DQS_H7":   PN = "CV7"  !CDS_PN = "CV7";
"MKB_DQS_H8":   PN = "DD7"  !CDS_PN = "DD7";
"MKB_DQS_H9":   PN = "BV6"  !CDS_PN = "BV6";
"MKB_DQS_L0":   PN = "CE5"  !CDS_PN = "CE5";
"MKB_DQS_L1":   PN = "CL5"  !CDS_PN = "CL5";
"MKB_DQS_L2":   PN = "CU5"  !CDS_PN = "CU5";
"MKB_DQS_L3":   PN = "DC5"  !CDS_PN = "DC5";
"MKB_DQS_L4":   PN = "BW7"  !CDS_PN = "BW7";
"MKB_DQS_L5":   PN = "CE7"  !CDS_PN = "CE7";
"MKB_DQS_L6":   PN = "CL7"  !CDS_PN = "CL7";
"MKB_DQS_L7":   PN = "CU7"  !CDS_PN = "CU7";
"MKB_DQS_L8":   PN = "DC7"  !CDS_PN = "DC7";
"MKB_DQS_L9":   PN = "BW5"  !CDS_PN = "BW5";
"MKB_PAR":   PN = "BL7"  !CDS_PN = "BL7";
"TEST39K":   PN = "BF7"  !CDS_PN = "BF7";
BODY = "Q_RES","I314": #LOCATION = "R510" !CDS_LOCATION = "R510" &SEC = "1" #&CDS_SEC = "1";
"A":   PN = "1"  !CDS_PN = "1";
"B":   PN = "2"  !CDS_PN = "2";
DRAWING = "@t6g_mb_lib.t6g(sch_1):page48";
BODY = "GENOA_SP5","I159": #LOCATION = "U26" !CDS_LOCATION = "U26" &SEC = "35" #&CDS_SEC = "35";
"ML0_CLK_H":   PN = "BC9"  !CDS_PN = "BC9";
"ML0_CLK_L":   PN = "BD9"  !CDS_PN = "BD9";
"ML1_CLK_H":   PN = "BF9"  !CDS_PN = "BF9";
"ML1_CLK_L":   PN = "BG9"  !CDS_PN = "BG9";
"ML_ALERT_L":   PN = "AT11"  !CDS_PN = "AT11";
"ML_RESET_L":   PN = "AU10"  !CDS_PN = "AU10";
"MLA0_CS_L0":   PN = "AU9"  !CDS_PN = "AU9";
"MLA0_CS_L1":   PN = "AV11"  !CDS_PN = "AV11";
"MLA0_RSP_L":   PN = "BN10"  !CDS_PN = "BN10";
"MLA1_CS_L0":   PN = "AV9"  !CDS_PN = "AV9";
"MLA1_CS_L1":   PN = "AW10"  !CDS_PN = "AW10";
"MLA1_RSP_L":   PN = "BP11"  !CDS_PN = "BP11";
"MLA_CA0":   PN = "AW9"  !CDS_PN = "AW9";
"MLA_CA1":   PN = "AY9"  !CDS_PN = "AY9";
"MLA_CA2":   PN = "AY11"  !CDS_PN = "AY11";
"MLA_CA3":   PN = "BA10"  !CDS_PN = "BA10";
"MLA_CA4":   PN = "BA9"  !CDS_PN = "BA9";
"MLA_CA5":   PN = "BB9"  !CDS_PN = "BB9";
"MLA_CA6":   PN = "BB11"  !CDS_PN = "BB11";
"MLA_CHECK0":   PN = "AJ9"  !CDS_PN = "AJ9";
"MLA_CHECK1":   PN = "AK11"  !CDS_PN = "AK11";
"MLA_CHECK2":   PN = "AK9"  !CDS_PN = "AK9";
"MLA_CHECK3":   PN = "AL10"  !CDS_PN = "AL10";
"MLA_CHECK4":   PN = "AN9"  !CDS_PN = "AN9";
"MLA_CHECK5":   PN = "AP11"  !CDS_PN = "AP11";
"MLA_CHECK6":   PN = "AP9"  !CDS_PN = "AP9";
"MLA_CHECK7":   PN = "AR10"  !CDS_PN = "AR10";
"MLA_DATA0":   PN = "E9"  !CDS_PN = "E9";
"MLA_DATA1":   PN = "F11"  !CDS_PN = "F11";
"MLA_DATA2":   PN = "F9"  !CDS_PN = "F9";
"MLA_DATA3":   PN = "G10"  !CDS_PN = "G10";
"MLA_DATA4":   PN = "J9"  !CDS_PN = "J9";
"MLA_DATA5":   PN = "K11"  !CDS_PN = "K11";
"MLA_DATA6":   PN = "K9"  !CDS_PN = "K9";
"MLA_DATA7":   PN = "L10"  !CDS_PN = "L10";
"MLA_DATA8":   PN = "L9"  !CDS_PN = "L9";
"MLA_DATA9":   PN = "M11"  !CDS_PN = "M11";
"MLA_DATA10":   PN = "M9"  !CDS_PN = "M9";
"MLA_DATA11":   PN = "N10"  !CDS_PN = "N10";
"MLA_DATA12":   PN = "R9"  !CDS_PN = "R9";
"MLA_DATA13":   PN = "T11"  !CDS_PN = "T11";
"MLA_DATA14":   PN = "T9"  !CDS_PN = "T9";
"MLA_DATA15":   PN = "U10"  !CDS_PN = "U10";
"MLA_DATA16":   PN = "U9"  !CDS_PN = "U9";
"MLA_DATA17":   PN = "V11"  !CDS_PN = "V11";
"MLA_DATA18":   PN = "V9"  !CDS_PN = "V9";
"MLA_DATA19":   PN = "W10"  !CDS_PN = "W10";
"MLA_DATA20":   PN = "AA9"  !CDS_PN = "AA9";
"MLA_DATA21":   PN = "AB11"  !CDS_PN = "AB11";
"MLA_DATA22":   PN = "AB9"  !CDS_PN = "AB9";
"MLA_DATA23":   PN = "AC10"  !CDS_PN = "AC10";
"MLA_DATA24":   PN = "AC9"  !CDS_PN = "AC9";
"MLA_DATA25":   PN = "AD11"  !CDS_PN = "AD11";
"MLA_DATA26":   PN = "AD9"  !CDS_PN = "AD9";
"MLA_DATA27":   PN = "AE10"  !CDS_PN = "AE10";
"MLA_DATA28":   PN = "AG9"  !CDS_PN = "AG9";
"MLA_DATA29":   PN = "AH11"  !CDS_PN = "AH11";
"MLA_DATA30":   PN = "AH9"  !CDS_PN = "AH9";
"MLA_DATA31":   PN = "AJ10"  !CDS_PN = "AJ10";
"MLA_DQS_H0":   PN = "G9"  !CDS_PN = "G9";
"MLA_DQS_H1":   PN = "N9"  !CDS_PN = "N9";
"MLA_DQS_H2":   PN = "W9"  !CDS_PN = "W9";
"MLA_DQS_H3":   PN = "AE9"  !CDS_PN = "AE9";
"MLA_DQS_H4":   PN = "AL9"  !CDS_PN = "AL9";
"MLA_DQS_H5":   PN = "J10"  !CDS_PN = "J10";
"MLA_DQS_H6":   PN = "R10"  !CDS_PN = "R10";
"MLA_DQS_H7":   PN = "AA10"  !CDS_PN = "AA10";
"MLA_DQS_H8":   PN = "AG10"  !CDS_PN = "AG10";
"MLA_DQS_H9":   PN = "AN10"  !CDS_PN = "AN10";
"MLA_DQS_L0":   PN = "H9"  !CDS_PN = "H9";
"MLA_DQS_L1":   PN = "P9"  !CDS_PN = "P9";
"MLA_DQS_L2":   PN = "Y9"  !CDS_PN = "Y9";
"MLA_DQS_L3":   PN = "AF9"  !CDS_PN = "AF9";
"MLA_DQS_L4":   PN = "AM9"  !CDS_PN = "AM9";
"MLA_DQS_L5":   PN = "H11"  !CDS_PN = "H11";
"MLA_DQS_L6":   PN = "P11"  !CDS_PN = "P11";
"MLA_DQS_L7":   PN = "Y11"  !CDS_PN = "Y11";
"MLA_DQS_L8":   PN = "AF11"  !CDS_PN = "AF11";
"MLA_DQS_L9":   PN = "AM11"  !CDS_PN = "AM11";
"MLA_PAR":   PN = "BC10"  !CDS_PN = "BC10";
"MLB0_CS_L0":   PN = "BM11"  !CDS_PN = "BM11";
"MLB0_CS_L1":   PN = "BN9"  !CDS_PN = "BN9";
"MLB0_RSP_L":   PN = "BP9"  !CDS_PN = "BP9";
"MLB1_CS_L0":   PN = "BL9"  !CDS_PN = "BL9";
"MLB1_CS_L1":   PN = "BM9"  !CDS_PN = "BM9";
"MLB1_RSP_L":   PN = "BR9"  !CDS_PN = "BR9";
"MLB_CA0":   PN = "BG10"  !CDS_PN = "BG10";
"MLB_CA1":   PN = "BH11"  !CDS_PN = "BH11";
"MLB_CA2":   PN = "BH9"  !CDS_PN = "BH9";
"MLB_CA3":   PN = "BJ9"  !CDS_PN = "BJ9";
"MLB_CA4":   PN = "BJ10"  !CDS_PN = "BJ10";
"MLB_CA5":   PN = "BK11"  !CDS_PN = "BK11";
"MLB_CA6":   PN = "BK9"  !CDS_PN = "BK9";
"MLB_CHECK0":   PN = "BY9"  !CDS_PN = "BY9";
"MLB_CHECK1":   PN = "CA10"  !CDS_PN = "CA10";
"MLB_CHECK2":   PN = "CA9"  !CDS_PN = "CA9";
"MLB_CHECK3":   PN = "CB11"  !CDS_PN = "CB11";
"MLB_CHECK4":   PN = "BT9"  !CDS_PN = "BT9";
"MLB_CHECK5":   PN = "BU10"  !CDS_PN = "BU10";
"MLB_CHECK6":   PN = "BU9"  !CDS_PN = "BU9";
"MLB_CHECK7":   PN = "BV11"  !CDS_PN = "BV11";
"MLB_DATA0":   PN = "CB9"  !CDS_PN = "CB9";
"MLB_DATA1":   PN = "CC10"  !CDS_PN = "CC10";
"MLB_DATA2":   PN = "CC9"  !CDS_PN = "CC9";
"MLB_DATA3":   PN = "CD11"  !CDS_PN = "CD11";
"MLB_DATA4":   PN = "CF9"  !CDS_PN = "CF9";
"MLB_DATA5":   PN = "CG10"  !CDS_PN = "CG10";
"MLB_DATA6":   PN = "CG9"  !CDS_PN = "CG9";
"MLB_DATA7":   PN = "CH11"  !CDS_PN = "CH11";
"MLB_DATA8":   PN = "CH9"  !CDS_PN = "CH9";
"MLB_DATA9":   PN = "CJ10"  !CDS_PN = "CJ10";
"MLB_DATA10":   PN = "CJ9"  !CDS_PN = "CJ9";
"MLB_DATA11":   PN = "CK11"  !CDS_PN = "CK11";
"MLB_DATA12":   PN = "CM9"  !CDS_PN = "CM9";
"MLB_DATA13":   PN = "CN10"  !CDS_PN = "CN10";
"MLB_DATA14":   PN = "CN9"  !CDS_PN = "CN9";
"MLB_DATA15":   PN = "CP11"  !CDS_PN = "CP11";
"MLB_DATA16":   PN = "CP9"  !CDS_PN = "CP9";
"MLB_DATA17":   PN = "CR10"  !CDS_PN = "CR10";
"MLB_DATA18":   PN = "CR9"  !CDS_PN = "CR9";
"MLB_DATA19":   PN = "CT11"  !CDS_PN = "CT11";
"MLB_DATA20":   PN = "CV9"  !CDS_PN = "CV9";
"MLB_DATA21":   PN = "CW10"  !CDS_PN = "CW10";
"MLB_DATA22":   PN = "CW9"  !CDS_PN = "CW9";
"MLB_DATA23":   PN = "CY11"  !CDS_PN = "CY11";
"MLB_DATA24":   PN = "CY9"  !CDS_PN = "CY9";
"MLB_DATA25":   PN = "DA10"  !CDS_PN = "DA10";
"MLB_DATA26":   PN = "DA9"  !CDS_PN = "DA9";
"MLB_DATA27":   PN = "DB11"  !CDS_PN = "DB11";
"MLB_DATA28":   PN = "DD9"  !CDS_PN = "DD9";
"MLB_DATA29":   PN = "DE10"  !CDS_PN = "DE10";
"MLB_DATA30":   PN = "DE9"  !CDS_PN = "DE9";
"MLB_DATA31":   PN = "DF9"  !CDS_PN = "DF9";
"MLB_DQS_H0":   PN = "CD9"  !CDS_PN = "CD9";
"MLB_DQS_H1":   PN = "CK9"  !CDS_PN = "CK9";
"MLB_DQS_H2":   PN = "CT9"  !CDS_PN = "CT9";
"MLB_DQS_H3":   PN = "DB9"  !CDS_PN = "DB9";
"MLB_DQS_H4":   PN = "BY11"  !CDS_PN = "BY11";
"MLB_DQS_H5":   PN = "CF11"  !CDS_PN = "CF11";
"MLB_DQS_H6":   PN = "CM11"  !CDS_PN = "CM11";
"MLB_DQS_H7":   PN = "CV11"  !CDS_PN = "CV11";
"MLB_DQS_H8":   PN = "DD11"  !CDS_PN = "DD11";
"MLB_DQS_H9":   PN = "BV9"  !CDS_PN = "BV9";
"MLB_DQS_L0":   PN = "CE9"  !CDS_PN = "CE9";
"MLB_DQS_L1":   PN = "CL9"  !CDS_PN = "CL9";
"MLB_DQS_L2":   PN = "CU9"  !CDS_PN = "CU9";
"MLB_DQS_L3":   PN = "DC9"  !CDS_PN = "DC9";
"MLB_DQS_L4":   PN = "BW10"  !CDS_PN = "BW10";
"MLB_DQS_L5":   PN = "CE10"  !CDS_PN = "CE10";
"MLB_DQS_L6":   PN = "CL10"  !CDS_PN = "CL10";
"MLB_DQS_L7":   PN = "CU10"  !CDS_PN = "CU10";
"MLB_DQS_L8":   PN = "DC10"  !CDS_PN = "DC10";
"MLB_DQS_L9":   PN = "BW9"  !CDS_PN = "BW9";
"MLB_PAR":   PN = "BL10"  !CDS_PN = "BL10";
"TEST39L":   PN = "BF11"  !CDS_PN = "BF11";
BODY = "Q_RES","I313": #LOCATION = "R511" !CDS_LOCATION = "R511" &SEC = "1" #&CDS_SEC = "1";
"A":   PN = "1"  !CDS_PN = "1";
"B":   PN = "2"  !CDS_PN = "2";
DRAWING = "@t6g_mb_lib.t6g(sch_1):page49";
BODY = "GENOA_SP5","I213": #LOCATION = "U26" !CDS_LOCATION = "U26" &SEC = "11" #&CDS_SEC = "11";
"G0_RXN0":   PN = "M40"  !CDS_PN = "M40";
"G0_RXN1":   PN = "K40"  !CDS_PN = "K40";
"G0_RXN2":   PN = "H40"  !CDS_PN = "H40";
"G0_RXN3":   PN = "L43"  !CDS_PN = "L43";
"G0_RXN4":   PN = "G43"  !CDS_PN = "G43";
"G0_RXN5":   PN = "J43"  !CDS_PN = "J43";
"G0_RXN6":   PN = "L46"  !CDS_PN = "L46";
"G0_RXN7":   PN = "G46"  !CDS_PN = "G46";
"G0_RXN8":   PN = "J46"  !CDS_PN = "J46";
"G0_RXN9":   PN = "L49"  !CDS_PN = "L49";
"G0_RXN10":   PN = "G49"  !CDS_PN = "G49";
"G0_RXN11":   PN = "J49"  !CDS_PN = "J49";
"G0_RXN12":   PN = "L52"  !CDS_PN = "L52";
"G0_RXN13":   PN = "G52"  !CDS_PN = "G52";
"G0_RXN14":   PN = "J52"  !CDS_PN = "J52";
"G0_RXN15":   PN = "N52"  !CDS_PN = "N52";
"G0_RXP0":   PN = "M41"  !CDS_PN = "M41";
"G0_RXP1":   PN = "K41"  !CDS_PN = "K41";
"G0_RXP2":   PN = "H41"  !CDS_PN = "H41";
"G0_RXP3":   PN = "L44"  !CDS_PN = "L44";
"G0_RXP4":   PN = "G44"  !CDS_PN = "G44";
"G0_RXP5":   PN = "J44"  !CDS_PN = "J44";
"G0_RXP6":   PN = "L47"  !CDS_PN = "L47";
"G0_RXP7":   PN = "G47"  !CDS_PN = "G47";
"G0_RXP8":   PN = "J47"  !CDS_PN = "J47";
"G0_RXP9":   PN = "L50"  !CDS_PN = "L50";
"G0_RXP10":   PN = "G50"  !CDS_PN = "G50";
"G0_RXP11":   PN = "J50"  !CDS_PN = "J50";
"G0_RXP12":   PN = "L53"  !CDS_PN = "L53";
"G0_RXP13":   PN = "G53"  !CDS_PN = "G53";
"G0_RXP14":   PN = "J53"  !CDS_PN = "J53";
"G0_RXP15":   PN = "N53"  !CDS_PN = "N53";
"G0_TXN0":   PN = "AF41"  !CDS_PN = "AF41";
"G0_TXN1":   PN = "AD41"  !CDS_PN = "AD41";
"G0_TXN2":   PN = "AB41"  !CDS_PN = "AB41";
"G0_TXN3":   PN = "AG44"  !CDS_PN = "AG44";
"G0_TXN4":   PN = "AA44"  !CDS_PN = "AA44";
"G0_TXN5":   PN = "AC44"  !CDS_PN = "AC44";
"G0_TXN6":   PN = "AE44"  !CDS_PN = "AE44";
"G0_TXN7":   PN = "AG47"  !CDS_PN = "AG47";
"G0_TXN8":   PN = "AC47"  !CDS_PN = "AC47";
"G0_TXN9":   PN = "AE47"  !CDS_PN = "AE47";
"G0_TXN10":   PN = "AG50"  !CDS_PN = "AG50";
"G0_TXN11":   PN = "AC50"  !CDS_PN = "AC50";
"G0_TXN12":   PN = "AE50"  !CDS_PN = "AE50";
"G0_TXN13":   PN = "AG53"  !CDS_PN = "AG53";
"G0_TXN14":   PN = "AC53"  !CDS_PN = "AC53";
"G0_TXN15":   PN = "AE53"  !CDS_PN = "AE53";
"G0_TXP0":   PN = "AF40"  !CDS_PN = "AF40";
"G0_TXP1":   PN = "AD40"  !CDS_PN = "AD40";
"G0_TXP2":   PN = "AB40"  !CDS_PN = "AB40";
"G0_TXP3":   PN = "AG43"  !CDS_PN = "AG43";
"G0_TXP4":   PN = "AA43"  !CDS_PN = "AA43";
"G0_TXP5":   PN = "AC43"  !CDS_PN = "AC43";
"G0_TXP6":   PN = "AE43"  !CDS_PN = "AE43";
"G0_TXP7":   PN = "AG46"  !CDS_PN = "AG46";
"G0_TXP8":   PN = "AC46"  !CDS_PN = "AC46";
"G0_TXP9":   PN = "AE46"  !CDS_PN = "AE46";
"G0_TXP10":   PN = "AG49"  !CDS_PN = "AG49";
"G0_TXP11":   PN = "AC49"  !CDS_PN = "AC49";
"G0_TXP12":   PN = "AE49"  !CDS_PN = "AE49";
"G0_TXP13":   PN = "AG52"  !CDS_PN = "AG52";
"G0_TXP14":   PN = "AC52"  !CDS_PN = "AC52";
"G0_TXP15":   PN = "AE52"  !CDS_PN = "AE52";
BODY = "GENOA_SP5","I214": #LOCATION = "U26" !CDS_LOCATION = "U26" &SEC = "12" #&CDS_SEC = "12";
"G1_RXN0":   PN = "V40"  !CDS_PN = "V40";
"G1_RXN1":   PN = "T40"  !CDS_PN = "T40";
"G1_RXN2":   PN = "P40"  !CDS_PN = "P40";
"G1_RXN3":   PN = "U43"  !CDS_PN = "U43";
"G1_RXN4":   PN = "N43"  !CDS_PN = "N43";
"G1_RXN5":   PN = "R43"  !CDS_PN = "R43";
"G1_RXN6":   PN = "U46"  !CDS_PN = "U46";
"G1_RXN7":   PN = "N46"  !CDS_PN = "N46";
"G1_RXN8":   PN = "R46"  !CDS_PN = "R46";
"G1_RXN9":   PN = "W49"  !CDS_PN = "W49";
"G1_RXN10":   PN = "N49"  !CDS_PN = "N49";
"G1_RXN11":   PN = "R49"  !CDS_PN = "R49";
"G1_RXN12":   PN = "U49"  !CDS_PN = "U49";
"G1_RXN13":   PN = "W52"  !CDS_PN = "W52";
"G1_RXN14":   PN = "R52"  !CDS_PN = "R52";
"G1_RXN15":   PN = "U52"  !CDS_PN = "U52";
"G1_RXP0":   PN = "V41"  !CDS_PN = "V41";
"G1_RXP1":   PN = "T41"  !CDS_PN = "T41";
"G1_RXP2":   PN = "P41"  !CDS_PN = "P41";
"G1_RXP3":   PN = "U44"  !CDS_PN = "U44";
"G1_RXP4":   PN = "N44"  !CDS_PN = "N44";
"G1_RXP5":   PN = "R44"  !CDS_PN = "R44";
"G1_RXP6":   PN = "U47"  !CDS_PN = "U47";
"G1_RXP7":   PN = "N47"  !CDS_PN = "N47";
"G1_RXP8":   PN = "R47"  !CDS_PN = "R47";
"G1_RXP9":   PN = "W50"  !CDS_PN = "W50";
"G1_RXP10":   PN = "N50"  !CDS_PN = "N50";
"G1_RXP11":   PN = "R50"  !CDS_PN = "R50";
"G1_RXP12":   PN = "U50"  !CDS_PN = "U50";
"G1_RXP13":   PN = "W53"  !CDS_PN = "W53";
"G1_RXP14":   PN = "R53"  !CDS_PN = "R53";
"G1_RXP15":   PN = "U53"  !CDS_PN = "U53";
"G1_TXN0":   PN = "AP41"  !CDS_PN = "AP41";
"G1_TXN1":   PN = "AM41"  !CDS_PN = "AM41";
"G1_TXN2":   PN = "AH41"  !CDS_PN = "AH41";
"G1_TXN3":   PN = "AK41"  !CDS_PN = "AK41";
"G1_TXN4":   PN = "AN44"  !CDS_PN = "AN44";
"G1_TXN5":   PN = "AJ44"  !CDS_PN = "AJ44";
"G1_TXN6":   PN = "AL44"  !CDS_PN = "AL44";
"G1_TXN7":   PN = "AN47"  !CDS_PN = "AN47";
"G1_TXN8":   PN = "AJ47"  !CDS_PN = "AJ47";
"G1_TXN9":   PN = "AL47"  !CDS_PN = "AL47";
"G1_TXN10":   PN = "AN50"  !CDS_PN = "AN50";
"G1_TXN11":   PN = "AJ50"  !CDS_PN = "AJ50";
"G1_TXN12":   PN = "AL50"  !CDS_PN = "AL50";
"G1_TXN13":   PN = "AN53"  !CDS_PN = "AN53";
"G1_TXN14":   PN = "AJ53"  !CDS_PN = "AJ53";
"G1_TXN15":   PN = "AL53"  !CDS_PN = "AL53";
"G1_TXP0":   PN = "AP40"  !CDS_PN = "AP40";
"G1_TXP1":   PN = "AM40"  !CDS_PN = "AM40";
"G1_TXP2":   PN = "AH40"  !CDS_PN = "AH40";
"G1_TXP3":   PN = "AK40"  !CDS_PN = "AK40";
"G1_TXP4":   PN = "AN43"  !CDS_PN = "AN43";
"G1_TXP5":   PN = "AJ43"  !CDS_PN = "AJ43";
"G1_TXP6":   PN = "AL43"  !CDS_PN = "AL43";
"G1_TXP7":   PN = "AN46"  !CDS_PN = "AN46";
"G1_TXP8":   PN = "AJ46"  !CDS_PN = "AJ46";
"G1_TXP9":   PN = "AL46"  !CDS_PN = "AL46";
"G1_TXP10":   PN = "AN49"  !CDS_PN = "AN49";
"G1_TXP11":   PN = "AJ49"  !CDS_PN = "AJ49";
"G1_TXP12":   PN = "AL49"  !CDS_PN = "AL49";
"G1_TXP13":   PN = "AN52"  !CDS_PN = "AN52";
"G1_TXP14":   PN = "AJ52"  !CDS_PN = "AJ52";
"G1_TXP15":   PN = "AL52"  !CDS_PN = "AL52";
DRAWING = "@t6g_mb_lib.t6g(sch_1):page50";
BODY = "GENOA_SP5","I143": #LOCATION = "U26" !CDS_LOCATION = "U26" &SEC = "13" #&CDS_SEC = "13";
"G2_RXN0":   PN = "AE23"  !CDS_PN = "AE23";
"G2_RXN1":   PN = "AC23"  !CDS_PN = "AC23";
"G2_RXN2":   PN = "AG23"  !CDS_PN = "AG23";
"G2_RXN3":   PN = "AE26"  !CDS_PN = "AE26";
"G2_RXN4":   PN = "AC26"  !CDS_PN = "AC26";
"G2_RXN5":   PN = "AG26"  !CDS_PN = "AG26";
"G2_RXN6":   PN = "AE29"  !CDS_PN = "AE29";
"G2_RXN7":   PN = "AC29"  !CDS_PN = "AC29";
"G2_RXN8":   PN = "AG29"  !CDS_PN = "AG29";
"G2_RXN9":   PN = "AE32"  !CDS_PN = "AE32";
"G2_RXN10":   PN = "AC32"  !CDS_PN = "AC32";
"G2_RXN11":   PN = "AA32"  !CDS_PN = "AA32";
"G2_RXN12":   PN = "AG32"  !CDS_PN = "AG32";
"G2_RXN13":   PN = "AB35"  !CDS_PN = "AB35";
"G2_RXN14":   PN = "AD35"  !CDS_PN = "AD35";
"G2_RXN15":   PN = "AF35"  !CDS_PN = "AF35";
"G2_RXP0":   PN = "AE24"  !CDS_PN = "AE24";
"G2_RXP1":   PN = "AC24"  !CDS_PN = "AC24";
"G2_RXP2":   PN = "AG24"  !CDS_PN = "AG24";
"G2_RXP3":   PN = "AE27"  !CDS_PN = "AE27";
"G2_RXP4":   PN = "AC27"  !CDS_PN = "AC27";
"G2_RXP5":   PN = "AG27"  !CDS_PN = "AG27";
"G2_RXP6":   PN = "AE30"  !CDS_PN = "AE30";
"G2_RXP7":   PN = "AC30"  !CDS_PN = "AC30";
"G2_RXP8":   PN = "AG30"  !CDS_PN = "AG30";
"G2_RXP9":   PN = "AE33"  !CDS_PN = "AE33";
"G2_RXP10":   PN = "AC33"  !CDS_PN = "AC33";
"G2_RXP11":   PN = "AA33"  !CDS_PN = "AA33";
"G2_RXP12":   PN = "AG33"  !CDS_PN = "AG33";
"G2_RXP13":   PN = "AB36"  !CDS_PN = "AB36";
"G2_RXP14":   PN = "AD36"  !CDS_PN = "AD36";
"G2_RXP15":   PN = "AF36"  !CDS_PN = "AF36";
"G2_TXN0":   PN = "N24"  !CDS_PN = "N24";
"G2_TXN1":   PN = "J24"  !CDS_PN = "J24";
"G2_TXN2":   PN = "G24"  !CDS_PN = "G24";
"G2_TXN3":   PN = "L24"  !CDS_PN = "L24";
"G2_TXN4":   PN = "J27"  !CDS_PN = "J27";
"G2_TXN5":   PN = "G27"  !CDS_PN = "G27";
"G2_TXN6":   PN = "L27"  !CDS_PN = "L27";
"G2_TXN7":   PN = "J30"  !CDS_PN = "J30";
"G2_TXN8":   PN = "G30"  !CDS_PN = "G30";
"G2_TXN9":   PN = "L30"  !CDS_PN = "L30";
"G2_TXN10":   PN = "J33"  !CDS_PN = "J33";
"G2_TXN11":   PN = "G33"  !CDS_PN = "G33";
"G2_TXN12":   PN = "L33"  !CDS_PN = "L33";
"G2_TXN13":   PN = "H36"  !CDS_PN = "H36";
"G2_TXN14":   PN = "K36"  !CDS_PN = "K36";
"G2_TXN15":   PN = "M36"  !CDS_PN = "M36";
"G2_TXP0":   PN = "N23"  !CDS_PN = "N23";
"G2_TXP1":   PN = "J23"  !CDS_PN = "J23";
"G2_TXP2":   PN = "G23"  !CDS_PN = "G23";
"G2_TXP3":   PN = "L23"  !CDS_PN = "L23";
"G2_TXP4":   PN = "J26"  !CDS_PN = "J26";
"G2_TXP5":   PN = "G26"  !CDS_PN = "G26";
"G2_TXP6":   PN = "L26"  !CDS_PN = "L26";
"G2_TXP7":   PN = "J29"  !CDS_PN = "J29";
"G2_TXP8":   PN = "G29"  !CDS_PN = "G29";
"G2_TXP9":   PN = "L29"  !CDS_PN = "L29";
"G2_TXP10":   PN = "J32"  !CDS_PN = "J32";
"G2_TXP11":   PN = "G32"  !CDS_PN = "G32";
"G2_TXP12":   PN = "L32"  !CDS_PN = "L32";
"G2_TXP13":   PN = "H35"  !CDS_PN = "H35";
"G2_TXP14":   PN = "K35"  !CDS_PN = "K35";
"G2_TXP15":   PN = "M35"  !CDS_PN = "M35";
BODY = "GENOA_SP5","I144": #LOCATION = "U26" !CDS_LOCATION = "U26" &SEC = "14" #&CDS_SEC = "14";
"G3_RXN0||SATA20_RXN":   PN = "AL23"  !CDS_PN = "AL23";
"G3_RXN1||SATA21_RXN":   PN = "AJ23"  !CDS_PN = "AJ23";
"G3_RXN2||SATA22_RXN":   PN = "AN23"  !CDS_PN = "AN23";
"G3_RXN3||SATA23_RXN":   PN = "AL26"  !CDS_PN = "AL26";
"G3_RXN4||SATA24_RXN":   PN = "AJ26"  !CDS_PN = "AJ26";
"G3_RXN5||SATA25_RXN":   PN = "AN26"  !CDS_PN = "AN26";
"G3_RXN6||SATA26_RXN":   PN = "AL29"  !CDS_PN = "AL29";
"G3_RXN7||SATA27_RXN":   PN = "AJ29"  !CDS_PN = "AJ29";
"G3_RXN8||SATA30_RXN":   PN = "AN29"  !CDS_PN = "AN29";
"G3_RXN9||SATA31_RXN":   PN = "AL32"  !CDS_PN = "AL32";
"G3_RXN10||SATA32_RXN":   PN = "AJ32"  !CDS_PN = "AJ32";
"G3_RXN11||SATA33_RXN":   PN = "AN32"  !CDS_PN = "AN32";
"G3_RXN12||SATA34_RXN":   PN = "AK35"  !CDS_PN = "AK35";
"G3_RXN13||SATA35_RXN":   PN = "AH35"  !CDS_PN = "AH35";
"G3_RXN14||SATA36_RXN":   PN = "AM35"  !CDS_PN = "AM35";
"G3_RXN15||SATA37_RXN":   PN = "AP35"  !CDS_PN = "AP35";
"G3_RXP0||SATA20_RXP":   PN = "AL24"  !CDS_PN = "AL24";
"G3_RXP1||SATA21_RXP":   PN = "AJ24"  !CDS_PN = "AJ24";
"G3_RXP2||SATA22_RXP":   PN = "AN24"  !CDS_PN = "AN24";
"G3_RXP3||SATA23_RXP":   PN = "AL27"  !CDS_PN = "AL27";
"G3_RXP4||SATA24_RXP":   PN = "AJ27"  !CDS_PN = "AJ27";
"G3_RXP5||SATA25_RXP":   PN = "AN27"  !CDS_PN = "AN27";
"G3_RXP6||SATA26_RXP":   PN = "AL30"  !CDS_PN = "AL30";
"G3_RXP7||SATA27_RXP":   PN = "AJ30"  !CDS_PN = "AJ30";
"G3_RXP8||SATA30_RXP":   PN = "AN30"  !CDS_PN = "AN30";
"G3_RXP9||SATA31_RXP":   PN = "AL33"  !CDS_PN = "AL33";
"G3_RXP10||SATA32_RXP":   PN = "AJ33"  !CDS_PN = "AJ33";
"G3_RXP11||SATA33_RXP":   PN = "AN33"  !CDS_PN = "AN33";
"G3_RXP12||SATA34_RXP":   PN = "AK36"  !CDS_PN = "AK36";
"G3_RXP13||SATA35_RXP":   PN = "AH36"  !CDS_PN = "AH36";
"G3_RXP14||SATA36_RXP":   PN = "AM36"  !CDS_PN = "AM36";
"G3_RXP15||SATA37_RXP":   PN = "AP36"  !CDS_PN = "AP36";
"G3_TXN0||SATA20_TXN":   PN = "U24"  !CDS_PN = "U24";
"G3_TXN1||SATA21_TXN":   PN = "R24"  !CDS_PN = "R24";
"G3_TXN2||SATA22_TXN":   PN = "W24"  !CDS_PN = "W24";
"G3_TXN3||SATA23_TXN":   PN = "U27"  !CDS_PN = "U27";
"G3_TXN4||SATA24_TXN":   PN = "R27"  !CDS_PN = "R27";
"G3_TXN5||SATA25_TXN":   PN = "N27"  !CDS_PN = "N27";
"G3_TXN6||SATA26_TXN":   PN = "W27"  !CDS_PN = "W27";
"G3_TXN7||SATA27_TXN":   PN = "R30"  !CDS_PN = "R30";
"G3_TXN8||SATA30_TXN":   PN = "N30"  !CDS_PN = "N30";
"G3_TXN9||SATA31_TXN":   PN = "U30"  !CDS_PN = "U30";
"G3_TXN10||SATA32_TXN":   PN = "R33"  !CDS_PN = "R33";
"G3_TXN11||SATA33_TXN":   PN = "N33"  !CDS_PN = "N33";
"G3_TXN12||SATA34_TXN":   PN = "U33"  !CDS_PN = "U33";
"G3_TXN13||SATA35_TXN":   PN = "P36"  !CDS_PN = "P36";
"G3_TXN14||SATA36_TXN":   PN = "T36"  !CDS_PN = "T36";
"G3_TXN15||SATA37_TXN":   PN = "V36"  !CDS_PN = "V36";
"G3_TXP0||SATA20_TXP":   PN = "U23"  !CDS_PN = "U23";
"G3_TXP1||SATA21_TXP":   PN = "R23"  !CDS_PN = "R23";
"G3_TXP2||SATA22_TXP":   PN = "W23"  !CDS_PN = "W23";
"G3_TXP3||SATA23_TXP":   PN = "U26"  !CDS_PN = "U26";
"G3_TXP4||SATA24_TXP":   PN = "R26"  !CDS_PN = "R26";
"G3_TXP5||SATA25_TXP":   PN = "N26"  !CDS_PN = "N26";
"G3_TXP6||SATA26_TXP":   PN = "W26"  !CDS_PN = "W26";
"G3_TXP7||SATA27_TXP":   PN = "R29"  !CDS_PN = "R29";
"G3_TXP8||SATA30_TXP":   PN = "N29"  !CDS_PN = "N29";
"G3_TXP9||SATA31_TXP":   PN = "U29"  !CDS_PN = "U29";
"G3_TXP10||SATA32_TXP":   PN = "R32"  !CDS_PN = "R32";
"G3_TXP11||SATA33_TXP":   PN = "N32"  !CDS_PN = "N32";
"G3_TXP12||SATA34_TXP":   PN = "U32"  !CDS_PN = "U32";
"G3_TXP13||SATA35_TXP":   PN = "P35"  !CDS_PN = "P35";
"G3_TXP14||SATA36_TXP":   PN = "T35"  !CDS_PN = "T35";
"G3_TXP15||SATA37_TXP":   PN = "V35"  !CDS_PN = "V35";
DRAWING = "@t6g_mb_lib.t6g(sch_1):page51";
BODY = "GENOA_SP5","I147": #LOCATION = "U26" !CDS_LOCATION = "U26" &SEC = "15" #&CDS_SEC = "15";
"P0_RXN0||SATA00_RXN":   PN = "BW53"  !CDS_PN = "BW53";
"P0_RXN1||SATA01_RXN":   PN = "CA53"  !CDS_PN = "CA53";
"P0_RXN2||SATA02_RXN":   PN = "BU53"  !CDS_PN = "BU53";
"P0_RXN3||SATA03_RXN":   PN = "BW50"  !CDS_PN = "BW50";
"P0_RXN4||SATA04_RXN":   PN = "CA50"  !CDS_PN = "CA50";
"P0_RXN5||SATA05_RXN":   PN = "BU50"  !CDS_PN = "BU50";
"P0_RXN6||SATA06_RXN":   PN = "BW47"  !CDS_PN = "BW47";
"P0_RXN7||SATA07_RXN":   PN = "CA47"  !CDS_PN = "CA47";
"P0_RXN8||SATA10_RXN":   PN = "BU47"  !CDS_PN = "BU47";
"P0_RXN9||SATA11_RXN":   PN = "BW44"  !CDS_PN = "BW44";
"P0_RXN10||SATA12_RXN":   PN = "CA44"  !CDS_PN = "CA44";
"P0_RXN11||SATA13_RXN":   PN = "BU44"  !CDS_PN = "BU44";
"P0_RXN12||SATA14_RXN":   PN = "BY41"  !CDS_PN = "BY41";
"P0_RXN13||SATA15_RXN":   PN = "CB41"  !CDS_PN = "CB41";
"P0_RXN14||SATA16_RXN":   PN = "BV41"  !CDS_PN = "BV41";
"P0_RXN15||SATA17_RXN":   PN = "BT41"  !CDS_PN = "BT41";
"P0_RXP0||SATA00_RXP":   PN = "BW52"  !CDS_PN = "BW52";
"P0_RXP1||SATA01_RXP":   PN = "CA52"  !CDS_PN = "CA52";
"P0_RXP2||SATA02_RXP":   PN = "BU52"  !CDS_PN = "BU52";
"P0_RXP3||SATA03_RXP":   PN = "BW49"  !CDS_PN = "BW49";
"P0_RXP4||SATA04_RXP":   PN = "CA49"  !CDS_PN = "CA49";
"P0_RXP5||SATA05_RXP":   PN = "BU49"  !CDS_PN = "BU49";
"P0_RXP6||SATA06_RXP":   PN = "BW46"  !CDS_PN = "BW46";
"P0_RXP7||SATA07_RXP":   PN = "CA46"  !CDS_PN = "CA46";
"P0_RXP8||SATA10_RXP":   PN = "BU46"  !CDS_PN = "BU46";
"P0_RXP9||SATA11_RXP":   PN = "BW43"  !CDS_PN = "BW43";
"P0_RXP10||SATA12_RXP":   PN = "CA43"  !CDS_PN = "CA43";
"P0_RXP11||SATA13_RXP":   PN = "BU43"  !CDS_PN = "BU43";
"P0_RXP12||SATA14_RXP":   PN = "BY40"  !CDS_PN = "BY40";
"P0_RXP13||SATA15_RXP":   PN = "CB40"  !CDS_PN = "CB40";
"P0_RXP14||SATA16_RXP":   PN = "BV40"  !CDS_PN = "BV40";
"P0_RXP15||SATA17_RXP":   PN = "BT40"  !CDS_PN = "BT40";
"P0_TXN0||SATA00_TXN":   PN = "CN52"  !CDS_PN = "CN52";
"P0_TXN1||SATA01_TXN":   PN = "CR52"  !CDS_PN = "CR52";
"P0_TXN2||SATA02_TXN":   PN = "CL52"  !CDS_PN = "CL52";
"P0_TXN3||SATA03_TXN":   PN = "CN49"  !CDS_PN = "CN49";
"P0_TXN4||SATA04_TXN":   PN = "CR49"  !CDS_PN = "CR49";
"P0_TXN5||SATA05_TXN":   PN = "CU49"  !CDS_PN = "CU49";
"P0_TXN6||SATA06_TXN":   PN = "CL49"  !CDS_PN = "CL49";
"P0_TXN7||SATA07_TXN":   PN = "CR46"  !CDS_PN = "CR46";
"P0_TXN8||SATA10_TXN":   PN = "CU46"  !CDS_PN = "CU46";
"P0_TXN9||SATA11_TXN":   PN = "CN46"  !CDS_PN = "CN46";
"P0_TXN10||SATA12_TXN":   PN = "CR43"  !CDS_PN = "CR43";
"P0_TXN11||SATA13_TXN":   PN = "CU43"  !CDS_PN = "CU43";
"P0_TXN12||SATA14_TXN":   PN = "CN43"  !CDS_PN = "CN43";
"P0_TXN13||SATA15_TXN":   PN = "CT40"  !CDS_PN = "CT40";
"P0_TXN14||SATA16_TXN":   PN = "CP40"  !CDS_PN = "CP40";
"P0_TXN15||SATA17_TXN":   PN = "CM40"  !CDS_PN = "CM40";
"P0_TXP0||SATA00_TXP":   PN = "CN53"  !CDS_PN = "CN53";
"P0_TXP1||SATA01_TXP":   PN = "CR53"  !CDS_PN = "CR53";
"P0_TXP2||SATA02_TXP":   PN = "CL53"  !CDS_PN = "CL53";
"P0_TXP3||SATA03_TXP":   PN = "CN50"  !CDS_PN = "CN50";
"P0_TXP4||SATA04_TXP":   PN = "CR50"  !CDS_PN = "CR50";
"P0_TXP5||SATA05_TXP":   PN = "CU50"  !CDS_PN = "CU50";
"P0_TXP6||SATA06_TXP":   PN = "CL50"  !CDS_PN = "CL50";
"P0_TXP7||SATA07_TXP":   PN = "CR47"  !CDS_PN = "CR47";
"P0_TXP8||SATA10_TXP":   PN = "CU47"  !CDS_PN = "CU47";
"P0_TXP9||SATA11_TXP":   PN = "CN47"  !CDS_PN = "CN47";
"P0_TXP10||SATA12_TXP":   PN = "CR44"  !CDS_PN = "CR44";
"P0_TXP11||SATA13_TXP":   PN = "CU44"  !CDS_PN = "CU44";
"P0_TXP12||SATA14_TXP":   PN = "CN44"  !CDS_PN = "CN44";
"P0_TXP13||SATA15_TXP":   PN = "CT41"  !CDS_PN = "CT41";
"P0_TXP14||SATA16_TXP":   PN = "CP41"  !CDS_PN = "CP41";
"P0_TXP15||SATA17_TXP":   PN = "CM41"  !CDS_PN = "CM41";
BODY = "GENOA_SP5","I148": #LOCATION = "U26" !CDS_LOCATION = "U26" &SEC = "16" #&CDS_SEC = "16";
"P1_RXN0":   PN = "CE53"  !CDS_PN = "CE53";
"P1_RXN1":   PN = "CG53"  !CDS_PN = "CG53";
"P1_RXN2":   PN = "CC53"  !CDS_PN = "CC53";
"P1_RXN3":   PN = "CE50"  !CDS_PN = "CE50";
"P1_RXN4":   PN = "CG50"  !CDS_PN = "CG50";
"P1_RXN5":   PN = "CC50"  !CDS_PN = "CC50";
"P1_RXN6":   PN = "CE47"  !CDS_PN = "CE47";
"P1_RXN7":   PN = "CG47"  !CDS_PN = "CG47";
"P1_RXN8":   PN = "CC47"  !CDS_PN = "CC47";
"P1_RXN9":   PN = "CE44"  !CDS_PN = "CE44";
"P1_RXN10":   PN = "CG44"  !CDS_PN = "CG44";
"P1_RXN11":   PN = "CJ44"  !CDS_PN = "CJ44";
"P1_RXN12":   PN = "CC44"  !CDS_PN = "CC44";
"P1_RXN13":   PN = "CH41"  !CDS_PN = "CH41";
"P1_RXN14":   PN = "CF41"  !CDS_PN = "CF41";
"P1_RXN15":   PN = "CD41"  !CDS_PN = "CD41";
"P1_RXP0":   PN = "CE52"  !CDS_PN = "CE52";
"P1_RXP1":   PN = "CG52"  !CDS_PN = "CG52";
"P1_RXP2":   PN = "CC52"  !CDS_PN = "CC52";
"P1_RXP3":   PN = "CE49"  !CDS_PN = "CE49";
"P1_RXP4":   PN = "CG49"  !CDS_PN = "CG49";
"P1_RXP5":   PN = "CC49"  !CDS_PN = "CC49";
"P1_RXP6":   PN = "CE46"  !CDS_PN = "CE46";
"P1_RXP7":   PN = "CG46"  !CDS_PN = "CG46";
"P1_RXP8":   PN = "CC46"  !CDS_PN = "CC46";
"P1_RXP9":   PN = "CE43"  !CDS_PN = "CE43";
"P1_RXP10":   PN = "CG43"  !CDS_PN = "CG43";
"P1_RXP11":   PN = "CJ43"  !CDS_PN = "CJ43";
"P1_RXP12":   PN = "CC43"  !CDS_PN = "CC43";
"P1_RXP13":   PN = "CH40"  !CDS_PN = "CH40";
"P1_RXP14":   PN = "CF40"  !CDS_PN = "CF40";
"P1_RXP15":   PN = "CD40"  !CDS_PN = "CD40";
"P1_TXN0":   PN = "CU52"  !CDS_PN = "CU52";
"P1_TXN1":   PN = "DA52"  !CDS_PN = "DA52";
"P1_TXN2":   PN = "DC52"  !CDS_PN = "DC52";
"P1_TXN3":   PN = "CW52"  !CDS_PN = "CW52";
"P1_TXN4":   PN = "DA49"  !CDS_PN = "DA49";
"P1_TXN5":   PN = "DC49"  !CDS_PN = "DC49";
"P1_TXN6":   PN = "CW49"  !CDS_PN = "CW49";
"P1_TXN7":   PN = "DA46"  !CDS_PN = "DA46";
"P1_TXN8":   PN = "DC46"  !CDS_PN = "DC46";
"P1_TXN9":   PN = "CW46"  !CDS_PN = "CW46";
"P1_TXN10":   PN = "DA43"  !CDS_PN = "DA43";
"P1_TXN11":   PN = "DC43"  !CDS_PN = "DC43";
"P1_TXN12":   PN = "CW43"  !CDS_PN = "CW43";
"P1_TXN13":   PN = "DB40"  !CDS_PN = "DB40";
"P1_TXN14":   PN = "CY40"  !CDS_PN = "CY40";
"P1_TXN15":   PN = "CV40"  !CDS_PN = "CV40";
"P1_TXP0":   PN = "CU53"  !CDS_PN = "CU53";
"P1_TXP1":   PN = "DA53"  !CDS_PN = "DA53";
"P1_TXP2":   PN = "DC53"  !CDS_PN = "DC53";
"P1_TXP3":   PN = "CW53"  !CDS_PN = "CW53";
"P1_TXP4":   PN = "DA50"  !CDS_PN = "DA50";
"P1_TXP5":   PN = "DC50"  !CDS_PN = "DC50";
"P1_TXP6":   PN = "CW50"  !CDS_PN = "CW50";
"P1_TXP7":   PN = "DA47"  !CDS_PN = "DA47";
"P1_TXP8":   PN = "DC47"  !CDS_PN = "DC47";
"P1_TXP9":   PN = "CW47"  !CDS_PN = "CW47";
"P1_TXP10":   PN = "DA44"  !CDS_PN = "DA44";
"P1_TXP11":   PN = "DC44"  !CDS_PN = "DC44";
"P1_TXP12":   PN = "CW44"  !CDS_PN = "CW44";
"P1_TXP13":   PN = "DB41"  !CDS_PN = "DB41";
"P1_TXP14":   PN = "CY41"  !CDS_PN = "CY41";
"P1_TXP15":   PN = "CV41"  !CDS_PN = "CV41";
DRAWING = "@t6g_mb_lib.t6g(sch_1):page52";
BODY = "GENOA_SP5","I147": #LOCATION = "U26" !CDS_LOCATION = "U26" &SEC = "18" #&CDS_SEC = "18";
"P3_RXN0":   PN = "CV36"  !CDS_PN = "CV36";
"P3_RXN1":   PN = "CY36"  !CDS_PN = "CY36";
"P3_RXN2":   PN = "DB36"  !CDS_PN = "DB36";
"P3_RXN3":   PN = "CW33"  !CDS_PN = "CW33";
"P3_RXN4":   PN = "DC33"  !CDS_PN = "DC33";
"P3_RXN5":   PN = "DA33"  !CDS_PN = "DA33";
"P3_RXN6":   PN = "CW30"  !CDS_PN = "CW30";
"P3_RXN7":   PN = "DC30"  !CDS_PN = "DC30";
"P3_RXN8":   PN = "DA30"  !CDS_PN = "DA30";
"P3_RXN9":   PN = "CW27"  !CDS_PN = "CW27";
"P3_RXN10":   PN = "DC27"  !CDS_PN = "DC27";
"P3_RXN11":   PN = "DA27"  !CDS_PN = "DA27";
"P3_RXN12":   PN = "CW24"  !CDS_PN = "CW24";
"P3_RXN13":   PN = "DC24"  !CDS_PN = "DC24";
"P3_RXN14":   PN = "DA24"  !CDS_PN = "DA24";
"P3_RXN15":   PN = "CU24"  !CDS_PN = "CU24";
"P3_RXP0":   PN = "CV35"  !CDS_PN = "CV35";
"P3_RXP1":   PN = "CY35"  !CDS_PN = "CY35";
"P3_RXP2":   PN = "DB35"  !CDS_PN = "DB35";
"P3_RXP3":   PN = "CW32"  !CDS_PN = "CW32";
"P3_RXP4":   PN = "DC32"  !CDS_PN = "DC32";
"P3_RXP5":   PN = "DA32"  !CDS_PN = "DA32";
"P3_RXP6":   PN = "CW29"  !CDS_PN = "CW29";
"P3_RXP7":   PN = "DC29"  !CDS_PN = "DC29";
"P3_RXP8":   PN = "DA29"  !CDS_PN = "DA29";
"P3_RXP9":   PN = "CW26"  !CDS_PN = "CW26";
"P3_RXP10":   PN = "DC26"  !CDS_PN = "DC26";
"P3_RXP11":   PN = "DA26"  !CDS_PN = "DA26";
"P3_RXP12":   PN = "CW23"  !CDS_PN = "CW23";
"P3_RXP13":   PN = "DC23"  !CDS_PN = "DC23";
"P3_RXP14":   PN = "DA23"  !CDS_PN = "DA23";
"P3_RXP15":   PN = "CU23"  !CDS_PN = "CU23";
"P3_TXN0":   PN = "CD35"  !CDS_PN = "CD35";
"P3_TXN1":   PN = "CF35"  !CDS_PN = "CF35";
"P3_TXN2":   PN = "CH35"  !CDS_PN = "CH35";
"P3_TXN3":   PN = "CC32"  !CDS_PN = "CC32";
"P3_TXN4":   PN = "CJ32"  !CDS_PN = "CJ32";
"P3_TXN5":   PN = "CG32"  !CDS_PN = "CG32";
"P3_TXN6":   PN = "CE32"  !CDS_PN = "CE32";
"P3_TXN7":   PN = "CC29"  !CDS_PN = "CC29";
"P3_TXN8":   PN = "CG29"  !CDS_PN = "CG29";
"P3_TXN9":   PN = "CE29"  !CDS_PN = "CE29";
"P3_TXN10":   PN = "CC26"  !CDS_PN = "CC26";
"P3_TXN11":   PN = "CG26"  !CDS_PN = "CG26";
"P3_TXN12":   PN = "CE26"  !CDS_PN = "CE26";
"P3_TXN13":   PN = "CC23"  !CDS_PN = "CC23";
"P3_TXN14":   PN = "CG23"  !CDS_PN = "CG23";
"P3_TXN15":   PN = "CE23"  !CDS_PN = "CE23";
"P3_TXP0":   PN = "CD36"  !CDS_PN = "CD36";
"P3_TXP1":   PN = "CF36"  !CDS_PN = "CF36";
"P3_TXP2":   PN = "CH36"  !CDS_PN = "CH36";
"P3_TXP3":   PN = "CC33"  !CDS_PN = "CC33";
"P3_TXP4":   PN = "CJ33"  !CDS_PN = "CJ33";
"P3_TXP5":   PN = "CG33"  !CDS_PN = "CG33";
"P3_TXP6":   PN = "CE33"  !CDS_PN = "CE33";
"P3_TXP7":   PN = "CC30"  !CDS_PN = "CC30";
"P3_TXP8":   PN = "CG30"  !CDS_PN = "CG30";
"P3_TXP9":   PN = "CE30"  !CDS_PN = "CE30";
"P3_TXP10":   PN = "CC27"  !CDS_PN = "CC27";
"P3_TXP11":   PN = "CG27"  !CDS_PN = "CG27";
"P3_TXP12":   PN = "CE27"  !CDS_PN = "CE27";
"P3_TXP13":   PN = "CC24"  !CDS_PN = "CC24";
"P3_TXP14":   PN = "CG24"  !CDS_PN = "CG24";
"P3_TXP15":   PN = "CE24"  !CDS_PN = "CE24";
BODY = "GENOA_SP5","I148": #LOCATION = "U26" !CDS_LOCATION = "U26" &SEC = "17" #&CDS_SEC = "17";
"P2_RXN0":   PN = "CM36"  !CDS_PN = "CM36";
"P2_RXN1":   PN = "CP36"  !CDS_PN = "CP36";
"P2_RXN2":   PN = "CT36"  !CDS_PN = "CT36";
"P2_RXN3":   PN = "CN33"  !CDS_PN = "CN33";
"P2_RXN4":   PN = "CU33"  !CDS_PN = "CU33";
"P2_RXN5":   PN = "CR33"  !CDS_PN = "CR33";
"P2_RXN6":   PN = "CN30"  !CDS_PN = "CN30";
"P2_RXN7":   PN = "CU30"  !CDS_PN = "CU30";
"P2_RXN8":   PN = "CR30"  !CDS_PN = "CR30";
"P2_RXN9":   PN = "CL27"  !CDS_PN = "CL27";
"P2_RXN10":   PN = "CU27"  !CDS_PN = "CU27";
"P2_RXN11":   PN = "CR27"  !CDS_PN = "CR27";
"P2_RXN12":   PN = "CN27"  !CDS_PN = "CN27";
"P2_RXN13":   PN = "CL24"  !CDS_PN = "CL24";
"P2_RXN14":   PN = "CR24"  !CDS_PN = "CR24";
"P2_RXN15":   PN = "CN24"  !CDS_PN = "CN24";
"P2_RXP0":   PN = "CM35"  !CDS_PN = "CM35";
"P2_RXP1":   PN = "CP35"  !CDS_PN = "CP35";
"P2_RXP2":   PN = "CT35"  !CDS_PN = "CT35";
"P2_RXP3":   PN = "CN32"  !CDS_PN = "CN32";
"P2_RXP4":   PN = "CU32"  !CDS_PN = "CU32";
"P2_RXP5":   PN = "CR32"  !CDS_PN = "CR32";
"P2_RXP6":   PN = "CN29"  !CDS_PN = "CN29";
"P2_RXP7":   PN = "CU29"  !CDS_PN = "CU29";
"P2_RXP8":   PN = "CR29"  !CDS_PN = "CR29";
"P2_RXP9":   PN = "CL26"  !CDS_PN = "CL26";
"P2_RXP10":   PN = "CU26"  !CDS_PN = "CU26";
"P2_RXP11":   PN = "CR26"  !CDS_PN = "CR26";
"P2_RXP12":   PN = "CN26"  !CDS_PN = "CN26";
"P2_RXP13":   PN = "CL23"  !CDS_PN = "CL23";
"P2_RXP14":   PN = "CR23"  !CDS_PN = "CR23";
"P2_RXP15":   PN = "CN23"  !CDS_PN = "CN23";
"P2_TXN0":   PN = "BT35"  !CDS_PN = "BT35";
"P2_TXN1":   PN = "BV35"  !CDS_PN = "BV35";
"P2_TXN2":   PN = "CB35"  !CDS_PN = "CB35";
"P2_TXN3":   PN = "BY35"  !CDS_PN = "BY35";
"P2_TXN4":   PN = "BU32"  !CDS_PN = "BU32";
"P2_TXN5":   PN = "CA32"  !CDS_PN = "CA32";
"P2_TXN6":   PN = "BW32"  !CDS_PN = "BW32";
"P2_TXN7":   PN = "BU29"  !CDS_PN = "BU29";
"P2_TXN8":   PN = "CA29"  !CDS_PN = "CA29";
"P2_TXN9":   PN = "BW29"  !CDS_PN = "BW29";
"P2_TXN10":   PN = "BU26"  !CDS_PN = "BU26";
"P2_TXN11":   PN = "CA26"  !CDS_PN = "CA26";
"P2_TXN12":   PN = "BW26"  !CDS_PN = "BW26";
"P2_TXN13":   PN = "BU23"  !CDS_PN = "BU23";
"P2_TXN14":   PN = "CA23"  !CDS_PN = "CA23";
"P2_TXN15":   PN = "BW23"  !CDS_PN = "BW23";
"P2_TXP0":   PN = "BT36"  !CDS_PN = "BT36";
"P2_TXP1":   PN = "BV36"  !CDS_PN = "BV36";
"P2_TXP2":   PN = "CB36"  !CDS_PN = "CB36";
"P2_TXP3":   PN = "BY36"  !CDS_PN = "BY36";
"P2_TXP4":   PN = "BU33"  !CDS_PN = "BU33";
"P2_TXP5":   PN = "CA33"  !CDS_PN = "CA33";
"P2_TXP6":   PN = "BW33"  !CDS_PN = "BW33";
"P2_TXP7":   PN = "BU30"  !CDS_PN = "BU30";
"P2_TXP8":   PN = "CA30"  !CDS_PN = "CA30";
"P2_TXP9":   PN = "BW30"  !CDS_PN = "BW30";
"P2_TXP10":   PN = "BU27"  !CDS_PN = "BU27";
"P2_TXP11":   PN = "CA27"  !CDS_PN = "CA27";
"P2_TXP12":   PN = "BW27"  !CDS_PN = "BW27";
"P2_TXP13":   PN = "BU24"  !CDS_PN = "BU24";
"P2_TXP14":   PN = "CA24"  !CDS_PN = "CA24";
"P2_TXP15":   PN = "BW24"  !CDS_PN = "BW24";
DRAWING = "@t6g_mb_lib.t6g(sch_1):page54";
BODY = "GENOA_SP5","I190": #LOCATION = "U26" !CDS_LOCATION = "U26" &SEC = "20" #&CDS_SEC = "20";
"ALERT_L":   PN = "A68"  !CDS_PN = "A68";
"AZ_BITCLK":   PN = "C32"  !CDS_PN = "C32";
"AZ_RST_L||SW_MDATA1":   PN = "A34"  !CDS_PN = "A34";
"AZ_SDIN0||SW_MDATA3":   PN = "C33"  !CDS_PN = "C33";
"AZ_SDIN1||SW_MCLK":   PN = "D33"  !CDS_PN = "D33";
"AZ_SDIN2||SW_MDATA0":   PN = "A33"  !CDS_PN = "A33";
"AZ_SDOUT||SW_MDATA2":   PN = "A32"  !CDS_PN = "A32";
"AZ_SYNC":   PN = "D32"  !CDS_PN = "D32";
"BP0":   PN = "C63"  !CDS_PN = "C63";
"BP1":   PN = "C62"  !CDS_PN = "C62";
"BP2":   PN = "A63"  !CDS_PN = "A63";
"BP3":   PN = "A62"  !CDS_PN = "A62";
"CORETYPE0":   PN = "C70"  !CDS_PN = "C70";
"CORETYPE1":   PN = "B69"  !CDS_PN = "B69";
"CORETYPE2":   PN = "D68"  !CDS_PN = "D68";
"CPU_PRESENT_L":   PN = "B66"  !CDS_PN = "B66";
"DBREQ_L":   PN = "C16"  !CDS_PN = "C16";
"PCC0_L":   PN = "C22"  !CDS_PN = "C22";
"PCC1_L":   PN = "DG72"  !CDS_PN = "DG72";
"PROCHOT_L":   PN = "A69"  !CDS_PN = "A69";
"RTC_LDO_SELECT":   PN = "DH8"  !CDS_PN = "DH8";
"SA0":   PN = "DJ55"  !CDS_PN = "DJ55";
"SA1":   PN = "DJ56"  !CDS_PN = "DJ56";
"SIC":   PN = "DJ71"  !CDS_PN = "DJ71";
"SID":   PN = "DH71"  !CDS_PN = "DH71";
"SP5R1":   PN = "C19"  !CDS_PN = "C19";
"SP5R2":   PN = "C68"  !CDS_PN = "C68";
"SP5R3":   PN = "DH73"  !CDS_PN = "DH73";
"SP5R4":   PN = "DH10"  !CDS_PN = "DH10";
"SVC0":   PN = "A23"  !CDS_PN = "A23";
"SVC1":   PN = "DJ72"  !CDS_PN = "DJ72";
"SVD0":   PN = "A22"  !CDS_PN = "A22";
"SVD1":   PN = "DH72"  !CDS_PN = "DH72";
"SVT0":   PN = "B21"  !CDS_PN = "B21";
"SVT1":   PN = "DG73"  !CDS_PN = "DG73";
"TCK":   PN = "B17"  !CDS_PN = "B17";
"TDI":   PN = "C17"  !CDS_PN = "C17";
"TDO":   PN = "C18"  !CDS_PN = "C18";
"TEST4_CCD0":   PN = "AA50"  !CDS_PN = "AA50";
"TEST4_CCD1":   PN = "CJ28"  !CDS_PN = "CJ28";
"TEST4_CCD2":   PN = "CJ48"  !CDS_PN = "CJ48";
"TEST4_CCD3":   PN = "AA30"  !CDS_PN = "AA30";
"TEST4_CCD4":   PN = "AA52"  !CDS_PN = "AA52";
"TEST4_CCD5":   PN = "CJ26"  !CDS_PN = "CJ26";
"TEST4_CCD6":   PN = "CJ50"  !CDS_PN = "CJ50";
"TEST4_CCD7":   PN = "AA27"  !CDS_PN = "AA27";
"TEST4_CCD8":   PN = "AA48"  !CDS_PN = "AA48";
"TEST4_CCD9":   PN = "CK30"  !CDS_PN = "CK30";
"TEST4_CCD10":   PN = "CJ47"  !CDS_PN = "CJ47";
"TEST4_CCD11":   PN = "AA28"  !CDS_PN = "AA28";
"TEST4_IOD":   PN = "AA25"  !CDS_PN = "AA25";
"TEST5_CCD0":   PN = "AA51"  !CDS_PN = "AA51";
"TEST5_CCD1":   PN = "CJ27"  !CDS_PN = "CJ27";
"TEST5_CCD2":   PN = "CJ49"  !CDS_PN = "CJ49";
"TEST5_CCD3":   PN = "Y30"  !CDS_PN = "Y30";
"TEST5_CCD4":   PN = "AA53"  !CDS_PN = "AA53";
"TEST5_CCD5":   PN = "CJ25"  !CDS_PN = "CJ25";
"TEST5_CCD6":   PN = "CJ51"  !CDS_PN = "CJ51";
"TEST5_CCD7":   PN = "AA26"  !CDS_PN = "AA26";
"TEST5_CCD8":   PN = "Y47"  !CDS_PN = "Y47";
"TEST5_CCD9":   PN = "CK29"  !CDS_PN = "CK29";
"TEST5_CCD10":   PN = "CK47"  !CDS_PN = "CK47";
"TEST5_CCD11":   PN = "Y29"  !CDS_PN = "Y29";
"TEST5_IOD":   PN = "AA24"  !CDS_PN = "AA24";
"TEST6_CCD0":   PN = "AA46"  !CDS_PN = "AA46";
"TEST6_CCD1":   PN = "CJ30"  !CDS_PN = "CJ30";
"TEST6_CCD2":   PN = "CJ46"  !CDS_PN = "CJ46";
"TEST6_CCD3":   PN = "Y46"  !CDS_PN = "Y46";
"TEST6_IOD":   PN = "AA49"  !CDS_PN = "AA49";
"TEST6_X3D0":   PN = "AA47"  !CDS_PN = "AA47";
"TEST6_X3D1":   PN = "CJ29"  !CDS_PN = "CJ29";
"TEST6_X3D2":   PN = "AA29"  !CDS_PN = "AA29";
"TEST6_X3D3":   PN = "CJ52"  !CDS_PN = "CJ52";
"TEST6_X3D4":   PN = "AA23"  !CDS_PN = "AA23";
"TEST6_X3D5":   PN = "CJ53"  !CDS_PN = "CJ53";
"TEST41_IOD":   PN = "W31"  !CDS_PN = "W31";
"TEST47_CCD0":   PN = "B60"  !CDS_PN = "B60";
"TEST47_CCD1":   PN = "CJ24"  !CDS_PN = "CJ24";
"TEST47_CCD2":   PN = "CK46"  !CDS_PN = "CK46";
"TEST47_CCD3":   PN = "E32"  !CDS_PN = "E32";
"TEST47_IOD0":   PN = "B58"  !CDS_PN = "B58";
"TEST47_IOD1":   PN = "D7"  !CDS_PN = "D7";
"TEST50_IOD":   PN = "B61"  !CDS_PN = "B61";
"THERMTRIP_L":   PN = "DJ9"  !CDS_PN = "DJ9";
"TMS":   PN = "A16"  !CDS_PN = "A16";
"TRST_L":   PN = "A17"  !CDS_PN = "A17";
"UART0_CTS_L||UART2_TXD||AGPIO135":   PN = "DJ33"  !CDS_PN = "DJ33";
"UART0_INTR||AGPIO139":   PN = "DG34"  !CDS_PN = "DG34";
"UART0_RTS_L||UART2_RXD||AGPIO137":   PN = "DF34"  !CDS_PN = "DF34";
"UART0_RXD||AGPIO136":   PN = "DG35"  !CDS_PN = "DG35";
"UART0_TXD||AGPIO138":   PN = "DJ34"  !CDS_PN = "DJ34";
"UART1_RXD||AGPIO141":   PN = "DH33"  !CDS_PN = "DH33";
"UART1_TXD||AGPIO142":   PN = "DJ32"  !CDS_PN = "DJ32";
"VDD_11_S3_SENSE":   PN = "DH3"  !CDS_PN = "DH3";
"VDD_18_S5_SENSE":   PN = "C74"  !CDS_PN = "C74";
"VDD_33_S5_SENSE":   PN = "BP53"  !CDS_PN = "BP53";
"VDDCR_CPU0_SENSE":   PN = "C2"  !CDS_PN = "C2";
"VDDCR_CPU1_SENSE":   PN = "DG3"  !CDS_PN = "DG3";
"VDDCR_SOC_SENSE":   PN = "B3"  !CDS_PN = "B3";
"VDDIO_SENSE":   PN = "BR53"  !CDS_PN = "BR53";
"VSS_SENSE_A":   PN = "C3"  !CDS_PN = "C3";
"VSS_SENSE_B":   PN = "BR54"  !CDS_PN = "BR54";
"VSS_SENSE_C":   PN = "DJ3"  !CDS_PN = "DJ3";
"VSS_SENSE_D":   PN = "B73"  !CDS_PN = "B73";
"XTRIG_L4":   PN = "C66"  !CDS_PN = "C66";
"XTRIG_L5":   PN = "C65"  !CDS_PN = "C65";
"XTRIG_L6":   PN = "A66"  !CDS_PN = "A66";
"XTRIG_L7":   PN = "A65"  !CDS_PN = "A65";
BODY = "Q_RES","I203": #LOCATION = "R529" !CDS_LOCATION = "R529" &SEC = "1" #&CDS_SEC = "1";
"A":   PN = "1"  !CDS_PN = "1";
"B":   PN = "2"  !CDS_PN = "2";
BODY = "TP","I237": #LOCATION = "TP20" !CDS_LOCATION = "TP20" &SEC = "1" #&CDS_SEC = "1";
"TP":   PN = "1"  !CDS_PN = "1";
BODY = "TP","I238": #LOCATION = "TP19" !CDS_LOCATION = "TP19" &SEC = "1" #&CDS_SEC = "1";
"TP":   PN = "1"  !CDS_PN = "1";
BODY = "TP","I240": #LOCATION = "TP18" !CDS_LOCATION = "TP18" &SEC = "1" #&CDS_SEC = "1";
"TP":   PN = "1"  !CDS_PN = "1";
BODY = "TP","I241": #LOCATION = "TP17" !CDS_LOCATION = "TP17" &SEC = "1" #&CDS_SEC = "1";
"TP":   PN = "1"  !CDS_PN = "1";
BODY = "TP","I242": #LOCATION = "TP16" !CDS_LOCATION = "TP16" &SEC = "1" #&CDS_SEC = "1";
"TP":   PN = "1"  !CDS_PN = "1";
BODY = "TP","I243": #LOCATION = "TP15" !CDS_LOCATION = "TP15" &SEC = "1" #&CDS_SEC = "1";
"TP":   PN = "1"  !CDS_PN = "1";
BODY = "TP","I244": #LOCATION = "TP14" !CDS_LOCATION = "TP14" &SEC = "1" #&CDS_SEC = "1";
"TP":   PN = "1"  !CDS_PN = "1";
BODY = "TP","I245": #LOCATION = "TP13" !CDS_LOCATION = "TP13" &SEC = "1" #&CDS_SEC = "1";
"TP":   PN = "1"  !CDS_PN = "1";
BODY = "TP","I272": #LOCATION = "TP12" !CDS_LOCATION = "TP12" &SEC = "1" #&CDS_SEC = "1";
"TP":   PN = "1"  !CDS_PN = "1";
BODY = "TP","I273": #LOCATION = "TP11" !CDS_LOCATION = "TP11" &SEC = "1" #&CDS_SEC = "1";
"TP":   PN = "1"  !CDS_PN = "1";
BODY = "Q_RES","I308": #LOCATION = "R528" !CDS_LOCATION = "R528" &SEC = "1" #&CDS_SEC = "1";
"A":   PN = "1"  !CDS_PN = "1";
"B":   PN = "2"  !CDS_PN = "2";
BODY = "Q_RES","I309": #LOCATION = "R527" !CDS_LOCATION = "R527" &SEC = "1" #&CDS_SEC = "1";
"A":   PN = "1"  !CDS_PN = "1";
"B":   PN = "2"  !CDS_PN = "2";
BODY = "Q_CAP","I310": #LOCATION = "C235" !CDS_LOCATION = "C235" &SEC = "1" #&CDS_SEC = "1";
"A":   PN = "1"  !CDS_PN = "1";
"B":   PN = "2"  !CDS_PN = "2";
BODY = "Q_CAP","I311": #LOCATION = "C234" !CDS_LOCATION = "C234" &SEC = "1" #&CDS_SEC = "1";
"A":   PN = "1"  !CDS_PN = "1";
"B":   PN = "2"  !CDS_PN = "2";
BODY = "Q_RES","I314": #LOCATION = "R526" !CDS_LOCATION = "R526" &SEC = "1" #&CDS_SEC = "1";
"A":   PN = "1"  !CDS_PN = "1";
"B":   PN = "2"  !CDS_PN = "2";
BODY = "Q_CAP","I315": #LOCATION = "C233" !CDS_LOCATION = "C233" &SEC = "1" #&CDS_SEC = "1";
"A":   PN = "1"  !CDS_PN = "1";
"B":   PN = "2"  !CDS_PN = "2";
BODY = "Q_RES","I316": #LOCATION = "R525" !CDS_LOCATION = "R525" &SEC = "1" #&CDS_SEC = "1";
"A":   PN = "1"  !CDS_PN = "1";
"B":   PN = "2"  !CDS_PN = "2";
BODY = "Q_RES","I317": #LOCATION = "R524" !CDS_LOCATION = "R524" &SEC = "1" #&CDS_SEC = "1";
"A":   PN = "1"  !CDS_PN = "1";
"B":   PN = "2"  !CDS_PN = "2";
BODY = "Q_CAP","I318": #LOCATION = "C232" !CDS_LOCATION = "C232" &SEC = "1" #&CDS_SEC = "1";
"A":   PN = "1"  !CDS_PN = "1";
"B":   PN = "2"  !CDS_PN = "2";
BODY = "Q_CAP","I319": #LOCATION = "C231" !CDS_LOCATION = "C231" &SEC = "1" #&CDS_SEC = "1";
"A":   PN = "1"  !CDS_PN = "1";
"B":   PN = "2"  !CDS_PN = "2";
BODY = "Q_RES","I324": #LOCATION = "R523" !CDS_LOCATION = "R523" &SEC = "1" #&CDS_SEC = "1";
"A":   PN = "1"  !CDS_PN = "1";
"B":   PN = "2"  !CDS_PN = "2";
BODY = "Q_CAP","I325": #LOCATION = "C230" !CDS_LOCATION = "C230" &SEC = "1" #&CDS_SEC = "1";
"A":   PN = "1"  !CDS_PN = "1";
"B":   PN = "2"  !CDS_PN = "2";
BODY = "Q_RES","I333": #LOCATION = "PR170" !CDS_LOCATION = "PR170" &SEC = "1" #&CDS_SEC = "1";
"A":   PN = "1"  !CDS_PN = "1";
"B":   PN = "2"  !CDS_PN = "2";
BODY = "Q_RES","I334": #LOCATION = "PR169" !CDS_LOCATION = "PR169" &SEC = "1" #&CDS_SEC = "1";
"A":   PN = "1"  !CDS_PN = "1";
"B":   PN = "2"  !CDS_PN = "2";
BODY = "Q_RES","I337": #LOCATION = "PR237" !CDS_LOCATION = "PR237" &SEC = "1" #&CDS_SEC = "1";
"A":   PN = "1"  !CDS_PN = "1";
"B":   PN = "2"  !CDS_PN = "2";
BODY = "Q_RES","I338": #LOCATION = "PR236" !CDS_LOCATION = "PR236" &SEC = "1" #&CDS_SEC = "1";
"A":   PN = "1"  !CDS_PN = "1";
"B":   PN = "2"  !CDS_PN = "2";
BODY = "Q_RES","I361": #LOCATION = "R618" !CDS_LOCATION = "R618" &SEC = "1" #&CDS_SEC = "1";
"A":   PN = "1"  !CDS_PN = "1";
"B":   PN = "2"  !CDS_PN = "2";
BODY = "Q_RES","I362": #LOCATION = "R486" !CDS_LOCATION = "R486" &SEC = "1" #&CDS_SEC = "1";
"A":   PN = "1"  !CDS_PN = "1";
"B":   PN = "2"  !CDS_PN = "2";
BODY = "Q_RES","I363": #LOCATION = "R928" !CDS_LOCATION = "R928" &SEC = "1" #&CDS_SEC = "1";
"A":   PN = "1"  !CDS_PN = "1";
"B":   PN = "2"  !CDS_PN = "2";
BODY = "Q_RES","I364": #LOCATION = "R862" !CDS_LOCATION = "R862" &SEC = "1" #&CDS_SEC = "1";
"A":   PN = "1"  !CDS_PN = "1";
"B":   PN = "2"  !CDS_PN = "2";
BODY = "Q_RES","I371": #LOCATION = "R929" !CDS_LOCATION = "R929" &SEC = "1" #&CDS_SEC = "1";
"A":   PN = "1"  !CDS_PN = "1";
"B":   PN = "2"  !CDS_PN = "2";
BODY = "Q_RES","I372": #LOCATION = "R930" !CDS_LOCATION = "R930" &SEC = "1" #&CDS_SEC = "1";
"A":   PN = "1"  !CDS_PN = "1";
"B":   PN = "2"  !CDS_PN = "2";
BODY = "Q_RES","I373": #LOCATION = "R932" !CDS_LOCATION = "R932" &SEC = "1" #&CDS_SEC = "1";
"A":   PN = "1"  !CDS_PN = "1";
"B":   PN = "2"  !CDS_PN = "2";
BODY = "Q_RES","I374": #LOCATION = "R931" !CDS_LOCATION = "R931" &SEC = "1" #&CDS_SEC = "1";
"A":   PN = "1"  !CDS_PN = "1";
"B":   PN = "2"  !CDS_PN = "2";
BODY = "Q_RES","I387": #LOCATION = "R517" !CDS_LOCATION = "R517" &SEC = "1" #&CDS_SEC = "1";
"A":   PN = "1"  !CDS_PN = "1";
"B":   PN = "2"  !CDS_PN = "2";
BODY = "Q_RES","I388": #LOCATION = "R522" !CDS_LOCATION = "R522" &SEC = "1" #&CDS_SEC = "1";
"A":   PN = "1"  !CDS_PN = "1";
"B":   PN = "2"  !CDS_PN = "2";
BODY = "Q_RES","I390": #LOCATION = "R513" !CDS_LOCATION = "R513" &SEC = "1" #&CDS_SEC = "1";
"A":   PN = "1"  !CDS_PN = "1";
"B":   PN = "2"  !CDS_PN = "2";
BODY = "Q_RES","I391": #LOCATION = "R515" !CDS_LOCATION = "R515" &SEC = "1" #&CDS_SEC = "1";
"A":   PN = "1"  !CDS_PN = "1";
"B":   PN = "2"  !CDS_PN = "2";
BODY = "Q_RES","I396": #LOCATION = "R520" !CDS_LOCATION = "R520" &SEC = "1" #&CDS_SEC = "1";
"A":   PN = "1"  !CDS_PN = "1";
"B":   PN = "2"  !CDS_PN = "2";
BODY = "Q_RES","I398": #LOCATION = "R535" !CDS_LOCATION = "R535" &SEC = "1" #&CDS_SEC = "1";
"A":   PN = "1"  !CDS_PN = "1";
"B":   PN = "2"  !CDS_PN = "2";
BODY = "Q_RES","I400": #LOCATION = "R512" !CDS_LOCATION = "R512" &SEC = "1" #&CDS_SEC = "1";
"A":   PN = "1"  !CDS_PN = "1";
"B":   PN = "2"  !CDS_PN = "2";
BODY = "Q_RES","I401": #LOCATION = "R514" !CDS_LOCATION = "R514" &SEC = "1" #&CDS_SEC = "1";
"A":   PN = "1"  !CDS_PN = "1";
"B":   PN = "2"  !CDS_PN = "2";
BODY = "Q_RES","I402": #LOCATION = "R516" !CDS_LOCATION = "R516" &SEC = "1" #&CDS_SEC = "1";
"A":   PN = "1"  !CDS_PN = "1";
"B":   PN = "2"  !CDS_PN = "2";
BODY = "Q_RES","I403": #LOCATION = "R518" !CDS_LOCATION = "R518" &SEC = "1" #&CDS_SEC = "1";
"A":   PN = "1"  !CDS_PN = "1";
"B":   PN = "2"  !CDS_PN = "2";
BODY = "Q_RES","I404": #LOCATION = "R519" !CDS_LOCATION = "R519" &SEC = "1" #&CDS_SEC = "1";
"A":   PN = "1"  !CDS_PN = "1";
"B":   PN = "2"  !CDS_PN = "2";
BODY = "Q_RES","I405": #LOCATION = "R521" !CDS_LOCATION = "R521" &SEC = "1" #&CDS_SEC = "1";
"A":   PN = "1"  !CDS_PN = "1";
"B":   PN = "2"  !CDS_PN = "2";
BODY = "Q_RES","I406": #LOCATION = "R531" !CDS_LOCATION = "R531" &SEC = "1" #&CDS_SEC = "1";
"A":   PN = "1"  !CDS_PN = "1";
"B":   PN = "2"  !CDS_PN = "2";
BODY = "Q_RES","I407": #LOCATION = "R532" !CDS_LOCATION = "R532" &SEC = "1" #&CDS_SEC = "1";
"A":   PN = "1"  !CDS_PN = "1";
"B":   PN = "2"  !CDS_PN = "2";
BODY = "Q_RES","I408": #LOCATION = "R533" !CDS_LOCATION = "R533" &SEC = "1" #&CDS_SEC = "1";
"A":   PN = "1"  !CDS_PN = "1";
"B":   PN = "2"  !CDS_PN = "2";
BODY = "Q_RES","I409": #LOCATION = "R534" !CDS_LOCATION = "R534" &SEC = "1" #&CDS_SEC = "1";
"A":   PN = "1"  !CDS_PN = "1";
"B":   PN = "2"  !CDS_PN = "2";
BODY = "Q_RES","I410": #LOCATION = "R537" !CDS_LOCATION = "R537" &SEC = "1" #&CDS_SEC = "1";
"A":   PN = "1"  !CDS_PN = "1";
"B":   PN = "2"  !CDS_PN = "2";
BODY = "Q_RES","I411": #LOCATION = "R538" !CDS_LOCATION = "R538" &SEC = "1" #&CDS_SEC = "1";
"A":   PN = "1"  !CDS_PN = "1";
"B":   PN = "2"  !CDS_PN = "2";
BODY = "Q_RES","I412": #LOCATION = "R539" !CDS_LOCATION = "R539" &SEC = "1" #&CDS_SEC = "1";
"A":   PN = "1"  !CDS_PN = "1";
"B":   PN = "2"  !CDS_PN = "2";
BODY = "Q_RES","I413": #LOCATION = "R540" !CDS_LOCATION = "R540" &SEC = "1" #&CDS_SEC = "1";
"A":   PN = "1"  !CDS_PN = "1";
"B":   PN = "2"  !CDS_PN = "2";
BODY = "Q_RES","I415": #LOCATION = "R488" !CDS_LOCATION = "R488" &SEC = "1" #&CDS_SEC = "1";
"A":   PN = "1"  !CDS_PN = "1";
"B":   PN = "2"  !CDS_PN = "2";
BODY = "Q_RES","I417": #LOCATION = "R497" !CDS_LOCATION = "R497" &SEC = "1" #&CDS_SEC = "1";
"A":   PN = "1"  !CDS_PN = "1";
"B":   PN = "2"  !CDS_PN = "2";
BODY = "SCONN8_G802M0083150RD3HR","I418": #LOCATION = "J7" !CDS_LOCATION = "J7" #SEC = "1" !CDS_SEC = "1";
"1":   PN = "1"  !CDS_PN = "1";
"2":   PN = "2"  !CDS_PN = "2";
"3":   PN = "3"  !CDS_PN = "3";
"4":   PN = "4"  !CDS_PN = "4";
"5":   PN = "5"  !CDS_PN = "5";
"6":   PN = "6"  !CDS_PN = "6";
"7":   PN = "7"  !CDS_PN = "7";
"8":   PN = "8"  !CDS_PN = "8";
BODY = "SCONN8_G802M0083150RD3HR","I419": #LOCATION = "J49" !CDS_LOCATION = "J49" #SEC = "1" !CDS_SEC = "1";
"1":   PN = "1"  !CDS_PN = "1";
"2":   PN = "2"  !CDS_PN = "2";
"3":   PN = "3"  !CDS_PN = "3";
"4":   PN = "4"  !CDS_PN = "4";
"5":   PN = "5"  !CDS_PN = "5";
"6":   PN = "6"  !CDS_PN = "6";
"7":   PN = "7"  !CDS_PN = "7";
"8":   PN = "8"  !CDS_PN = "8";
BODY = "Q_RES","I421": #LOCATION = "R536" !CDS_LOCATION = "R536" &SEC = "1" #&CDS_SEC = "1";
"A":   PN = "1"  !CDS_PN = "1";
"B":   PN = "2"  !CDS_PN = "2";
DRAWING = "@t6g_mb_lib.t6g(sch_1):page55";
BODY = "Q_CAP","I3": #LOCATION = "C236" !CDS_LOCATION = "C236" &SEC = "1" #&CDS_SEC = "1";
"A":   PN = "1"  !CDS_PN = "1";
"B":   PN = "2"  !CDS_PN = "2";
BODY = "Q_CAP","I5": #LOCATION = "C238" !CDS_LOCATION = "C238" &SEC = "1" #&CDS_SEC = "1";
"A":   PN = "1"  !CDS_PN = "1";
"B":   PN = "2"  !CDS_PN = "2";
BODY = "Q_CRYSTAL","I7": #LOCATION = "Y5" !CDS_LOCATION = "Y5" &SEC = "1" #&CDS_SEC = "1";
"1":   PN = "1"  !CDS_PN = "1";
"2":   PN = "2"  !CDS_PN = "2";
BODY = "Q_CAP","I9": #LOCATION = "C239" !CDS_LOCATION = "C239" &SEC = "1" #&CDS_SEC = "1";
"A":   PN = "1"  !CDS_PN = "1";
"B":   PN = "2"  !CDS_PN = "2";
BODY = "Q_RES","I10": #LOCATION = "R571" !CDS_LOCATION = "R571" &SEC = "1" #&CDS_SEC = "1";
"A":   PN = "1"  !CDS_PN = "1";
"B":   PN = "2"  !CDS_PN = "2";
BODY = "Q_XTAL_4P_13BI_24GND","I12": #LOCATION = "Y4" !CDS_LOCATION = "Y4" &SEC = "1" #&CDS_SEC = "1";
"G1":   PN = "2"  !CDS_PN = "2";
"G2":   PN = "4"  !CDS_PN = "4";
"X1":   PN = "1"  !CDS_PN = "1";
"X2":   PN = "3"  !CDS_PN = "3";
BODY = "Q_CAP","I15": #LOCATION = "C237" !CDS_LOCATION = "C237" &SEC = "1" #&CDS_SEC = "1";
"A":   PN = "1"  !CDS_PN = "1";
"B":   PN = "2"  !CDS_PN = "2";
BODY = "Q_RES","I24": #LOCATION = "R574" !CDS_LOCATION = "R574" &SEC = "1" #&CDS_SEC = "1";
"A":   PN = "1"  !CDS_PN = "1";
"B":   PN = "2"  !CDS_PN = "2";
BODY = "Q_RES","I26": #LOCATION = "R573" !CDS_LOCATION = "R573" &SEC = "1" #&CDS_SEC = "1";
"A":   PN = "1"  !CDS_PN = "1";
"B":   PN = "2"  !CDS_PN = "2";
BODY = "GENOA_SP5","I182": #LOCATION = "U26" !CDS_LOCATION = "U26" &SEC = "21" #&CDS_SEC = "21";
"AGPIO3||SPD_HOST_CTRL_L":   PN = "DE36"  !CDS_PN = "DE36";
"AGPIO4||SATA_ACT_L":   PN = "DF36"  !CDS_PN = "DF36";
"AGPIO5||DEVSLP0||SATA_ZP0_L":   PN = "DF40"  !CDS_PN = "DF40";
"AGPIO6||DEVSLP1||SATA_ZP1_L":   PN = "DE40"  !CDS_PN = "DE40";
"AGPIO7":   PN = "DH4"  !CDS_PN = "DH4";
"AGPIO21":   PN = "DF33"  !CDS_PN = "DF33";
"AGPIO22":   PN = "DE32"  !CDS_PN = "DE32";
"AGPIO87":   PN = "DG11"  !CDS_PN = "DG11";
"AGPIO88":   PN = "DJ29"  !CDS_PN = "DJ29";
"AGPIO104":   PN = "DH30"  !CDS_PN = "DH30";
"AGPIO105":   PN = "DE30"  !CDS_PN = "DE30";
"AGPIO106":   PN = "DF31"  !CDS_PN = "DF31";
"AGPIO107":   PN = "DG31"  !CDS_PN = "DG31";
"AGPIO109":   PN = "DG32"  !CDS_PN = "DG32";
"AGPIO115||CLK_REQ11_L":   PN = "DH16"  !CDS_PN = "DH16";
"AGPIO116||CLK_REQ12_L":   PN = "DH15"  !CDS_PN = "DH15";
"AGPIO256||SGPIO0_CLK":   PN = "A14"  !CDS_PN = "A14";
"AGPIO257||SGPIO1_CLK||CLK_REQ01_L":   PN = "C14"  !CDS_PN = "C14";
"AGPIO258||SGPIO2_CLK||CLK_REQ02_L":   PN = "A13"  !CDS_PN = "A13";
"AGPIO259||SGPIO3_CLK":   PN = "B16"  !CDS_PN = "B16";
"FORCE_SELFREFRESH":   PN = "B63"  !CDS_PN = "B63";
"GENINT_L||PM_INTR_L||UBM_CPRSNT_CHANGE_DET_L||AGPIO89":   PN = "DJ35"  !CDS_PN = "DJ35";
"GPP_CLK01N":   PN = "A7"  !CDS_PN = "A7";
"GPP_CLK01P":   PN = "A8"  !CDS_PN = "A8";
"GPP_CLK02N":   PN = "C6"  !CDS_PN = "C6";
"GPP_CLK02P":   PN = "B6"  !CDS_PN = "B6";
"GPP_CLK03N":   PN = "A11"  !CDS_PN = "A11";
"GPP_CLK03P":   PN = "A10"  !CDS_PN = "A10";
"GPP_CLK04N":   PN = "C12"  !CDS_PN = "C12";
"GPP_CLK04P":   PN = "B12"  !CDS_PN = "B12";
"GPP_CLK05N":   PN = "C9"  !CDS_PN = "C9";
"GPP_CLK05P":   PN = "B9"  !CDS_PN = "B9";
"GPP_CLK11N":   PN = "DJ42"  !CDS_PN = "DJ42";
"GPP_CLK11P":   PN = "DJ41"  !CDS_PN = "DJ41";
"GPP_CLK12N":   PN = "DJ44"  !CDS_PN = "DJ44";
"GPP_CLK12P":   PN = "DJ45"  !CDS_PN = "DJ45";
"GPP_CLK13N":   PN = "DJ54"  !CDS_PN = "DJ54";
"GPP_CLK13P":   PN = "DJ53"  !CDS_PN = "DJ53";
"GPP_CLK14N":   PN = "DJ47"  !CDS_PN = "DJ47";
"GPP_CLK14P":   PN = "DJ48"  !CDS_PN = "DJ48";
"GPP_CLK15N":   PN = "DJ50"  !CDS_PN = "DJ50";
"GPP_CLK15P":   PN = "DJ51"  !CDS_PN = "DJ51";
"I2C4_SCL||HP_SCL||UBM_SCL||AGPIO13":   PN = "DG12"  !CDS_PN = "DG12";
"I2C4_SDA||HP_SDA||UBM_SDA||AGPIO14":   PN = "DH12"  !CDS_PN = "DH12";
"I2C5_SCL||BMC_SCL||SMBUS1_SCL||AGPIO19":   PN = "DJ21"  !CDS_PN = "DJ21";
"I2C5_SDA||BMC_SDA||SMBUS1_SDA||AGPIO20":   PN = "DJ20"  !CDS_PN = "DJ20";
"I3C0_SCL||I2C0_SCL||SPD0_SCL||SMBUS0_SCL||AGPIO145":   PN = "A71"  !CDS_PN = "A71";
"I3C0_SDA||I2C0_SDA||SPD0_SDA||SMBUS0_SDA||AGPIO146":   PN = "B71"  !CDS_PN = "B71";
"I3C1_SCL||I2C1_SCL||SPD1_SCL||AGPIO147":   PN = "C7"  !CDS_PN = "C7";
"I3C1_SDA||I2C1_SDA||SPD1_SDA||AGPIO148":   PN = "A5"  !CDS_PN = "A5";
"I3C2_SCL||I2C2_SCL||SPD2_SCL||AGPIO149":   PN = "C72"  !CDS_PN = "C72";
"I3C2_SDA||I2C2_SDA||SPD2_SDA||AGPIO150":   PN = "B72"  !CDS_PN = "B72";
"I3C3_SCL||I2C3_SCL||SPD3_SCL||AGPIO151":   PN = "A4"  !CDS_PN = "A4";
"I3C3_SDA||I2C3_SDA||SPD3_SDA||AGPIO152":   PN = "B4"  !CDS_PN = "B4";
"NMI_SYNC_FLOOD_L":   PN = "DJ31"  !CDS_PN = "DJ31";
"NV_SAVE_L":   PN = "B64"  !CDS_PN = "B64";
"PCIE_RST0_L||AGPIO266":   PN = "D18"  !CDS_PN = "D18";
"PCIE_RST1_L||AGPIO26":   PN = "DG36"  !CDS_PN = "DG36";
"PWR_BTN_L||AGPIO0":   PN = "DH7"  !CDS_PN = "DH7";
"PWR_GOOD":   PN = "DJ8"  !CDS_PN = "DJ8";
"PWRGD_OUT||AGPIO12":   PN = "DH36"  !CDS_PN = "DH36";
"PWROK||SVI_RST_L":   PN = "D69"  !CDS_PN = "D69";
"REFCLK100SSC_N||GPP_CLK10N":   PN = "A20"  !CDS_PN = "A20";
"REFCLK100SSC_P||GPP_CLK10P":   PN = "A19"  !CDS_PN = "A19";
"RESET_L":   PN = "B67"  !CDS_PN = "B67";
"RSMRST_L":   PN = "DG10"  !CDS_PN = "DG10";
"RTCCLK":   PN = "DH9"  !CDS_PN = "DH9";
"SEC_SCL||AGPIO262":   PN = "B14"  !CDS_PN = "B14";
"SEC_SDA||AGPIO263":   PN = "D14"  !CDS_PN = "D14";
"SGPIO_DATAOUT||AGPIO260":   PN = "D15"  !CDS_PN = "D15";
"SGPIO_LOAD||AGPIO261":   PN = "B15"  !CDS_PN = "B15";
"SLP_S3_L":   PN = "DJ5"  !CDS_PN = "DJ5";
"SLP_S5_L":   PN = "DG4"  !CDS_PN = "DG4";
"SMERR_L||AGPIO24":   PN = "DJ11"  !CDS_PN = "DJ11";
"SYS_RESET_L||AGPIO1":   PN = "DH6"  !CDS_PN = "DH6";
"WAKE_L||AGPIO2":   PN = "DJ10"  !CDS_PN = "DJ10";
"X32K_X1":   PN = "DJ14"  !CDS_PN = "DJ14";
"X32K_X2":   PN = "DJ13"  !CDS_PN = "DJ13";
"X48M_X1":   PN = "DJ17"  !CDS_PN = "DJ17";
"X48M_X2":   PN = "DJ16"  !CDS_PN = "DJ16";
BODY = "Q_RES","I236": #LOCATION = "R570" !CDS_LOCATION = "R570" &SEC = "1" #&CDS_SEC = "1";
"A":   PN = "1"  !CDS_PN = "1";
"B":   PN = "2"  !CDS_PN = "2";
BODY = "Q_RES","I292": #LOCATION = "R1424" !CDS_LOCATION = "R1424" &SEC = "1" #&CDS_SEC = "1";
"A":   PN = "1"  !CDS_PN = "1";
"B":   PN = "2"  !CDS_PN = "2";
BODY = "Q_RES","I296": #LOCATION = "R575" !CDS_LOCATION = "R575" &SEC = "1" #&CDS_SEC = "1";
"A":   PN = "1"  !CDS_PN = "1";
"B":   PN = "2"  !CDS_PN = "2";
BODY = "Q_RES","I297": #LOCATION = "R191" !CDS_LOCATION = "R191" &SEC = "1" #&CDS_SEC = "1";
"A":   PN = "1"  !CDS_PN = "1";
"B":   PN = "2"  !CDS_PN = "2";
BODY = "Q_RES","I298": #LOCATION = "R192" !CDS_LOCATION = "R192" &SEC = "1" #&CDS_SEC = "1";
"A":   PN = "1"  !CDS_PN = "1";
"B":   PN = "2"  !CDS_PN = "2";
BODY = "Q_RES","I302": #LOCATION = "R3352" !CDS_LOCATION = "R3352" &SEC = "1" #&CDS_SEC = "1";
"A":   PN = "1"  !CDS_PN = "1";
"B":   PN = "2"  !CDS_PN = "2";
BODY = "Q_RES","I303": #LOCATION = "R3353" !CDS_LOCATION = "R3353" &SEC = "1" #&CDS_SEC = "1";
"A":   PN = "1"  !CDS_PN = "1";
"B":   PN = "2"  !CDS_PN = "2";
BODY = "Q_RES","I306": #LOCATION = "R3355" !CDS_LOCATION = "R3355" &SEC = "1" #&CDS_SEC = "1";
"A":   PN = "1"  !CDS_PN = "1";
"B":   PN = "2"  !CDS_PN = "2";
BODY = "Q_RES","I307": #LOCATION = "R3354" !CDS_LOCATION = "R3354" &SEC = "1" #&CDS_SEC = "1";
"A":   PN = "1"  !CDS_PN = "1";
"B":   PN = "2"  !CDS_PN = "2";
BODY = "Q_RES","I308": #LOCATION = "R3194" !CDS_LOCATION = "R3194" &SEC = "1" #&CDS_SEC = "1";
"A":   PN = "1"  !CDS_PN = "1";
"B":   PN = "2"  !CDS_PN = "2";
BODY = "Q_RES","I309": #LOCATION = "R3195" !CDS_LOCATION = "R3195" &SEC = "1" #&CDS_SEC = "1";
"A":   PN = "1"  !CDS_PN = "1";
"B":   PN = "2"  !CDS_PN = "2";
BODY = "Q_RES","I312": #LOCATION = "R3196" !CDS_LOCATION = "R3196" &SEC = "1" #&CDS_SEC = "1";
"A":   PN = "1"  !CDS_PN = "1";
"B":   PN = "2"  !CDS_PN = "2";
BODY = "Q_RES","I313": #LOCATION = "R3197" !CDS_LOCATION = "R3197" &SEC = "1" #&CDS_SEC = "1";
"A":   PN = "1"  !CDS_PN = "1";
"B":   PN = "2"  !CDS_PN = "2";
BODY = "Q_RES","I316": #LOCATION = "R3198" !CDS_LOCATION = "R3198" &SEC = "1" #&CDS_SEC = "1";
"A":   PN = "1"  !CDS_PN = "1";
"B":   PN = "2"  !CDS_PN = "2";
BODY = "Q_RES","I317": #LOCATION = "R3199" !CDS_LOCATION = "R3199" &SEC = "1" #&CDS_SEC = "1";
"A":   PN = "1"  !CDS_PN = "1";
"B":   PN = "2"  !CDS_PN = "2";
BODY = "Q_RES","I320": #LOCATION = "R3200" !CDS_LOCATION = "R3200" &SEC = "1" #&CDS_SEC = "1";
"A":   PN = "1"  !CDS_PN = "1";
"B":   PN = "2"  !CDS_PN = "2";
BODY = "Q_RES","I321": #LOCATION = "R3201" !CDS_LOCATION = "R3201" &SEC = "1" #&CDS_SEC = "1";
"A":   PN = "1"  !CDS_PN = "1";
"B":   PN = "2"  !CDS_PN = "2";
BODY = "Q_RES","I326": #LOCATION = "R4306" !CDS_LOCATION = "R4306" &SEC = "1" #&CDS_SEC = "1";
"A":   PN = "1"  !CDS_PN = "1";
"B":   PN = "2"  !CDS_PN = "2";
BODY = "Q_RES","I327": #LOCATION = "R4305" !CDS_LOCATION = "R4305" &SEC = "1" #&CDS_SEC = "1";
"A":   PN = "1"  !CDS_PN = "1";
"B":   PN = "2"  !CDS_PN = "2";
BODY = "Q_RES","I330": #LOCATION = "R5032" !CDS_LOCATION = "R5032" &SEC = "1" #&CDS_SEC = "1";
"A":   PN = "1"  !CDS_PN = "1";
"B":   PN = "2"  !CDS_PN = "2";
BODY = "Q_RES","I331": #LOCATION = "R5031" !CDS_LOCATION = "R5031" &SEC = "1" #&CDS_SEC = "1";
"A":   PN = "1"  !CDS_PN = "1";
"B":   PN = "2"  !CDS_PN = "2";
BODY = "Q_RES","I334": #LOCATION = "R5030" !CDS_LOCATION = "R5030" &SEC = "1" #&CDS_SEC = "1";
"A":   PN = "1"  !CDS_PN = "1";
"B":   PN = "2"  !CDS_PN = "2";
BODY = "Q_RES","I335": #LOCATION = "R491" !CDS_LOCATION = "R491" &SEC = "1" #&CDS_SEC = "1";
"A":   PN = "1"  !CDS_PN = "1";
"B":   PN = "2"  !CDS_PN = "2";
BODY = "Q_RES","I336": #LOCATION = "R544" !CDS_LOCATION = "R544" &SEC = "1" #&CDS_SEC = "1";
"A":   PN = "1"  !CDS_PN = "1";
"B":   PN = "2"  !CDS_PN = "2";
BODY = "Q_RES","I337": #LOCATION = "R545" !CDS_LOCATION = "R545" &SEC = "1" #&CDS_SEC = "1";
"A":   PN = "1"  !CDS_PN = "1";
"B":   PN = "2"  !CDS_PN = "2";
BODY = "Q_RES","I338": #LOCATION = "R546" !CDS_LOCATION = "R546" &SEC = "1" #&CDS_SEC = "1";
"A":   PN = "1"  !CDS_PN = "1";
"B":   PN = "2"  !CDS_PN = "2";
BODY = "Q_RES","I339": #LOCATION = "R456" !CDS_LOCATION = "R456" &SEC = "1" #&CDS_SEC = "1";
"A":   PN = "1"  !CDS_PN = "1";
"B":   PN = "2"  !CDS_PN = "2";
BODY = "Q_RES","I341": #LOCATION = "R584" !CDS_LOCATION = "R584" &SEC = "1" #&CDS_SEC = "1";
"A":   PN = "1"  !CDS_PN = "1";
"B":   PN = "2"  !CDS_PN = "2";
BODY = "Q_RES","I342": #LOCATION = "R583" !CDS_LOCATION = "R583" &SEC = "1" #&CDS_SEC = "1";
"A":   PN = "1"  !CDS_PN = "1";
"B":   PN = "2"  !CDS_PN = "2";
BODY = "Q_RES","I352": #LOCATION = "R548" !CDS_LOCATION = "R548" &SEC = "1" #&CDS_SEC = "1";
"A":   PN = "1"  !CDS_PN = "1";
"B":   PN = "2"  !CDS_PN = "2";
BODY = "Q_RES","I353": #LOCATION = "R549" !CDS_LOCATION = "R549" &SEC = "1" #&CDS_SEC = "1";
"A":   PN = "1"  !CDS_PN = "1";
"B":   PN = "2"  !CDS_PN = "2";
BODY = "Q_RES","I355": #LOCATION = "R562" !CDS_LOCATION = "R562" &SEC = "1" #&CDS_SEC = "1";
"A":   PN = "1"  !CDS_PN = "1";
"B":   PN = "2"  !CDS_PN = "2";
BODY = "Q_RES","I356": #LOCATION = "R559" !CDS_LOCATION = "R559" &SEC = "1" #&CDS_SEC = "1";
"A":   PN = "1"  !CDS_PN = "1";
"B":   PN = "2"  !CDS_PN = "2";
BODY = "Q_RES","I357": #LOCATION = "R556" !CDS_LOCATION = "R556" &SEC = "1" #&CDS_SEC = "1";
"A":   PN = "1"  !CDS_PN = "1";
"B":   PN = "2"  !CDS_PN = "2";
BODY = "Q_RES","I359": #LOCATION = "R553" !CDS_LOCATION = "R553" &SEC = "1" #&CDS_SEC = "1";
"A":   PN = "1"  !CDS_PN = "1";
"B":   PN = "2"  !CDS_PN = "2";
BODY = "Q_RES","I360": #LOCATION = "R551" !CDS_LOCATION = "R551" &SEC = "1" #&CDS_SEC = "1";
"A":   PN = "1"  !CDS_PN = "1";
"B":   PN = "2"  !CDS_PN = "2";
BODY = "Q_RES","I362": #LOCATION = "R547" !CDS_LOCATION = "R547" &SEC = "1" #&CDS_SEC = "1";
"A":   PN = "1"  !CDS_PN = "1";
"B":   PN = "2"  !CDS_PN = "2";
BODY = "Q_RES","I363": #LOCATION = "R550" !CDS_LOCATION = "R550" &SEC = "1" #&CDS_SEC = "1";
"A":   PN = "1"  !CDS_PN = "1";
"B":   PN = "2"  !CDS_PN = "2";
BODY = "Q_RES","I364": #LOCATION = "R557" !CDS_LOCATION = "R557" &SEC = "1" #&CDS_SEC = "1";
"A":   PN = "1"  !CDS_PN = "1";
"B":   PN = "2"  !CDS_PN = "2";
BODY = "Q_RES","I365": #LOCATION = "R541" !CDS_LOCATION = "R541" &SEC = "1" #&CDS_SEC = "1";
"A":   PN = "1"  !CDS_PN = "1";
"B":   PN = "2"  !CDS_PN = "2";
BODY = "Q_RES","I366": #LOCATION = "R542" !CDS_LOCATION = "R542" &SEC = "1" #&CDS_SEC = "1";
"A":   PN = "1"  !CDS_PN = "1";
"B":   PN = "2"  !CDS_PN = "2";
BODY = "Q_RES","I367": #LOCATION = "R543" !CDS_LOCATION = "R543" &SEC = "1" #&CDS_SEC = "1";
"A":   PN = "1"  !CDS_PN = "1";
"B":   PN = "2"  !CDS_PN = "2";
BODY = "Q_RES","I368": #LOCATION = "R563" !CDS_LOCATION = "R563" &SEC = "1" #&CDS_SEC = "1";
"A":   PN = "1"  !CDS_PN = "1";
"B":   PN = "2"  !CDS_PN = "2";
BODY = "Q_RES","I386": #LOCATION = "R5103" !CDS_LOCATION = "R5103" &SEC = "1" #&CDS_SEC = "1";
"A":   PN = "1"  !CDS_PN = "1";
"B":   PN = "2"  !CDS_PN = "2";
BODY = "Q_CAP","I388": #LOCATION = "C5024" !CDS_LOCATION = "C5024" &SEC = "1" #&CDS_SEC = "1";
"A":   PN = "1"  !CDS_PN = "1";
"B":   PN = "2"  !CDS_PN = "2";
BODY = "Q_RES","I389": #LOCATION = "R572" !CDS_LOCATION = "R572" #SEC = "1" !CDS_SEC = "1";
"A":   PN = "1"  !CDS_PN = "1";
"B":   PN = "2"  !CDS_PN = "2";
BODY = "Q_RES","I390": #LOCATION = "R558" !CDS_LOCATION = "R558" #SEC = "1" !CDS_SEC = "1";
"A":   PN = "1"  !CDS_PN = "1";
"B":   PN = "2"  !CDS_PN = "2";
BODY = "Q_RES","I392": #LOCATION = "R6503" !CDS_LOCATION = "R6503" &SEC = "1" #&CDS_SEC = "1";
"A":   PN = "1"  !CDS_PN = "1";
"B":   PN = "2"  !CDS_PN = "2";
BODY = "Q_RES","I394": #LOCATION = "R8351" !CDS_LOCATION = "R8351" &SEC = "1" #&CDS_SEC = "1";
"A":   PN = "1"  !CDS_PN = "1";
"B":   PN = "2"  !CDS_PN = "2";
BODY = "Q_RES","I397": #LOCATION = "R8350" !CDS_LOCATION = "R8350" &SEC = "1" #&CDS_SEC = "1";
"A":   PN = "1"  !CDS_PN = "1";
"B":   PN = "2"  !CDS_PN = "2";
DRAWING = "@t6g_mb_lib.t6g(sch_1):page56";
BODY = "GENOA_SP5","I8": #LOCATION = "U26" !CDS_LOCATION = "U26" &SEC = "22" #&CDS_SEC = "22";
"AGPIO76||SPI_TPM_CS_L":   PN = "DJ25"  !CDS_PN = "DJ25";
"ESPI0_ALERT_L||AGPIO108":   PN = "DJ22"  !CDS_PN = "DJ22";
"ESPI0_DAT0||SPI0_DAT0||AGPIO120":   PN = "DF28"  !CDS_PN = "DF28";
"ESPI0_DAT1||SPI0_DAT1||AGPIO121":   PN = "DG22"  !CDS_PN = "DG22";
"ESPI0_DAT2||SPI0_DAT2||AGPIO122":   PN = "DJ28"  !CDS_PN = "DJ28";
"ESPI0_DAT3||SPI0_DAT3||AGPIO123":   PN = "DG29"  !CDS_PN = "DG29";
"ESPI1_ALERT_L||AGPIO110":   PN = "DF24"  !CDS_PN = "DF24";
"ESPI1_DAT0||SPI1_DAT0||AGPIO131":   PN = "DH24"  !CDS_PN = "DH24";
"ESPI1_DAT1||SPI1_DAT1||AGPIO132":   PN = "DE24"  !CDS_PN = "DE24";
"ESPI1_DAT2||SPI1_DAT2||AGPIO133":   PN = "DF25"  !CDS_PN = "DF25";
"ESPI1_DAT3||SPI1_DAT3||AGPIO134":   PN = "DG25"  !CDS_PN = "DG25";
"ESPI_CLK0||SPI_CLK0||AGPIO117":   PN = "DJ27"  !CDS_PN = "DJ27";
"ESPI_CLK1||SPI_CLK1||AGPIO75":   PN = "DG23"  !CDS_PN = "DG23";
"ESPI_CLK2||AGPIO74":   PN = "DF27"  !CDS_PN = "DF27";
"ESPI_CS0_L||AGPIO124":   PN = "DG28"  !CDS_PN = "DG28";
"ESPI_CS1_L||AGPIO125":   PN = "DJ23"  !CDS_PN = "DJ23";
"ESPI_RSTIN_L||KBRST_L||AGPIO129":   PN = "DJ26"  !CDS_PN = "DJ26";
"ESPI_RSTOUT_L||AGPIO23":   PN = "DE27"  !CDS_PN = "DE27";
"SPI_CS0_L||AGPIO118":   PN = "DF30"  !CDS_PN = "DF30";
"SPI_CS1_L||AGPIO119":   PN = "DG26"  !CDS_PN = "DG26";
"SPI_CS2_L||AGPIO126":   PN = "DH27"  !CDS_PN = "DH27";
"USB00_DN":   PN = "A25"  !CDS_PN = "A25";
"USB00_DP":   PN = "A26"  !CDS_PN = "A26";
"USB00_OC_L||AGPIO264":   PN = "E23"  !CDS_PN = "E23";
"USB00_RXN":   PN = "E26"  !CDS_PN = "E26";
"USB00_RXP":   PN = "E27"  !CDS_PN = "E27";
"USB00_TXN":   PN = "C26"  !CDS_PN = "C26";
"USB00_TXP":   PN = "C25"  !CDS_PN = "C25";
"USB01_DN":   PN = "A29"  !CDS_PN = "A29";
"USB01_DP":   PN = "A28"  !CDS_PN = "A28";
"USB01_OC_L||AGPIO265":   PN = "E24"  !CDS_PN = "E24";
"USB01_RXN":   PN = "C28"  !CDS_PN = "C28";
"USB01_RXP":   PN = "C29"  !CDS_PN = "C29";
"USB01_TXN":   PN = "E29"  !CDS_PN = "E29";
"USB01_TXP":   PN = "E30"  !CDS_PN = "E30";
"USB10_DN":   PN = "DH67"  !CDS_PN = "DH67";
"USB10_DP":   PN = "DJ67"  !CDS_PN = "DJ67";
"USB10_OC_L||AGPIO16":   PN = "DG40"  !CDS_PN = "DG40";
"USB10_RXN":   PN = "DH65"  !CDS_PN = "DH65";
"USB10_RXP":   PN = "DJ65"  !CDS_PN = "DJ65";
"USB10_TXN":   PN = "DJ69"  !CDS_PN = "DJ69";
"USB10_TXP":   PN = "DH69"  !CDS_PN = "DH69";
"USB11_DN":   PN = "DJ60"  !CDS_PN = "DJ60";
"USB11_DP":   PN = "DH60"  !CDS_PN = "DH60";
"USB11_OC_L||AGPIO17":   PN = "DH40"  !CDS_PN = "DH40";
"USB11_RXN":   PN = "DH62"  !CDS_PN = "DH62";
"USB11_RXP":   PN = "DJ62"  !CDS_PN = "DJ62";
"USB11_TXN":   PN = "DH58"  !CDS_PN = "DH58";
"USB11_TXP":   PN = "DG58"  !CDS_PN = "DG58";
BODY = "Q_RES","I11": #LOCATION = "R738" !CDS_LOCATION = "R738" &SEC = "1" #&CDS_SEC = "1";
"A":   PN = "1"  !CDS_PN = "1";
"B":   PN = "2"  !CDS_PN = "2";
DRAWING = "@t6g_mb_lib.t6g(sch_1):page57";
BODY = "GENOA_SP5","I29": #LOCATION = "U26" !CDS_LOCATION = "U26" &SEC = "24" #&CDS_SEC = "24";
"VDDCR_CPU0_AB23":   PN = "AB23"  !CDS_PN = "AB23";
"VDDCR_CPU0_AB24":   PN = "AB24"  !CDS_PN = "AB24";
"VDDCR_CPU0_AB26":   PN = "AB26"  !CDS_PN = "AB26";
"VDDCR_CPU0_AB27":   PN = "AB27"  !CDS_PN = "AB27";
"VDDCR_CPU0_AB29":   PN = "AB29"  !CDS_PN = "AB29";
"VDDCR_CPU0_AB30":   PN = "AB30"  !CDS_PN = "AB30";
"VDDCR_CPU0_AB32":   PN = "AB32"  !CDS_PN = "AB32";
"VDDCR_CPU0_AB33":   PN = "AB33"  !CDS_PN = "AB33";
"VDDCR_CPU0_AB43":   PN = "AB43"  !CDS_PN = "AB43";
"VDDCR_CPU0_AB44":   PN = "AB44"  !CDS_PN = "AB44";
"VDDCR_CPU0_AB46":   PN = "AB46"  !CDS_PN = "AB46";
"VDDCR_CPU0_AB47":   PN = "AB47"  !CDS_PN = "AB47";
"VDDCR_CPU0_AB49":   PN = "AB49"  !CDS_PN = "AB49";
"VDDCR_CPU0_AB50":   PN = "AB50"  !CDS_PN = "AB50";
"VDDCR_CPU0_AB52":   PN = "AB52"  !CDS_PN = "AB52";
"VDDCR_CPU0_AB53":   PN = "AB53"  !CDS_PN = "AB53";
"VDDCR_CPU0_AC35":   PN = "AC35"  !CDS_PN = "AC35";
"VDDCR_CPU0_AC36":   PN = "AC36"  !CDS_PN = "AC36";
"VDDCR_CPU0_AC40":   PN = "AC40"  !CDS_PN = "AC40";
"VDDCR_CPU0_AC41":   PN = "AC41"  !CDS_PN = "AC41";
"VDDCR_CPU0_AF23":   PN = "AF23"  !CDS_PN = "AF23";
"VDDCR_CPU0_AF24":   PN = "AF24"  !CDS_PN = "AF24";
"VDDCR_CPU0_AF26":   PN = "AF26"  !CDS_PN = "AF26";
"VDDCR_CPU0_AF27":   PN = "AF27"  !CDS_PN = "AF27";
"VDDCR_CPU0_AF29":   PN = "AF29"  !CDS_PN = "AF29";
"VDDCR_CPU0_AF30":   PN = "AF30"  !CDS_PN = "AF30";
"VDDCR_CPU0_AF32":   PN = "AF32"  !CDS_PN = "AF32";
"VDDCR_CPU0_AF33":   PN = "AF33"  !CDS_PN = "AF33";
"VDDCR_CPU0_AF43":   PN = "AF43"  !CDS_PN = "AF43";
"VDDCR_CPU0_AF44":   PN = "AF44"  !CDS_PN = "AF44";
"VDDCR_CPU0_AF46":   PN = "AF46"  !CDS_PN = "AF46";
"VDDCR_CPU0_AF47":   PN = "AF47"  !CDS_PN = "AF47";
"VDDCR_CPU0_AF49":   PN = "AF49"  !CDS_PN = "AF49";
"VDDCR_CPU0_AF50":   PN = "AF50"  !CDS_PN = "AF50";
"VDDCR_CPU0_AF52":   PN = "AF52"  !CDS_PN = "AF52";
"VDDCR_CPU0_AF53":   PN = "AF53"  !CDS_PN = "AF53";
"VDDCR_CPU0_AG35":   PN = "AG35"  !CDS_PN = "AG35";
"VDDCR_CPU0_AG36":   PN = "AG36"  !CDS_PN = "AG36";
"VDDCR_CPU0_AG40":   PN = "AG40"  !CDS_PN = "AG40";
"VDDCR_CPU0_AG41":   PN = "AG41"  !CDS_PN = "AG41";
"VDDCR_CPU0_AK23":   PN = "AK23"  !CDS_PN = "AK23";
"VDDCR_CPU0_AK24":   PN = "AK24"  !CDS_PN = "AK24";
"VDDCR_CPU0_AK26":   PN = "AK26"  !CDS_PN = "AK26";
"VDDCR_CPU0_AK27":   PN = "AK27"  !CDS_PN = "AK27";
"VDDCR_CPU0_AK29":   PN = "AK29"  !CDS_PN = "AK29";
"VDDCR_CPU0_AK30":   PN = "AK30"  !CDS_PN = "AK30";
"VDDCR_CPU0_AK32":   PN = "AK32"  !CDS_PN = "AK32";
"VDDCR_CPU0_AK33":   PN = "AK33"  !CDS_PN = "AK33";
"VDDCR_CPU0_AK43":   PN = "AK43"  !CDS_PN = "AK43";
"VDDCR_CPU0_AK44":   PN = "AK44"  !CDS_PN = "AK44";
"VDDCR_CPU0_AK46":   PN = "AK46"  !CDS_PN = "AK46";
"VDDCR_CPU0_AK47":   PN = "AK47"  !CDS_PN = "AK47";
"VDDCR_CPU0_AK49":   PN = "AK49"  !CDS_PN = "AK49";
"VDDCR_CPU0_AK50":   PN = "AK50"  !CDS_PN = "AK50";
"VDDCR_CPU0_AK52":   PN = "AK52"  !CDS_PN = "AK52";
"VDDCR_CPU0_AK53":   PN = "AK53"  !CDS_PN = "AK53";
"VDDCR_CPU0_AL35":   PN = "AL35"  !CDS_PN = "AL35";
"VDDCR_CPU0_AL36":   PN = "AL36"  !CDS_PN = "AL36";
"VDDCR_CPU0_AL40":   PN = "AL40"  !CDS_PN = "AL40";
"VDDCR_CPU0_AL41":   PN = "AL41"  !CDS_PN = "AL41";
"VDDCR_CPU0_AP23":   PN = "AP23"  !CDS_PN = "AP23";
"VDDCR_CPU0_AP24":   PN = "AP24"  !CDS_PN = "AP24";
"VDDCR_CPU0_AP26":   PN = "AP26"  !CDS_PN = "AP26";
"VDDCR_CPU0_AP27":   PN = "AP27"  !CDS_PN = "AP27";
"VDDCR_CPU0_AP29":   PN = "AP29"  !CDS_PN = "AP29";
"VDDCR_CPU0_AP30":   PN = "AP30"  !CDS_PN = "AP30";
"VDDCR_CPU0_AP32":   PN = "AP32"  !CDS_PN = "AP32";
"VDDCR_CPU0_AP33":   PN = "AP33"  !CDS_PN = "AP33";
"VDDCR_CPU0_AP43":   PN = "AP43"  !CDS_PN = "AP43";
"VDDCR_CPU0_AP44":   PN = "AP44"  !CDS_PN = "AP44";
"VDDCR_CPU0_AP46":   PN = "AP46"  !CDS_PN = "AP46";
"VDDCR_CPU0_AP47":   PN = "AP47"  !CDS_PN = "AP47";
"VDDCR_CPU0_AP49":   PN = "AP49"  !CDS_PN = "AP49";
"VDDCR_CPU0_AP50":   PN = "AP50"  !CDS_PN = "AP50";
"VDDCR_CPU0_AP52":   PN = "AP52"  !CDS_PN = "AP52";
"VDDCR_CPU0_AP53":   PN = "AP53"  !CDS_PN = "AP53";
"VDDCR_CPU0_AR23":   PN = "AR23"  !CDS_PN = "AR23";
"VDDCR_CPU0_AR25":   PN = "AR25"  !CDS_PN = "AR25";
"VDDCR_CPU0_AR27":   PN = "AR27"  !CDS_PN = "AR27";
"VDDCR_CPU0_AR29":   PN = "AR29"  !CDS_PN = "AR29";
"VDDCR_CPU0_AR31":   PN = "AR31"  !CDS_PN = "AR31";
"VDDCR_CPU0_AR33":   PN = "AR33"  !CDS_PN = "AR33";
"VDDCR_CPU0_AR35":   PN = "AR35"  !CDS_PN = "AR35";
"VDDCR_CPU0_AR40":   PN = "AR40"  !CDS_PN = "AR40";
"VDDCR_CPU0_AR42":   PN = "AR42"  !CDS_PN = "AR42";
"VDDCR_CPU0_AR44":   PN = "AR44"  !CDS_PN = "AR44";
"VDDCR_CPU0_AR46":   PN = "AR46"  !CDS_PN = "AR46";
"VDDCR_CPU0_AR48":   PN = "AR48"  !CDS_PN = "AR48";
"VDDCR_CPU0_AR50":   PN = "AR50"  !CDS_PN = "AR50";
"VDDCR_CPU0_AT24":   PN = "AT24"  !CDS_PN = "AT24";
"VDDCR_CPU0_AT26":   PN = "AT26"  !CDS_PN = "AT26";
"VDDCR_CPU0_AT28":   PN = "AT28"  !CDS_PN = "AT28";
"VDDCR_CPU0_AT30":   PN = "AT30"  !CDS_PN = "AT30";
"VDDCR_CPU0_AT32":   PN = "AT32"  !CDS_PN = "AT32";
"VDDCR_CPU0_AT34":   PN = "AT34"  !CDS_PN = "AT34";
"VDDCR_CPU0_AT36":   PN = "AT36"  !CDS_PN = "AT36";
"VDDCR_CPU0_AT39":   PN = "AT39"  !CDS_PN = "AT39";
"VDDCR_CPU0_AT41":   PN = "AT41"  !CDS_PN = "AT41";
"VDDCR_CPU0_AT43":   PN = "AT43"  !CDS_PN = "AT43";
"VDDCR_CPU0_AT45":   PN = "AT45"  !CDS_PN = "AT45";
"VDDCR_CPU0_AT47":   PN = "AT47"  !CDS_PN = "AT47";
"VDDCR_CPU0_AT49":   PN = "AT49"  !CDS_PN = "AT49";
"VDDCR_CPU0_AU25":   PN = "AU25"  !CDS_PN = "AU25";
"VDDCR_CPU0_AU29":   PN = "AU29"  !CDS_PN = "AU29";
"VDDCR_CPU0_AU33":   PN = "AU33"  !CDS_PN = "AU33";
"VDDCR_CPU0_AU42":   PN = "AU42"  !CDS_PN = "AU42";
"VDDCR_CPU0_AU44":   PN = "AU44"  !CDS_PN = "AU44";
"VDDCR_CPU0_AU46":   PN = "AU46"  !CDS_PN = "AU46";
"VDDCR_CPU0_AU48":   PN = "AU48"  !CDS_PN = "AU48";
"VDDCR_CPU0_B19":   PN = "B19"  !CDS_PN = "B19";
"VDDCR_CPU0_B20":   PN = "B20"  !CDS_PN = "B20";
"VDDCR_CPU0_B22":   PN = "B22"  !CDS_PN = "B22";
"VDDCR_CPU0_B23":   PN = "B23"  !CDS_PN = "B23";
"VDDCR_CPU0_B25":   PN = "B25"  !CDS_PN = "B25";
"VDDCR_CPU0_B26":   PN = "B26"  !CDS_PN = "B26";
"VDDCR_CPU0_B28":   PN = "B28"  !CDS_PN = "B28";
"VDDCR_CPU0_B29":   PN = "B29"  !CDS_PN = "B29";
"VDDCR_CPU0_B31":   PN = "B31"  !CDS_PN = "B31";
"VDDCR_CPU0_B32":   PN = "B32"  !CDS_PN = "B32";
"VDDCR_CPU0_B34":   PN = "B34"  !CDS_PN = "B34";
"VDDCR_CPU0_B35":   PN = "B35"  !CDS_PN = "B35";
"VDDCR_CPU0_B41":   PN = "B41"  !CDS_PN = "B41";
"VDDCR_CPU0_B42":   PN = "B42"  !CDS_PN = "B42";
"VDDCR_CPU0_B44":   PN = "B44"  !CDS_PN = "B44";
"VDDCR_CPU0_B45":   PN = "B45"  !CDS_PN = "B45";
"VDDCR_CPU0_B47":   PN = "B47"  !CDS_PN = "B47";
"VDDCR_CPU0_B48":   PN = "B48"  !CDS_PN = "B48";
"VDDCR_CPU0_B50":   PN = "B50"  !CDS_PN = "B50";
"VDDCR_CPU0_B51":   PN = "B51"  !CDS_PN = "B51";
"VDDCR_CPU0_B53":   PN = "B53"  !CDS_PN = "B53";
"VDDCR_CPU0_B54":   PN = "B54"  !CDS_PN = "B54";
"VDDCR_CPU0_B56":   PN = "B56"  !CDS_PN = "B56";
"VDDCR_CPU0_B57":   PN = "B57"  !CDS_PN = "B57";
"VDDCR_CPU0_C20":   PN = "C20"  !CDS_PN = "C20";
"VDDCR_CPU0_D55":   PN = "D55"  !CDS_PN = "D55";
"VDDCR_CPU0_D56":   PN = "D56"  !CDS_PN = "D56";
"VDDCR_CPU0_E22":   PN = "E22"  !CDS_PN = "E22";
"VDDCR_CPU0_E25":   PN = "E25"  !CDS_PN = "E25";
"VDDCR_CPU0_E28":   PN = "E28"  !CDS_PN = "E28";
"VDDCR_CPU0_E31":   PN = "E31"  !CDS_PN = "E31";
"VDDCR_CPU0_E34":   PN = "E34"  !CDS_PN = "E34";
"VDDCR_CPU0_E35":   PN = "E35"  !CDS_PN = "E35";
"VDDCR_CPU0_E42":   PN = "E42"  !CDS_PN = "E42";
"VDDCR_CPU0_E45":   PN = "E45"  !CDS_PN = "E45";
"VDDCR_CPU0_E48":   PN = "E48"  !CDS_PN = "E48";
"VDDCR_CPU0_E51":   PN = "E51"  !CDS_PN = "E51";
"VDDCR_CPU0_E54":   PN = "E54"  !CDS_PN = "E54";
"VDDCR_CPU0_F22":   PN = "F22"  !CDS_PN = "F22";
"VDDCR_CPU0_F25":   PN = "F25"  !CDS_PN = "F25";
"VDDCR_CPU0_F28":   PN = "F28"  !CDS_PN = "F28";
"VDDCR_CPU0_F31":   PN = "F31"  !CDS_PN = "F31";
"VDDCR_CPU0_F34":   PN = "F34"  !CDS_PN = "F34";
"VDDCR_CPU0_F42":   PN = "F42"  !CDS_PN = "F42";
"VDDCR_CPU0_F45":   PN = "F45"  !CDS_PN = "F45";
"VDDCR_CPU0_F48":   PN = "F48"  !CDS_PN = "F48";
"VDDCR_CPU0_F51":   PN = "F51"  !CDS_PN = "F51";
"VDDCR_CPU0_F54":   PN = "F54"  !CDS_PN = "F54";
"VDDCR_CPU0_G35":   PN = "G35"  !CDS_PN = "G35";
"VDDCR_CPU0_G36":   PN = "G36"  !CDS_PN = "G36";
"VDDCR_CPU0_G40":   PN = "G40"  !CDS_PN = "G40";
"VDDCR_CPU0_G41":   PN = "G41"  !CDS_PN = "G41";
"VDDCR_CPU0_H23":   PN = "H23"  !CDS_PN = "H23";
"VDDCR_CPU0_H24":   PN = "H24"  !CDS_PN = "H24";
"VDDCR_CPU0_H26":   PN = "H26"  !CDS_PN = "H26";
"VDDCR_CPU0_H27":   PN = "H27"  !CDS_PN = "H27";
"VDDCR_CPU0_H29":   PN = "H29"  !CDS_PN = "H29";
"VDDCR_CPU0_H30":   PN = "H30"  !CDS_PN = "H30";
"VDDCR_CPU0_H32":   PN = "H32"  !CDS_PN = "H32";
"VDDCR_CPU0_H33":   PN = "H33"  !CDS_PN = "H33";
"VDDCR_CPU0_H43":   PN = "H43"  !CDS_PN = "H43";
"VDDCR_CPU0_H44":   PN = "H44"  !CDS_PN = "H44";
"VDDCR_CPU0_H46":   PN = "H46"  !CDS_PN = "H46";
"VDDCR_CPU0_H47":   PN = "H47"  !CDS_PN = "H47";
"VDDCR_CPU0_H49":   PN = "H49"  !CDS_PN = "H49";
"VDDCR_CPU0_H50":   PN = "H50"  !CDS_PN = "H50";
"VDDCR_CPU0_H52":   PN = "H52"  !CDS_PN = "H52";
"VDDCR_CPU0_H53":   PN = "H53"  !CDS_PN = "H53";
"VDDCR_CPU0_J35":   PN = "J35"  !CDS_PN = "J35";
"VDDCR_CPU0_J36":   PN = "J36"  !CDS_PN = "J36";
"VDDCR_CPU0_J40":   PN = "J40"  !CDS_PN = "J40";
"VDDCR_CPU0_J41":   PN = "J41"  !CDS_PN = "J41";
"VDDCR_CPU0_M23":   PN = "M23"  !CDS_PN = "M23";
"VDDCR_CPU0_M24":   PN = "M24"  !CDS_PN = "M24";
"VDDCR_CPU0_M26":   PN = "M26"  !CDS_PN = "M26";
"VDDCR_CPU0_M27":   PN = "M27"  !CDS_PN = "M27";
"VDDCR_CPU0_M29":   PN = "M29"  !CDS_PN = "M29";
"VDDCR_CPU0_M30":   PN = "M30"  !CDS_PN = "M30";
"VDDCR_CPU0_M32":   PN = "M32"  !CDS_PN = "M32";
"VDDCR_CPU0_M33":   PN = "M33"  !CDS_PN = "M33";
"VDDCR_CPU0_M43":   PN = "M43"  !CDS_PN = "M43";
"VDDCR_CPU0_M44":   PN = "M44"  !CDS_PN = "M44";
"VDDCR_CPU0_M46":   PN = "M46"  !CDS_PN = "M46";
"VDDCR_CPU0_M47":   PN = "M47"  !CDS_PN = "M47";
"VDDCR_CPU0_M49":   PN = "M49"  !CDS_PN = "M49";
"VDDCR_CPU0_M50":   PN = "M50"  !CDS_PN = "M50";
"VDDCR_CPU0_M52":   PN = "M52"  !CDS_PN = "M52";
"VDDCR_CPU0_M53":   PN = "M53"  !CDS_PN = "M53";
"VDDCR_CPU0_N35":   PN = "N35"  !CDS_PN = "N35";
"VDDCR_CPU0_N36":   PN = "N36"  !CDS_PN = "N36";
"VDDCR_CPU0_N40":   PN = "N40"  !CDS_PN = "N40";
"VDDCR_CPU0_N41":   PN = "N41"  !CDS_PN = "N41";
"VDDCR_CPU0_T23":   PN = "T23"  !CDS_PN = "T23";
"VDDCR_CPU0_T24":   PN = "T24"  !CDS_PN = "T24";
"VDDCR_CPU0_T26":   PN = "T26"  !CDS_PN = "T26";
"VDDCR_CPU0_T27":   PN = "T27"  !CDS_PN = "T27";
"VDDCR_CPU0_T29":   PN = "T29"  !CDS_PN = "T29";
"VDDCR_CPU0_T30":   PN = "T30"  !CDS_PN = "T30";
"VDDCR_CPU0_T32":   PN = "T32"  !CDS_PN = "T32";
"VDDCR_CPU0_T33":   PN = "T33"  !CDS_PN = "T33";
"VDDCR_CPU0_T43":   PN = "T43"  !CDS_PN = "T43";
"VDDCR_CPU0_T44":   PN = "T44"  !CDS_PN = "T44";
"VDDCR_CPU0_T46":   PN = "T46"  !CDS_PN = "T46";
"VDDCR_CPU0_T47":   PN = "T47"  !CDS_PN = "T47";
"VDDCR_CPU0_T49":   PN = "T49"  !CDS_PN = "T49";
"VDDCR_CPU0_T50":   PN = "T50"  !CDS_PN = "T50";
"VDDCR_CPU0_T52":   PN = "T52"  !CDS_PN = "T52";
"VDDCR_CPU0_T53":   PN = "T53"  !CDS_PN = "T53";
"VDDCR_CPU0_U35":   PN = "U35"  !CDS_PN = "U35";
"VDDCR_CPU0_U36":   PN = "U36"  !CDS_PN = "U36";
"VDDCR_CPU0_U40":   PN = "U40"  !CDS_PN = "U40";
"VDDCR_CPU0_U41":   PN = "U41"  !CDS_PN = "U41";
"VDDCR_CPU0_W29":   PN = "W29"  !CDS_PN = "W29";
"VDDCR_CPU0_W30":   PN = "W30"  !CDS_PN = "W30";
"VDDCR_CPU0_W32":   PN = "W32"  !CDS_PN = "W32";
"VDDCR_CPU0_W33":   PN = "W33"  !CDS_PN = "W33";
"VDDCR_CPU0_W43":   PN = "W43"  !CDS_PN = "W43";
"VDDCR_CPU0_W44":   PN = "W44"  !CDS_PN = "W44";
"VDDCR_CPU0_W46":   PN = "W46"  !CDS_PN = "W46";
"VDDCR_CPU0_W47":   PN = "W47"  !CDS_PN = "W47";
"VDDCR_CPU0_Y35":   PN = "Y35"  !CDS_PN = "Y35";
"VDDCR_CPU0_Y36":   PN = "Y36"  !CDS_PN = "Y36";
"VDDCR_CPU0_Y40":   PN = "Y40"  !CDS_PN = "Y40";
"VDDCR_CPU0_Y41":   PN = "Y41"  !CDS_PN = "Y41";
BODY = "GENOA_SP5","I32": #LOCATION = "U26" !CDS_LOCATION = "U26" &SEC = "25" #&CDS_SEC = "25";
"VDDCR_CPU1_BN27":   PN = "BN27"  !CDS_PN = "BN27";
"VDDCR_CPU1_BN31":   PN = "BN31"  !CDS_PN = "BN31";
"VDDCR_CPU1_BN35":   PN = "BN35"  !CDS_PN = "BN35";
"VDDCR_CPU1_BN42":   PN = "BN42"  !CDS_PN = "BN42";
"VDDCR_CPU1_BN46":   PN = "BN46"  !CDS_PN = "BN46";
"VDDCR_CPU1_BN50":   PN = "BN50"  !CDS_PN = "BN50";
"VDDCR_CPU1_BP24":   PN = "BP24"  !CDS_PN = "BP24";
"VDDCR_CPU1_BP26":   PN = "BP26"  !CDS_PN = "BP26";
"VDDCR_CPU1_BP28":   PN = "BP28"  !CDS_PN = "BP28";
"VDDCR_CPU1_BP30":   PN = "BP30"  !CDS_PN = "BP30";
"VDDCR_CPU1_BP32":   PN = "BP32"  !CDS_PN = "BP32";
"VDDCR_CPU1_BP34":   PN = "BP34"  !CDS_PN = "BP34";
"VDDCR_CPU1_BP36":   PN = "BP36"  !CDS_PN = "BP36";
"VDDCR_CPU1_BP39":   PN = "BP39"  !CDS_PN = "BP39";
"VDDCR_CPU1_BP41":   PN = "BP41"  !CDS_PN = "BP41";
"VDDCR_CPU1_BP43":   PN = "BP43"  !CDS_PN = "BP43";
"VDDCR_CPU1_BP45":   PN = "BP45"  !CDS_PN = "BP45";
"VDDCR_CPU1_BP47":   PN = "BP47"  !CDS_PN = "BP47";
"VDDCR_CPU1_BP49":   PN = "BP49"  !CDS_PN = "BP49";
"VDDCR_CPU1_BR23":   PN = "BR23"  !CDS_PN = "BR23";
"VDDCR_CPU1_BR25":   PN = "BR25"  !CDS_PN = "BR25";
"VDDCR_CPU1_BR27":   PN = "BR27"  !CDS_PN = "BR27";
"VDDCR_CPU1_BR29":   PN = "BR29"  !CDS_PN = "BR29";
"VDDCR_CPU1_BR31":   PN = "BR31"  !CDS_PN = "BR31";
"VDDCR_CPU1_BR33":   PN = "BR33"  !CDS_PN = "BR33";
"VDDCR_CPU1_BR35":   PN = "BR35"  !CDS_PN = "BR35";
"VDDCR_CPU1_BR40":   PN = "BR40"  !CDS_PN = "BR40";
"VDDCR_CPU1_BR42":   PN = "BR42"  !CDS_PN = "BR42";
"VDDCR_CPU1_BR44":   PN = "BR44"  !CDS_PN = "BR44";
"VDDCR_CPU1_BR46":   PN = "BR46"  !CDS_PN = "BR46";
"VDDCR_CPU1_BR48":   PN = "BR48"  !CDS_PN = "BR48";
"VDDCR_CPU1_BR50":   PN = "BR50"  !CDS_PN = "BR50";
"VDDCR_CPU1_BR52":   PN = "BR52"  !CDS_PN = "BR52";
"VDDCR_CPU1_BT23":   PN = "BT23"  !CDS_PN = "BT23";
"VDDCR_CPU1_BT24":   PN = "BT24"  !CDS_PN = "BT24";
"VDDCR_CPU1_BT26":   PN = "BT26"  !CDS_PN = "BT26";
"VDDCR_CPU1_BT27":   PN = "BT27"  !CDS_PN = "BT27";
"VDDCR_CPU1_BT29":   PN = "BT29"  !CDS_PN = "BT29";
"VDDCR_CPU1_BT30":   PN = "BT30"  !CDS_PN = "BT30";
"VDDCR_CPU1_BT32":   PN = "BT32"  !CDS_PN = "BT32";
"VDDCR_CPU1_BT33":   PN = "BT33"  !CDS_PN = "BT33";
"VDDCR_CPU1_BT43":   PN = "BT43"  !CDS_PN = "BT43";
"VDDCR_CPU1_BT44":   PN = "BT44"  !CDS_PN = "BT44";
"VDDCR_CPU1_BT46":   PN = "BT46"  !CDS_PN = "BT46";
"VDDCR_CPU1_BT47":   PN = "BT47"  !CDS_PN = "BT47";
"VDDCR_CPU1_BT49":   PN = "BT49"  !CDS_PN = "BT49";
"VDDCR_CPU1_BT50":   PN = "BT50"  !CDS_PN = "BT50";
"VDDCR_CPU1_BT52":   PN = "BT52"  !CDS_PN = "BT52";
"VDDCR_CPU1_BT53":   PN = "BT53"  !CDS_PN = "BT53";
"VDDCR_CPU1_BW35":   PN = "BW35"  !CDS_PN = "BW35";
"VDDCR_CPU1_BW36":   PN = "BW36"  !CDS_PN = "BW36";
"VDDCR_CPU1_BW40":   PN = "BW40"  !CDS_PN = "BW40";
"VDDCR_CPU1_BW41":   PN = "BW41"  !CDS_PN = "BW41";
"VDDCR_CPU1_BY23":   PN = "BY23"  !CDS_PN = "BY23";
"VDDCR_CPU1_BY24":   PN = "BY24"  !CDS_PN = "BY24";
"VDDCR_CPU1_BY26":   PN = "BY26"  !CDS_PN = "BY26";
"VDDCR_CPU1_BY27":   PN = "BY27"  !CDS_PN = "BY27";
"VDDCR_CPU1_BY29":   PN = "BY29"  !CDS_PN = "BY29";
"VDDCR_CPU1_BY30":   PN = "BY30"  !CDS_PN = "BY30";
"VDDCR_CPU1_BY32":   PN = "BY32"  !CDS_PN = "BY32";
"VDDCR_CPU1_BY33":   PN = "BY33"  !CDS_PN = "BY33";
"VDDCR_CPU1_BY43":   PN = "BY43"  !CDS_PN = "BY43";
"VDDCR_CPU1_BY44":   PN = "BY44"  !CDS_PN = "BY44";
"VDDCR_CPU1_BY46":   PN = "BY46"  !CDS_PN = "BY46";
"VDDCR_CPU1_BY47":   PN = "BY47"  !CDS_PN = "BY47";
"VDDCR_CPU1_BY49":   PN = "BY49"  !CDS_PN = "BY49";
"VDDCR_CPU1_BY50":   PN = "BY50"  !CDS_PN = "BY50";
"VDDCR_CPU1_BY52":   PN = "BY52"  !CDS_PN = "BY52";
"VDDCR_CPU1_BY53":   PN = "BY53"  !CDS_PN = "BY53";
"VDDCR_CPU1_CC35":   PN = "CC35"  !CDS_PN = "CC35";
"VDDCR_CPU1_CC36":   PN = "CC36"  !CDS_PN = "CC36";
"VDDCR_CPU1_CC40":   PN = "CC40"  !CDS_PN = "CC40";
"VDDCR_CPU1_CC41":   PN = "CC41"  !CDS_PN = "CC41";
"VDDCR_CPU1_CD23":   PN = "CD23"  !CDS_PN = "CD23";
"VDDCR_CPU1_CD24":   PN = "CD24"  !CDS_PN = "CD24";
"VDDCR_CPU1_CD26":   PN = "CD26"  !CDS_PN = "CD26";
"VDDCR_CPU1_CD27":   PN = "CD27"  !CDS_PN = "CD27";
"VDDCR_CPU1_CD29":   PN = "CD29"  !CDS_PN = "CD29";
"VDDCR_CPU1_CD30":   PN = "CD30"  !CDS_PN = "CD30";
"VDDCR_CPU1_CD32":   PN = "CD32"  !CDS_PN = "CD32";
"VDDCR_CPU1_CD33":   PN = "CD33"  !CDS_PN = "CD33";
"VDDCR_CPU1_CD43":   PN = "CD43"  !CDS_PN = "CD43";
"VDDCR_CPU1_CD44":   PN = "CD44"  !CDS_PN = "CD44";
"VDDCR_CPU1_CD46":   PN = "CD46"  !CDS_PN = "CD46";
"VDDCR_CPU1_CD47":   PN = "CD47"  !CDS_PN = "CD47";
"VDDCR_CPU1_CD49":   PN = "CD49"  !CDS_PN = "CD49";
"VDDCR_CPU1_CD50":   PN = "CD50"  !CDS_PN = "CD50";
"VDDCR_CPU1_CD52":   PN = "CD52"  !CDS_PN = "CD52";
"VDDCR_CPU1_CD53":   PN = "CD53"  !CDS_PN = "CD53";
"VDDCR_CPU1_CG35":   PN = "CG35"  !CDS_PN = "CG35";
"VDDCR_CPU1_CG36":   PN = "CG36"  !CDS_PN = "CG36";
"VDDCR_CPU1_CG40":   PN = "CG40"  !CDS_PN = "CG40";
"VDDCR_CPU1_CG41":   PN = "CG41"  !CDS_PN = "CG41";
"VDDCR_CPU1_CH23":   PN = "CH23"  !CDS_PN = "CH23";
"VDDCR_CPU1_CH24":   PN = "CH24"  !CDS_PN = "CH24";
"VDDCR_CPU1_CH26":   PN = "CH26"  !CDS_PN = "CH26";
"VDDCR_CPU1_CH27":   PN = "CH27"  !CDS_PN = "CH27";
"VDDCR_CPU1_CH29":   PN = "CH29"  !CDS_PN = "CH29";
"VDDCR_CPU1_CH30":   PN = "CH30"  !CDS_PN = "CH30";
"VDDCR_CPU1_CH32":   PN = "CH32"  !CDS_PN = "CH32";
"VDDCR_CPU1_CH33":   PN = "CH33"  !CDS_PN = "CH33";
"VDDCR_CPU1_CH43":   PN = "CH43"  !CDS_PN = "CH43";
"VDDCR_CPU1_CH44":   PN = "CH44"  !CDS_PN = "CH44";
"VDDCR_CPU1_CH46":   PN = "CH46"  !CDS_PN = "CH46";
"VDDCR_CPU1_CH47":   PN = "CH47"  !CDS_PN = "CH47";
"VDDCR_CPU1_CH49":   PN = "CH49"  !CDS_PN = "CH49";
"VDDCR_CPU1_CH50":   PN = "CH50"  !CDS_PN = "CH50";
"VDDCR_CPU1_CH52":   PN = "CH52"  !CDS_PN = "CH52";
"VDDCR_CPU1_CH53":   PN = "CH53"  !CDS_PN = "CH53";
"VDDCR_CPU1_CK35":   PN = "CK35"  !CDS_PN = "CK35";
"VDDCR_CPU1_CK36":   PN = "CK36"  !CDS_PN = "CK36";
"VDDCR_CPU1_CK40":   PN = "CK40"  !CDS_PN = "CK40";
"VDDCR_CPU1_CK41":   PN = "CK41"  !CDS_PN = "CK41";
"VDDCR_CPU1_CL29":   PN = "CL29"  !CDS_PN = "CL29";
"VDDCR_CPU1_CL30":   PN = "CL30"  !CDS_PN = "CL30";
"VDDCR_CPU1_CL32":   PN = "CL32"  !CDS_PN = "CL32";
"VDDCR_CPU1_CL33":   PN = "CL33"  !CDS_PN = "CL33";
"VDDCR_CPU1_CL43":   PN = "CL43"  !CDS_PN = "CL43";
"VDDCR_CPU1_CL44":   PN = "CL44"  !CDS_PN = "CL44";
"VDDCR_CPU1_CL46":   PN = "CL46"  !CDS_PN = "CL46";
"VDDCR_CPU1_CL47":   PN = "CL47"  !CDS_PN = "CL47";
"VDDCR_CPU1_CN35":   PN = "CN35"  !CDS_PN = "CN35";
"VDDCR_CPU1_CN36":   PN = "CN36"  !CDS_PN = "CN36";
"VDDCR_CPU1_CN40":   PN = "CN40"  !CDS_PN = "CN40";
"VDDCR_CPU1_CN41":   PN = "CN41"  !CDS_PN = "CN41";
"VDDCR_CPU1_CP23":   PN = "CP23"  !CDS_PN = "CP23";
"VDDCR_CPU1_CP24":   PN = "CP24"  !CDS_PN = "CP24";
"VDDCR_CPU1_CP26":   PN = "CP26"  !CDS_PN = "CP26";
"VDDCR_CPU1_CP27":   PN = "CP27"  !CDS_PN = "CP27";
"VDDCR_CPU1_CP29":   PN = "CP29"  !CDS_PN = "CP29";
"VDDCR_CPU1_CP30":   PN = "CP30"  !CDS_PN = "CP30";
"VDDCR_CPU1_CP32":   PN = "CP32"  !CDS_PN = "CP32";
"VDDCR_CPU1_CP33":   PN = "CP33"  !CDS_PN = "CP33";
"VDDCR_CPU1_CP43":   PN = "CP43"  !CDS_PN = "CP43";
"VDDCR_CPU1_CP44":   PN = "CP44"  !CDS_PN = "CP44";
"VDDCR_CPU1_CP46":   PN = "CP46"  !CDS_PN = "CP46";
"VDDCR_CPU1_CP47":   PN = "CP47"  !CDS_PN = "CP47";
"VDDCR_CPU1_CP49":   PN = "CP49"  !CDS_PN = "CP49";
"VDDCR_CPU1_CP50":   PN = "CP50"  !CDS_PN = "CP50";
"VDDCR_CPU1_CP52":   PN = "CP52"  !CDS_PN = "CP52";
"VDDCR_CPU1_CP53":   PN = "CP53"  !CDS_PN = "CP53";
"VDDCR_CPU1_CU35":   PN = "CU35"  !CDS_PN = "CU35";
"VDDCR_CPU1_CU36":   PN = "CU36"  !CDS_PN = "CU36";
"VDDCR_CPU1_CU40":   PN = "CU40"  !CDS_PN = "CU40";
"VDDCR_CPU1_CU41":   PN = "CU41"  !CDS_PN = "CU41";
"VDDCR_CPU1_CV23":   PN = "CV23"  !CDS_PN = "CV23";
"VDDCR_CPU1_CV24":   PN = "CV24"  !CDS_PN = "CV24";
"VDDCR_CPU1_CV26":   PN = "CV26"  !CDS_PN = "CV26";
"VDDCR_CPU1_CV27":   PN = "CV27"  !CDS_PN = "CV27";
"VDDCR_CPU1_CV29":   PN = "CV29"  !CDS_PN = "CV29";
"VDDCR_CPU1_CV30":   PN = "CV30"  !CDS_PN = "CV30";
"VDDCR_CPU1_CV32":   PN = "CV32"  !CDS_PN = "CV32";
"VDDCR_CPU1_CV33":   PN = "CV33"  !CDS_PN = "CV33";
"VDDCR_CPU1_CV43":   PN = "CV43"  !CDS_PN = "CV43";
"VDDCR_CPU1_CV44":   PN = "CV44"  !CDS_PN = "CV44";
"VDDCR_CPU1_CV46":   PN = "CV46"  !CDS_PN = "CV46";
"VDDCR_CPU1_CV47":   PN = "CV47"  !CDS_PN = "CV47";
"VDDCR_CPU1_CV49":   PN = "CV49"  !CDS_PN = "CV49";
"VDDCR_CPU1_CV50":   PN = "CV50"  !CDS_PN = "CV50";
"VDDCR_CPU1_CV52":   PN = "CV52"  !CDS_PN = "CV52";
"VDDCR_CPU1_CV53":   PN = "CV53"  !CDS_PN = "CV53";
"VDDCR_CPU1_DA35":   PN = "DA35"  !CDS_PN = "DA35";
"VDDCR_CPU1_DA36":   PN = "DA36"  !CDS_PN = "DA36";
"VDDCR_CPU1_DA40":   PN = "DA40"  !CDS_PN = "DA40";
"VDDCR_CPU1_DA41":   PN = "DA41"  !CDS_PN = "DA41";
"VDDCR_CPU1_DB23":   PN = "DB23"  !CDS_PN = "DB23";
"VDDCR_CPU1_DB24":   PN = "DB24"  !CDS_PN = "DB24";
"VDDCR_CPU1_DB26":   PN = "DB26"  !CDS_PN = "DB26";
"VDDCR_CPU1_DB27":   PN = "DB27"  !CDS_PN = "DB27";
"VDDCR_CPU1_DB29":   PN = "DB29"  !CDS_PN = "DB29";
"VDDCR_CPU1_DB30":   PN = "DB30"  !CDS_PN = "DB30";
"VDDCR_CPU1_DB32":   PN = "DB32"  !CDS_PN = "DB32";
"VDDCR_CPU1_DB33":   PN = "DB33"  !CDS_PN = "DB33";
"VDDCR_CPU1_DB43":   PN = "DB43"  !CDS_PN = "DB43";
"VDDCR_CPU1_DB44":   PN = "DB44"  !CDS_PN = "DB44";
"VDDCR_CPU1_DB46":   PN = "DB46"  !CDS_PN = "DB46";
"VDDCR_CPU1_DB47":   PN = "DB47"  !CDS_PN = "DB47";
"VDDCR_CPU1_DB49":   PN = "DB49"  !CDS_PN = "DB49";
"VDDCR_CPU1_DB50":   PN = "DB50"  !CDS_PN = "DB50";
"VDDCR_CPU1_DB52":   PN = "DB52"  !CDS_PN = "DB52";
"VDDCR_CPU1_DB53":   PN = "DB53"  !CDS_PN = "DB53";
"VDDCR_CPU1_DC35":   PN = "DC35"  !CDS_PN = "DC35";
"VDDCR_CPU1_DC36":   PN = "DC36"  !CDS_PN = "DC36";
"VDDCR_CPU1_DC40":   PN = "DC40"  !CDS_PN = "DC40";
"VDDCR_CPU1_DC41":   PN = "DC41"  !CDS_PN = "DC41";
"VDDCR_CPU1_DD22":   PN = "DD22"  !CDS_PN = "DD22";
"VDDCR_CPU1_DD25":   PN = "DD25"  !CDS_PN = "DD25";
"VDDCR_CPU1_DD28":   PN = "DD28"  !CDS_PN = "DD28";
"VDDCR_CPU1_DD31":   PN = "DD31"  !CDS_PN = "DD31";
"VDDCR_CPU1_DD34":   PN = "DD34"  !CDS_PN = "DD34";
"VDDCR_CPU1_DD42":   PN = "DD42"  !CDS_PN = "DD42";
"VDDCR_CPU1_DD45":   PN = "DD45"  !CDS_PN = "DD45";
"VDDCR_CPU1_DD48":   PN = "DD48"  !CDS_PN = "DD48";
"VDDCR_CPU1_DD51":   PN = "DD51"  !CDS_PN = "DD51";
"VDDCR_CPU1_DD54":   PN = "DD54"  !CDS_PN = "DD54";
"VDDCR_CPU1_DE22":   PN = "DE22"  !CDS_PN = "DE22";
"VDDCR_CPU1_DE25":   PN = "DE25"  !CDS_PN = "DE25";
"VDDCR_CPU1_DE28":   PN = "DE28"  !CDS_PN = "DE28";
"VDDCR_CPU1_DE31":   PN = "DE31"  !CDS_PN = "DE31";
"VDDCR_CPU1_DE34":   PN = "DE34"  !CDS_PN = "DE34";
"VDDCR_CPU1_DE35":   PN = "DE35"  !CDS_PN = "DE35";
"VDDCR_CPU1_DE41":   PN = "DE41"  !CDS_PN = "DE41";
"VDDCR_CPU1_DE42":   PN = "DE42"  !CDS_PN = "DE42";
"VDDCR_CPU1_DE45":   PN = "DE45"  !CDS_PN = "DE45";
"VDDCR_CPU1_DE48":   PN = "DE48"  !CDS_PN = "DE48";
"VDDCR_CPU1_DE51":   PN = "DE51"  !CDS_PN = "DE51";
"VDDCR_CPU1_DE54":   PN = "DE54"  !CDS_PN = "DE54";
"VDDCR_CPU1_DG19":   PN = "DG19"  !CDS_PN = "DG19";
"VDDCR_CPU1_DG57":   PN = "DG57"  !CDS_PN = "DG57";
"VDDCR_CPU1_DH19":   PN = "DH19"  !CDS_PN = "DH19";
"VDDCR_CPU1_DH20":   PN = "DH20"  !CDS_PN = "DH20";
"VDDCR_CPU1_DH22":   PN = "DH22"  !CDS_PN = "DH22";
"VDDCR_CPU1_DH23":   PN = "DH23"  !CDS_PN = "DH23";
"VDDCR_CPU1_DH25":   PN = "DH25"  !CDS_PN = "DH25";
"VDDCR_CPU1_DH26":   PN = "DH26"  !CDS_PN = "DH26";
"VDDCR_CPU1_DH28":   PN = "DH28"  !CDS_PN = "DH28";
"VDDCR_CPU1_DH29":   PN = "DH29"  !CDS_PN = "DH29";
"VDDCR_CPU1_DH31":   PN = "DH31"  !CDS_PN = "DH31";
"VDDCR_CPU1_DH32":   PN = "DH32"  !CDS_PN = "DH32";
"VDDCR_CPU1_DH34":   PN = "DH34"  !CDS_PN = "DH34";
"VDDCR_CPU1_DH35":   PN = "DH35"  !CDS_PN = "DH35";
"VDDCR_CPU1_DH41":   PN = "DH41"  !CDS_PN = "DH41";
"VDDCR_CPU1_DH42":   PN = "DH42"  !CDS_PN = "DH42";
"VDDCR_CPU1_DH44":   PN = "DH44"  !CDS_PN = "DH44";
"VDDCR_CPU1_DH45":   PN = "DH45"  !CDS_PN = "DH45";
"VDDCR_CPU1_DH47":   PN = "DH47"  !CDS_PN = "DH47";
"VDDCR_CPU1_DH48":   PN = "DH48"  !CDS_PN = "DH48";
"VDDCR_CPU1_DH50":   PN = "DH50"  !CDS_PN = "DH50";
"VDDCR_CPU1_DH51":   PN = "DH51"  !CDS_PN = "DH51";
"VDDCR_CPU1_DH53":   PN = "DH53"  !CDS_PN = "DH53";
"VDDCR_CPU1_DH54":   PN = "DH54"  !CDS_PN = "DH54";
"VDDCR_CPU1_DH56":   PN = "DH56"  !CDS_PN = "DH56";
"VDDCR_CPU1_DH57":   PN = "DH57"  !CDS_PN = "DH57";
BODY = "GENOA_SP5","I45": #LOCATION = "U26" !CDS_LOCATION = "U26" &SEC = "27" #&CDS_SEC = "27";
"VDD_11_S3_BJ18":   PN = "BJ18"  !CDS_PN = "BJ18";
"VDD_11_S3_BJ23":   PN = "BJ23"  !CDS_PN = "BJ23";
"VDD_11_S3_BJ25":   PN = "BJ25"  !CDS_PN = "BJ25";
"VDD_11_S3_BJ27":   PN = "BJ27"  !CDS_PN = "BJ27";
"VDD_11_S3_BK22":   PN = "BK22"  !CDS_PN = "BK22";
"VDD_11_S3_BK24":   PN = "BK24"  !CDS_PN = "BK24";
"VDD_11_S3_BK26":   PN = "BK26"  !CDS_PN = "BK26";
"VDD_11_S3_BK28":   PN = "BK28"  !CDS_PN = "BK28";
"VDD_11_S3_BK49":   PN = "BK49"  !CDS_PN = "BK49";
"VDD_11_S3_BL23":   PN = "BL23"  !CDS_PN = "BL23";
"VDD_11_S3_BL25":   PN = "BL25"  !CDS_PN = "BL25";
"VDD_11_S3_BL27":   PN = "BL27"  !CDS_PN = "BL27";
"VDD_11_S3_BL48":   PN = "BL48"  !CDS_PN = "BL48";
"VDD_11_S3_BM12":   PN = "BM12"  !CDS_PN = "BM12";
"VDD_11_S3_BM19":   PN = "BM19"  !CDS_PN = "BM19";
"VDD_11_S3_BM22":   PN = "BM22"  !CDS_PN = "BM22";
"VDD_11_S3_BM24":   PN = "BM24"  !CDS_PN = "BM24";
"VDD_11_S3_BM26":   PN = "BM26"  !CDS_PN = "BM26";
"VDD_11_S3_BM28":   PN = "BM28"  !CDS_PN = "BM28";
"VDD_11_S3_BM30":   PN = "BM30"  !CDS_PN = "BM30";
"VDD_11_S3_BM32":   PN = "BM32"  !CDS_PN = "BM32";
"VDD_11_S3_BM34":   PN = "BM34"  !CDS_PN = "BM34";
"VDD_11_S3_BM36":   PN = "BM36"  !CDS_PN = "BM36";
"VDD_11_S3_BM39":   PN = "BM39"  !CDS_PN = "BM39";
"VDD_11_S3_BM41":   PN = "BM41"  !CDS_PN = "BM41";
"VDD_11_S3_BM43":   PN = "BM43"  !CDS_PN = "BM43";
"VDD_11_S3_BM45":   PN = "BM45"  !CDS_PN = "BM45";
"VDD_11_S3_BM47":   PN = "BM47"  !CDS_PN = "BM47";
"VDD_11_S3_BM49":   PN = "BM49"  !CDS_PN = "BM49";
"VDD_11_S3_BN25":   PN = "BN25"  !CDS_PN = "BN25";
"VDD_11_S3_BN29":   PN = "BN29"  !CDS_PN = "BN29";
"VDD_11_S3_BN33":   PN = "BN33"  !CDS_PN = "BN33";
"VDD_11_S3_BN40":   PN = "BN40"  !CDS_PN = "BN40";
"VDD_11_S3_BN44":   PN = "BN44"  !CDS_PN = "BN44";
"VDD_11_S3_BN48":   PN = "BN48"  !CDS_PN = "BN48";
"VDD_11_S3_BP22":   PN = "BP22"  !CDS_PN = "BP22";
"VDD_11_S3_BR4":   PN = "BR4"  !CDS_PN = "BR4";
"VDD_11_S3_BR11":   PN = "BR11"  !CDS_PN = "BR11";
"VDD_11_S3_BR18":   PN = "BR18"  !CDS_PN = "BR18";
"VDD_11_S3_BV5":   PN = "BV5"  !CDS_PN = "BV5";
"VDD_11_S3_BV12":   PN = "BV12"  !CDS_PN = "BV12";
"VDD_11_S3_BV19":   PN = "BV19"  !CDS_PN = "BV19";
"VDD_11_S3_BV22":   PN = "BV22"  !CDS_PN = "BV22";
"VDD_11_S3_CA4":   PN = "CA4"  !CDS_PN = "CA4";
"VDD_11_S3_CA11":   PN = "CA11"  !CDS_PN = "CA11";
"VDD_11_S3_CA18":   PN = "CA18"  !CDS_PN = "CA18";
"VDD_11_S3_CB22":   PN = "CB22"  !CDS_PN = "CB22";
"VDD_11_S3_CD5":   PN = "CD5"  !CDS_PN = "CD5";
"VDD_11_S3_CD12":   PN = "CD12"  !CDS_PN = "CD12";
"VDD_11_S3_CD19":   PN = "CD19"  !CDS_PN = "CD19";
"VDD_11_S3_CF22":   PN = "CF22"  !CDS_PN = "CF22";
"VDD_11_S3_CG4":   PN = "CG4"  !CDS_PN = "CG4";
"VDD_11_S3_CG11":   PN = "CG11"  !CDS_PN = "CG11";
"VDD_11_S3_CG18":   PN = "CG18"  !CDS_PN = "CG18";
"VDD_11_S3_CJ22":   PN = "CJ22"  !CDS_PN = "CJ22";
"VDD_11_S3_CK5":   PN = "CK5"  !CDS_PN = "CK5";
"VDD_11_S3_CK12":   PN = "CK12"  !CDS_PN = "CK12";
"VDD_11_S3_CK19":   PN = "CK19"  !CDS_PN = "CK19";
"VDD_11_S3_CM22":   PN = "CM22"  !CDS_PN = "CM22";
"VDD_11_S3_CN4":   PN = "CN4"  !CDS_PN = "CN4";
"VDD_11_S3_CN11":   PN = "CN11"  !CDS_PN = "CN11";
"VDD_11_S3_CN18":   PN = "CN18"  !CDS_PN = "CN18";
"VDD_11_S3_CT5":   PN = "CT5"  !CDS_PN = "CT5";
"VDD_11_S3_CT12":   PN = "CT12"  !CDS_PN = "CT12";
"VDD_11_S3_CT19":   PN = "CT19"  !CDS_PN = "CT19";
"VDD_11_S3_CT22":   PN = "CT22"  !CDS_PN = "CT22";
"VDD_11_S3_CW4":   PN = "CW4"  !CDS_PN = "CW4";
"VDD_11_S3_CW11":   PN = "CW11"  !CDS_PN = "CW11";
"VDD_11_S3_CW18":   PN = "CW18"  !CDS_PN = "CW18";
"VDD_11_S3_CY22":   PN = "CY22"  !CDS_PN = "CY22";
"VDD_11_S3_DB5":   PN = "DB5"  !CDS_PN = "DB5";
"VDD_11_S3_DB12":   PN = "DB12"  !CDS_PN = "DB12";
"VDD_11_S3_DB19":   PN = "DB19"  !CDS_PN = "DB19";
"VDD_11_S3_DE4":   PN = "DE4"  !CDS_PN = "DE4";
"VDD_11_S3_DE11":   PN = "DE11"  !CDS_PN = "DE11";
"VDD_11_S3_DE18":   PN = "DE18"  !CDS_PN = "DE18";
"VDD_11_S3_DG5":   PN = "DG5"  !CDS_PN = "DG5";
"VDD_18_S5_AR52":   PN = "AR52"  !CDS_PN = "AR52";
"VDD_18_S5_AR54":   PN = "AR54"  !CDS_PN = "AR54";
"VDD_18_S5_AT51":   PN = "AT51"  !CDS_PN = "AT51";
"VDD_18_S5_AT53":   PN = "AT53"  !CDS_PN = "AT53";
"VDD_18_S5_AU50":   PN = "AU50"  !CDS_PN = "AU50";
"VDD_18_S5_AU52":   PN = "AU52"  !CDS_PN = "AU52";
"VDD_18_S5_AU54":   PN = "AU54"  !CDS_PN = "AU54";
"VDD_18_S5_AV49":   PN = "AV49"  !CDS_PN = "AV49";
"VDD_18_S5_AV51":   PN = "AV51"  !CDS_PN = "AV51";
"VDD_18_S5_AV53":   PN = "AV53"  !CDS_PN = "AV53";
"VDD_18_S5_AW50":   PN = "AW50"  !CDS_PN = "AW50";
"VDD_18_S5_AW52":   PN = "AW52"  !CDS_PN = "AW52";
"VDD_18_S5_AW54":   PN = "AW54"  !CDS_PN = "AW54";
"VDD_18_S5_AY51":   PN = "AY51"  !CDS_PN = "AY51";
"VDD_18_S5_AY53":   PN = "AY53"  !CDS_PN = "AY53";
"VDD_18_S5_BA50":   PN = "BA50"  !CDS_PN = "BA50";
"VDD_18_S5_BA52":   PN = "BA52"  !CDS_PN = "BA52";
"VDD_18_S5_BA54":   PN = "BA54"  !CDS_PN = "BA54";
"VDD_18_S5_BB51":   PN = "BB51"  !CDS_PN = "BB51";
"VDD_18_S5_BB53":   PN = "BB53"  !CDS_PN = "BB53";
"VDD_18_S5_BC52":   PN = "BC52"  !CDS_PN = "BC52";
"VDD_18_S5_BC54":   PN = "BC54"  !CDS_PN = "BC54";
"VDD_33_S5_BN52":   PN = "BN52"  !CDS_PN = "BN52";
"VDD_33_S5_BP51":   PN = "BP51"  !CDS_PN = "BP51";
"VDDBT_RTC_G":   PN = "BN23"  !CDS_PN = "BN23";
"VDDIO_AA54":   PN = "AA54"  !CDS_PN = "AA54";
"VDDIO_AC58":   PN = "AC58"  !CDS_PN = "AC58";
"VDDIO_AC65":   PN = "AC65"  !CDS_PN = "AC65";
"VDDIO_AC72":   PN = "AC72"  !CDS_PN = "AC72";
"VDDIO_AD54":   PN = "AD54"  !CDS_PN = "AD54";
"VDDIO_AF57":   PN = "AF57"  !CDS_PN = "AF57";
"VDDIO_AF64":   PN = "AF64"  !CDS_PN = "AF64";
"VDDIO_AF71":   PN = "AF71"  !CDS_PN = "AF71";
"VDDIO_AH54":   PN = "AH54"  !CDS_PN = "AH54";
"VDDIO_AJ58":   PN = "AJ58"  !CDS_PN = "AJ58";
"VDDIO_AJ65":   PN = "AJ65"  !CDS_PN = "AJ65";
"VDDIO_AJ72":   PN = "AJ72"  !CDS_PN = "AJ72";
"VDDIO_AM54":   PN = "AM54"  !CDS_PN = "AM54";
"VDDIO_AM57":   PN = "AM57"  !CDS_PN = "AM57";
"VDDIO_AM64":   PN = "AM64"  !CDS_PN = "AM64";
"VDDIO_AM71":   PN = "AM71"  !CDS_PN = "AM71";
"VDDIO_AR58":   PN = "AR58"  !CDS_PN = "AR58";
"VDDIO_AR65":   PN = "AR65"  !CDS_PN = "AR65";
"VDDIO_AR72":   PN = "AR72"  !CDS_PN = "AR72";
"VDDIO_AUDIO":   PN = "BH27"  !CDS_PN = "BH27";
"VDDIO_AV57":   PN = "AV57"  !CDS_PN = "AV57";
"VDDIO_AV64":   PN = "AV64"  !CDS_PN = "AV64";
"VDDIO_AV71":   PN = "AV71"  !CDS_PN = "AV71";
"VDDIO_BA58":   PN = "BA58"  !CDS_PN = "BA58";
"VDDIO_BA65":   PN = "BA65"  !CDS_PN = "BA65";
"VDDIO_BA72":   PN = "BA72"  !CDS_PN = "BA72";
"VDDIO_BD50":   PN = "BD50"  !CDS_PN = "BD50";
"VDDIO_BD52":   PN = "BD52"  !CDS_PN = "BD52";
"VDDIO_BD54":   PN = "BD54"  !CDS_PN = "BD54";
"VDDIO_BF51":   PN = "BF51"  !CDS_PN = "BF51";
"VDDIO_BF53":   PN = "BF53"  !CDS_PN = "BF53";
"VDDIO_BF57":   PN = "BF57"  !CDS_PN = "BF57";
"VDDIO_BF64":   PN = "BF64"  !CDS_PN = "BF64";
"VDDIO_BF71":   PN = "BF71"  !CDS_PN = "BF71";
"VDDIO_BG50":   PN = "BG50"  !CDS_PN = "BG50";
"VDDIO_BG52":   PN = "BG52"  !CDS_PN = "BG52";
"VDDIO_BG54":   PN = "BG54"  !CDS_PN = "BG54";
"VDDIO_BH51":   PN = "BH51"  !CDS_PN = "BH51";
"VDDIO_BH53":   PN = "BH53"  !CDS_PN = "BH53";
"VDDIO_BJ50":   PN = "BJ50"  !CDS_PN = "BJ50";
"VDDIO_BJ52":   PN = "BJ52"  !CDS_PN = "BJ52";
"VDDIO_BJ54":   PN = "BJ54"  !CDS_PN = "BJ54";
"VDDIO_BJ58":   PN = "BJ58"  !CDS_PN = "BJ58";
"VDDIO_BJ65":   PN = "BJ65"  !CDS_PN = "BJ65";
"VDDIO_BJ72":   PN = "BJ72"  !CDS_PN = "BJ72";
"VDDIO_BK51":   PN = "BK51"  !CDS_PN = "BK51";
"VDDIO_BK53":   PN = "BK53"  !CDS_PN = "BK53";
"VDDIO_BL50":   PN = "BL50"  !CDS_PN = "BL50";
"VDDIO_BL52":   PN = "BL52"  !CDS_PN = "BL52";
"VDDIO_BL54":   PN = "BL54"  !CDS_PN = "BL54";
"VDDIO_BM51":   PN = "BM51"  !CDS_PN = "BM51";
"VDDIO_BM53":   PN = "BM53"  !CDS_PN = "BM53";
"VDDIO_BM57":   PN = "BM57"  !CDS_PN = "BM57";
"VDDIO_BM64":   PN = "BM64"  !CDS_PN = "BM64";
"VDDIO_BM71":   PN = "BM71"  !CDS_PN = "BM71";
"VDDIO_BN54":   PN = "BN54"  !CDS_PN = "BN54";
"VDDIO_BR58":   PN = "BR58"  !CDS_PN = "BR58";
"VDDIO_BR65":   PN = "BR65"  !CDS_PN = "BR65";
"VDDIO_BR72":   PN = "BR72"  !CDS_PN = "BR72";
"VDDIO_BV54":   PN = "BV54"  !CDS_PN = "BV54";
"VDDIO_BV57":   PN = "BV57"  !CDS_PN = "BV57";
"VDDIO_BV64":   PN = "BV64"  !CDS_PN = "BV64";
"VDDIO_BV71":   PN = "BV71"  !CDS_PN = "BV71";
"VDDIO_CA58":   PN = "CA58"  !CDS_PN = "CA58";
"VDDIO_CA65":   PN = "CA65"  !CDS_PN = "CA65";
"VDDIO_CA72":   PN = "CA72"  !CDS_PN = "CA72";
"VDDIO_CB54":   PN = "CB54"  !CDS_PN = "CB54";
"VDDIO_CD57":   PN = "CD57"  !CDS_PN = "CD57";
"VDDIO_CD64":   PN = "CD64"  !CDS_PN = "CD64";
"VDDIO_CD71":   PN = "CD71"  !CDS_PN = "CD71";
"VDDIO_CF54":   PN = "CF54"  !CDS_PN = "CF54";
"VDDIO_CG58":   PN = "CG58"  !CDS_PN = "CG58";
"VDDIO_CG65":   PN = "CG65"  !CDS_PN = "CG65";
"VDDIO_CG72":   PN = "CG72"  !CDS_PN = "CG72";
"VDDIO_CJ54":   PN = "CJ54"  !CDS_PN = "CJ54";
"VDDIO_CK57":   PN = "CK57"  !CDS_PN = "CK57";
"VDDIO_CK64":   PN = "CK64"  !CDS_PN = "CK64";
"VDDIO_CK71":   PN = "CK71"  !CDS_PN = "CK71";
"VDDIO_CM54":   PN = "CM54"  !CDS_PN = "CM54";
"VDDIO_CN58":   PN = "CN58"  !CDS_PN = "CN58";
"VDDIO_CN65":   PN = "CN65"  !CDS_PN = "CN65";
"VDDIO_CN72":   PN = "CN72"  !CDS_PN = "CN72";
"VDDIO_CT54":   PN = "CT54"  !CDS_PN = "CT54";
"VDDIO_CT57":   PN = "CT57"  !CDS_PN = "CT57";
"VDDIO_CT64":   PN = "CT64"  !CDS_PN = "CT64";
"VDDIO_CT71":   PN = "CT71"  !CDS_PN = "CT71";
"VDDIO_CW58":   PN = "CW58"  !CDS_PN = "CW58";
"VDDIO_CW65":   PN = "CW65"  !CDS_PN = "CW65";
"VDDIO_CW72":   PN = "CW72"  !CDS_PN = "CW72";
"VDDIO_CY54":   PN = "CY54"  !CDS_PN = "CY54";
"VDDIO_DB57":   PN = "DB57"  !CDS_PN = "DB57";
"VDDIO_DB64":   PN = "DB64"  !CDS_PN = "DB64";
"VDDIO_DB71":   PN = "DB71"  !CDS_PN = "DB71";
"VDDIO_DE58":   PN = "DE58"  !CDS_PN = "DE58";
"VDDIO_DE65":   PN = "DE65"  !CDS_PN = "DE65";
"VDDIO_DE72":   PN = "DE72"  !CDS_PN = "DE72";
"VDDIO_DG64":   PN = "DG64"  !CDS_PN = "DG64";
"VDDIO_DG71":   PN = "DG71"  !CDS_PN = "DG71";
"VDDIO_H57":   PN = "H57"  !CDS_PN = "H57";
"VDDIO_H64":   PN = "H64"  !CDS_PN = "H64";
"VDDIO_H71":   PN = "H71"  !CDS_PN = "H71";
"VDDIO_K54":   PN = "K54"  !CDS_PN = "K54";
"VDDIO_L58":   PN = "L58"  !CDS_PN = "L58";
"VDDIO_L65":   PN = "L65"  !CDS_PN = "L65";
"VDDIO_L72":   PN = "L72"  !CDS_PN = "L72";
"VDDIO_P54":   PN = "P54"  !CDS_PN = "P54";
"VDDIO_P57":   PN = "P57"  !CDS_PN = "P57";
"VDDIO_P64":   PN = "P64"  !CDS_PN = "P64";
"VDDIO_P71":   PN = "P71"  !CDS_PN = "P71";
"VDDIO_U58":   PN = "U58"  !CDS_PN = "U58";
"VDDIO_U65":   PN = "U65"  !CDS_PN = "U65";
"VDDIO_U72":   PN = "U72"  !CDS_PN = "U72";
"VDDIO_V54":   PN = "V54"  !CDS_PN = "V54";
"VDDIO_Y57":   PN = "Y57"  !CDS_PN = "Y57";
"VDDIO_Y64":   PN = "Y64"  !CDS_PN = "Y64";
"VDDIO_Y71":   PN = "Y71"  !CDS_PN = "Y71";
BODY = "GENOA_SP5","I46": #LOCATION = "U26" !CDS_LOCATION = "U26" &SEC = "23" #&CDS_SEC = "23";
"RSVD_A31":   PN = "A31"  !CDS_PN = "A31";
"RSVD_A35":   PN = "A35"  !CDS_PN = "A35";
"RSVD_A41":   PN = "A41"  !CDS_PN = "A41";
"RSVD_A42":   PN = "A42"  !CDS_PN = "A42";
"RSVD_A45":   PN = "A45"  !CDS_PN = "A45";
"RSVD_A48":   PN = "A48"  !CDS_PN = "A48";
"RSVD_A50":   PN = "A50"  !CDS_PN = "A50";
"RSVD_A51":   PN = "A51"  !CDS_PN = "A51";
"RSVD_A54":   PN = "A54"  !CDS_PN = "A54";
"RSVD_A55":   PN = "A55"  !CDS_PN = "A55";
"RSVD_A56":   PN = "A56"  !CDS_PN = "A56";
"RSVD_A57":   PN = "A57"  !CDS_PN = "A57";
"RSVD_A59":   PN = "A59"  !CDS_PN = "A59";
"RSVD_A60":   PN = "A60"  !CDS_PN = "A60";
"RSVD_B40":   PN = "B40"  !CDS_PN = "B40";
"RSVD_BD4":   PN = "BD4"  !CDS_PN = "BD4";
"RSVD_BD7":   PN = "BD7"  !CDS_PN = "BD7";
"RSVD_BD11":   PN = "BD11"  !CDS_PN = "BD11";
"RSVD_BD14":   PN = "BD14"  !CDS_PN = "BD14";
"RSVD_BD18":   PN = "BD18"  !CDS_PN = "BD18";
"RSVD_BD21":   PN = "BD21"  !CDS_PN = "BD21";
"RSVD_BD55":   PN = "BD55"  !CDS_PN = "BD55";
"RSVD_BD58":   PN = "BD58"  !CDS_PN = "BD58";
"RSVD_BD62":   PN = "BD62"  !CDS_PN = "BD62";
"RSVD_BD65":   PN = "BD65"  !CDS_PN = "BD65";
"RSVD_BD69":   PN = "BD69"  !CDS_PN = "BD69";
"RSVD_BD72":   PN = "BD72"  !CDS_PN = "BD72";
"RSVD_C31":   PN = "C31"  !CDS_PN = "C31";
"RSVD_C34":   PN = "C34"  !CDS_PN = "C34";
"RSVD_C35":   PN = "C35"  !CDS_PN = "C35";
"RSVD_C53":   PN = "C53"  !CDS_PN = "C53";
"RSVD_C54":   PN = "C54"  !CDS_PN = "C54";
"RSVD_D4":   PN = "D4"  !CDS_PN = "D4";
"RSVD_D8":   PN = "D8"  !CDS_PN = "D8";
"RSVD_D11":   PN = "D11"  !CDS_PN = "D11";
"RSVD_D22":   PN = "D22"  !CDS_PN = "D22";
"RSVD_D34":   PN = "D34"  !CDS_PN = "D34";
"RSVD_D36":   PN = "D36"  !CDS_PN = "D36";
"RSVD_D58":   PN = "D58"  !CDS_PN = "D58";
"RSVD_D62":   PN = "D62"  !CDS_PN = "D62";
"RSVD_D65":   PN = "D65"  !CDS_PN = "D65";
"RSVD_D72":   PN = "D72"  !CDS_PN = "D72";
"RSVD_DG17":   PN = "DG17"  !CDS_PN = "DG17";
"RSVD_DH17":   PN = "DH17"  !CDS_PN = "DH17";
"RSVD_DH21":   PN = "DH21"  !CDS_PN = "DH21";
"RSVD_DJ4":   PN = "DJ4"  !CDS_PN = "DJ4";
"RSVD_E33":   PN = "E33"  !CDS_PN = "E33";
"RSVD_E36":   PN = "E36"  !CDS_PN = "E36";
"TEST4_CCD12":   PN = "C58"  !CDS_PN = "C58";
"TEST4_CCD13":   PN = "DH13"  !CDS_PN = "DH13";
"TEST4_CCD14":   PN = "DF41"  !CDS_PN = "DF41";
"TEST4_CCD15":   PN = "C23"  !CDS_PN = "C23";
"TEST5_CCD12":   PN = "C59"  !CDS_PN = "C59";
"TEST5_CCD13":   PN = "DH14"  !CDS_PN = "DH14";
"TEST5_CCD14":   PN = "DG42"  !CDS_PN = "DG42";
"TEST5_CCD15":   PN = "D23"  !CDS_PN = "D23";
"TEST6_X3D6":   PN = "B36"  !CDS_PN = "B36";
"TEST6_X3D7":   PN = "DJ57"  !CDS_PN = "DJ57";
BODY = "GENOA_SP5","I49": #LOCATION = "U26" !CDS_LOCATION = "U26" &SEC = "26" #&CDS_SEC = "26";
"VDDCR_SOC_AA22":   PN = "AA22"  !CDS_PN = "AA22";
"VDDCR_SOC_AC4":   PN = "AC4"  !CDS_PN = "AC4";
"VDDCR_SOC_AC11":   PN = "AC11"  !CDS_PN = "AC11";
"VDDCR_SOC_AC18":   PN = "AC18"  !CDS_PN = "AC18";
"VDDCR_SOC_AD22":   PN = "AD22"  !CDS_PN = "AD22";
"VDDCR_SOC_AF5":   PN = "AF5"  !CDS_PN = "AF5";
"VDDCR_SOC_AF12":   PN = "AF12"  !CDS_PN = "AF12";
"VDDCR_SOC_AF19":   PN = "AF19"  !CDS_PN = "AF19";
"VDDCR_SOC_AH22":   PN = "AH22"  !CDS_PN = "AH22";
"VDDCR_SOC_AJ4":   PN = "AJ4"  !CDS_PN = "AJ4";
"VDDCR_SOC_AJ11":   PN = "AJ11"  !CDS_PN = "AJ11";
"VDDCR_SOC_AJ18":   PN = "AJ18"  !CDS_PN = "AJ18";
"VDDCR_SOC_AM5":   PN = "AM5"  !CDS_PN = "AM5";
"VDDCR_SOC_AM12":   PN = "AM12"  !CDS_PN = "AM12";
"VDDCR_SOC_AM19":   PN = "AM19"  !CDS_PN = "AM19";
"VDDCR_SOC_AM22":   PN = "AM22"  !CDS_PN = "AM22";
"VDDCR_SOC_AR4":   PN = "AR4"  !CDS_PN = "AR4";
"VDDCR_SOC_AR11":   PN = "AR11"  !CDS_PN = "AR11";
"VDDCR_SOC_AR18":   PN = "AR18"  !CDS_PN = "AR18";
"VDDCR_SOC_AT22":   PN = "AT22"  !CDS_PN = "AT22";
"VDDCR_SOC_AU23":   PN = "AU23"  !CDS_PN = "AU23";
"VDDCR_SOC_AU27":   PN = "AU27"  !CDS_PN = "AU27";
"VDDCR_SOC_AU31":   PN = "AU31"  !CDS_PN = "AU31";
"VDDCR_SOC_AU35":   PN = "AU35"  !CDS_PN = "AU35";
"VDDCR_SOC_AU40":   PN = "AU40"  !CDS_PN = "AU40";
"VDDCR_SOC_AV5":   PN = "AV5"  !CDS_PN = "AV5";
"VDDCR_SOC_AV12":   PN = "AV12"  !CDS_PN = "AV12";
"VDDCR_SOC_AV19":   PN = "AV19"  !CDS_PN = "AV19";
"VDDCR_SOC_AV22":   PN = "AV22"  !CDS_PN = "AV22";
"VDDCR_SOC_AV24":   PN = "AV24"  !CDS_PN = "AV24";
"VDDCR_SOC_AV26":   PN = "AV26"  !CDS_PN = "AV26";
"VDDCR_SOC_AV28":   PN = "AV28"  !CDS_PN = "AV28";
"VDDCR_SOC_AV30":   PN = "AV30"  !CDS_PN = "AV30";
"VDDCR_SOC_AV32":   PN = "AV32"  !CDS_PN = "AV32";
"VDDCR_SOC_AV34":   PN = "AV34"  !CDS_PN = "AV34";
"VDDCR_SOC_AV36":   PN = "AV36"  !CDS_PN = "AV36";
"VDDCR_SOC_AV39":   PN = "AV39"  !CDS_PN = "AV39";
"VDDCR_SOC_AV41":   PN = "AV41"  !CDS_PN = "AV41";
"VDDCR_SOC_AV43":   PN = "AV43"  !CDS_PN = "AV43";
"VDDCR_SOC_AV45":   PN = "AV45"  !CDS_PN = "AV45";
"VDDCR_SOC_AV47":   PN = "AV47"  !CDS_PN = "AV47";
"VDDCR_SOC_AW23":   PN = "AW23"  !CDS_PN = "AW23";
"VDDCR_SOC_AW25":   PN = "AW25"  !CDS_PN = "AW25";
"VDDCR_SOC_AW27":   PN = "AW27"  !CDS_PN = "AW27";
"VDDCR_SOC_AW48":   PN = "AW48"  !CDS_PN = "AW48";
"VDDCR_SOC_AY22":   PN = "AY22"  !CDS_PN = "AY22";
"VDDCR_SOC_AY24":   PN = "AY24"  !CDS_PN = "AY24";
"VDDCR_SOC_AY26":   PN = "AY26"  !CDS_PN = "AY26";
"VDDCR_SOC_AY28":   PN = "AY28"  !CDS_PN = "AY28";
"VDDCR_SOC_AY49":   PN = "AY49"  !CDS_PN = "AY49";
"VDDCR_SOC_B5":   PN = "B5"  !CDS_PN = "B5";
"VDDCR_SOC_BA4":   PN = "BA4"  !CDS_PN = "BA4";
"VDDCR_SOC_BA11":   PN = "BA11"  !CDS_PN = "BA11";
"VDDCR_SOC_BA18":   PN = "BA18"  !CDS_PN = "BA18";
"VDDCR_SOC_BA23":   PN = "BA23"  !CDS_PN = "BA23";
"VDDCR_SOC_BA25":   PN = "BA25"  !CDS_PN = "BA25";
"VDDCR_SOC_BA27":   PN = "BA27"  !CDS_PN = "BA27";
"VDDCR_SOC_BA48":   PN = "BA48"  !CDS_PN = "BA48";
"VDDCR_SOC_BB22":   PN = "BB22"  !CDS_PN = "BB22";
"VDDCR_SOC_BB24":   PN = "BB24"  !CDS_PN = "BB24";
"VDDCR_SOC_BB26":   PN = "BB26"  !CDS_PN = "BB26";
"VDDCR_SOC_BB28":   PN = "BB28"  !CDS_PN = "BB28";
"VDDCR_SOC_BB49":   PN = "BB49"  !CDS_PN = "BB49";
"VDDCR_SOC_BC23":   PN = "BC23"  !CDS_PN = "BC23";
"VDDCR_SOC_BC25":   PN = "BC25"  !CDS_PN = "BC25";
"VDDCR_SOC_BC27":   PN = "BC27"  !CDS_PN = "BC27";
"VDDCR_SOC_BC48":   PN = "BC48"  !CDS_PN = "BC48";
"VDDCR_SOC_BD5":   PN = "BD5"  !CDS_PN = "BD5";
"VDDCR_SOC_BD12":   PN = "BD12"  !CDS_PN = "BD12";
"VDDCR_SOC_BD19":   PN = "BD19"  !CDS_PN = "BD19";
"VDDCR_SOC_BD22":   PN = "BD22"  !CDS_PN = "BD22";
"VDDCR_SOC_BD24":   PN = "BD24"  !CDS_PN = "BD24";
"VDDCR_SOC_BD26":   PN = "BD26"  !CDS_PN = "BD26";
"VDDCR_SOC_BD28":   PN = "BD28"  !CDS_PN = "BD28";
"VDDCR_SOC_BD48":   PN = "BD48"  !CDS_PN = "BD48";
"VDDCR_SOC_BF23":   PN = "BF23"  !CDS_PN = "BF23";
"VDDCR_SOC_BF25":   PN = "BF25"  !CDS_PN = "BF25";
"VDDCR_SOC_BF27":   PN = "BF27"  !CDS_PN = "BF27";
"VDDCR_SOC_BF48":   PN = "BF48"  !CDS_PN = "BF48";
"VDDCR_SOC_BG22":   PN = "BG22"  !CDS_PN = "BG22";
"VDDCR_SOC_BG24":   PN = "BG24"  !CDS_PN = "BG24";
"VDDCR_SOC_BG26":   PN = "BG26"  !CDS_PN = "BG26";
"VDDCR_SOC_BG28":   PN = "BG28"  !CDS_PN = "BG28";
"VDDCR_SOC_BG48":   PN = "BG48"  !CDS_PN = "BG48";
"VDDCR_SOC_BH23":   PN = "BH23"  !CDS_PN = "BH23";
"VDDCR_SOC_BH25":   PN = "BH25"  !CDS_PN = "BH25";
"VDDCR_SOC_BH48":   PN = "BH48"  !CDS_PN = "BH48";
"VDDCR_SOC_BJ4":   PN = "BJ4"  !CDS_PN = "BJ4";
"VDDCR_SOC_BJ11":   PN = "BJ11"  !CDS_PN = "BJ11";
"VDDCR_SOC_BJ48":   PN = "BJ48"  !CDS_PN = "BJ48";
"VDDCR_SOC_BM5":   PN = "BM5"  !CDS_PN = "BM5";
"VDDCR_SOC_C4":   PN = "C4"  !CDS_PN = "C4";
"VDDCR_SOC_E4":   PN = "E4"  !CDS_PN = "E4";
"VDDCR_SOC_E11":   PN = "E11"  !CDS_PN = "E11";
"VDDCR_SOC_H5":   PN = "H5"  !CDS_PN = "H5";
"VDDCR_SOC_H12":   PN = "H12"  !CDS_PN = "H12";
"VDDCR_SOC_H19":   PN = "H19"  !CDS_PN = "H19";
"VDDCR_SOC_K22":   PN = "K22"  !CDS_PN = "K22";
"VDDCR_SOC_L4":   PN = "L4"  !CDS_PN = "L4";
"VDDCR_SOC_L11":   PN = "L11"  !CDS_PN = "L11";
"VDDCR_SOC_L18":   PN = "L18"  !CDS_PN = "L18";
"VDDCR_SOC_P5":   PN = "P5"  !CDS_PN = "P5";
"VDDCR_SOC_P12":   PN = "P12"  !CDS_PN = "P12";
"VDDCR_SOC_P19":   PN = "P19"  !CDS_PN = "P19";
"VDDCR_SOC_P22":   PN = "P22"  !CDS_PN = "P22";
"VDDCR_SOC_U4":   PN = "U4"  !CDS_PN = "U4";
"VDDCR_SOC_U11":   PN = "U11"  !CDS_PN = "U11";
"VDDCR_SOC_U18":   PN = "U18"  !CDS_PN = "U18";
"VDDCR_SOC_V22":   PN = "V22"  !CDS_PN = "V22";
"VDDCR_SOC_Y5":   PN = "Y5"  !CDS_PN = "Y5";
"VDDCR_SOC_Y12":   PN = "Y12"  !CDS_PN = "Y12";
"VDDCR_SOC_Y19":   PN = "Y19"  !CDS_PN = "Y19";
BODY = "Q_RES","I51": #LOCATION = "R374" !CDS_LOCATION = "R374" &SEC = "1" #&CDS_SEC = "1";
"A":   PN = "1"  !CDS_PN = "1";
"B":   PN = "2"  !CDS_PN = "2";
BODY = "Q_RES","I52": #LOCATION = "R373" !CDS_LOCATION = "R373" &SEC = "1" #&CDS_SEC = "1";
"A":   PN = "1"  !CDS_PN = "1";
"B":   PN = "2"  !CDS_PN = "2";
DRAWING = "@t6g_mb_lib.t6g(sch_1):page58";
BODY = "GENOA_SP5","I1": #LOCATION = "U26" !CDS_LOCATION = "U26" &SEC = "28" #&CDS_SEC = "28";
"VSS_A3":   PN = "A3"  !CDS_PN = "A3";
"VSS_A9":   PN = "A9"  !CDS_PN = "A9";
"VSS_A15":   PN = "A15"  !CDS_PN = "A15";
"VSS_A21":   PN = "A21"  !CDS_PN = "A21";
"VSS_A27":   PN = "A27"  !CDS_PN = "A27";
"VSS_A43":   PN = "A43"  !CDS_PN = "A43";
"VSS_A44":   PN = "A44"  !CDS_PN = "A44";
"VSS_A47":   PN = "A47"  !CDS_PN = "A47";
"VSS_A49":   PN = "A49"  !CDS_PN = "A49";
"VSS_A53":   PN = "A53"  !CDS_PN = "A53";
"VSS_A61":   PN = "A61"  !CDS_PN = "A61";
"VSS_A67":   PN = "A67"  !CDS_PN = "A67";
"VSS_A72":   PN = "A72"  !CDS_PN = "A72";
"VSS_A73":   PN = "A73"  !CDS_PN = "A73";
"VSS_B7":   PN = "B7"  !CDS_PN = "B7";
"VSS_B8":   PN = "B8"  !CDS_PN = "B8";
"VSS_B10":   PN = "B10"  !CDS_PN = "B10";
"VSS_B11":   PN = "B11"  !CDS_PN = "B11";
"VSS_B13":   PN = "B13"  !CDS_PN = "B13";
"VSS_B18":   PN = "B18"  !CDS_PN = "B18";
"VSS_B24":   PN = "B24"  !CDS_PN = "B24";
"VSS_B27":   PN = "B27"  !CDS_PN = "B27";
"VSS_B30":   PN = "B30"  !CDS_PN = "B30";
"VSS_B33":   PN = "B33"  !CDS_PN = "B33";
"VSS_B37":   PN = "B37"  !CDS_PN = "B37";
"VSS_B39":   PN = "B39"  !CDS_PN = "B39";
"VSS_B43":   PN = "B43"  !CDS_PN = "B43";
"VSS_B46":   PN = "B46"  !CDS_PN = "B46";
"VSS_B49":   PN = "B49"  !CDS_PN = "B49";
"VSS_B52":   PN = "B52"  !CDS_PN = "B52";
"VSS_B55":   PN = "B55"  !CDS_PN = "B55";
"VSS_B59":   PN = "B59"  !CDS_PN = "B59";
"VSS_B62":   PN = "B62"  !CDS_PN = "B62";
"VSS_B65":   PN = "B65"  !CDS_PN = "B65";
"VSS_B68":   PN = "B68"  !CDS_PN = "B68";
"VSS_B70":   PN = "B70"  !CDS_PN = "B70";
"VSS_C1":   PN = "C1"  !CDS_PN = "C1";
"VSS_C5":   PN = "C5"  !CDS_PN = "C5";
"VSS_C8":   PN = "C8"  !CDS_PN = "C8";
"VSS_C10":   PN = "C10"  !CDS_PN = "C10";
"VSS_C11":   PN = "C11"  !CDS_PN = "C11";
"VSS_C13":   PN = "C13"  !CDS_PN = "C13";
"VSS_C15":   PN = "C15"  !CDS_PN = "C15";
"VSS_C21":   PN = "C21"  !CDS_PN = "C21";
"VSS_C24":   PN = "C24"  !CDS_PN = "C24";
"VSS_C27":   PN = "C27"  !CDS_PN = "C27";
"VSS_C30":   PN = "C30"  !CDS_PN = "C30";
"VSS_C36":   PN = "C36"  !CDS_PN = "C36";
"VSS_C40":   PN = "C40"  !CDS_PN = "C40";
"VSS_C43":   PN = "C43"  !CDS_PN = "C43";
"VSS_C46":   PN = "C46"  !CDS_PN = "C46";
"VSS_C49":   PN = "C49"  !CDS_PN = "C49";
"VSS_C52":   PN = "C52"  !CDS_PN = "C52";
"VSS_C55":   PN = "C55"  !CDS_PN = "C55";
"VSS_C56":   PN = "C56"  !CDS_PN = "C56";
"VSS_C57":   PN = "C57"  !CDS_PN = "C57";
"VSS_C61":   PN = "C61"  !CDS_PN = "C61";
"VSS_C64":   PN = "C64"  !CDS_PN = "C64";
"VSS_C67":   PN = "C67"  !CDS_PN = "C67";
"VSS_C69":   PN = "C69"  !CDS_PN = "C69";
"VSS_C71":   PN = "C71"  !CDS_PN = "C71";
"VSS_C73":   PN = "C73"  !CDS_PN = "C73";
"VSS_C75":   PN = "C75"  !CDS_PN = "C75";
"VSS_D2":   PN = "D2"  !CDS_PN = "D2";
"VSS_D3":   PN = "D3"  !CDS_PN = "D3";
"VSS_D5":   PN = "D5"  !CDS_PN = "D5";
"VSS_D6":   PN = "D6"  !CDS_PN = "D6";
"VSS_D9":   PN = "D9"  !CDS_PN = "D9";
"VSS_D10":   PN = "D10"  !CDS_PN = "D10";
"VSS_D12":   PN = "D12"  !CDS_PN = "D12";
"VSS_D13":   PN = "D13"  !CDS_PN = "D13";
"VSS_D16":   PN = "D16"  !CDS_PN = "D16";
"VSS_D17":   PN = "D17"  !CDS_PN = "D17";
"VSS_D19":   PN = "D19"  !CDS_PN = "D19";
"VSS_D20":   PN = "D20"  !CDS_PN = "D20";
"VSS_D21":   PN = "D21"  !CDS_PN = "D21";
"VSS_D24":   PN = "D24"  !CDS_PN = "D24";
"VSS_D25":   PN = "D25"  !CDS_PN = "D25";
"VSS_D26":   PN = "D26"  !CDS_PN = "D26";
"VSS_D27":   PN = "D27"  !CDS_PN = "D27";
"VSS_D28":   PN = "D28"  !CDS_PN = "D28";
"VSS_D29":   PN = "D29"  !CDS_PN = "D29";
"VSS_D30":   PN = "D30"  !CDS_PN = "D30";
"VSS_D31":   PN = "D31"  !CDS_PN = "D31";
"VSS_D35":   PN = "D35"  !CDS_PN = "D35";
"VSS_D37":   PN = "D37"  !CDS_PN = "D37";
"VSS_D39":   PN = "D39"  !CDS_PN = "D39";
"VSS_D40":   PN = "D40"  !CDS_PN = "D40";
"VSS_D41":   PN = "D41"  !CDS_PN = "D41";
"VSS_D42":   PN = "D42"  !CDS_PN = "D42";
"VSS_D43":   PN = "D43"  !CDS_PN = "D43";
"VSS_D44":   PN = "D44"  !CDS_PN = "D44";
"VSS_D45":   PN = "D45"  !CDS_PN = "D45";
"VSS_D46":   PN = "D46"  !CDS_PN = "D46";
"VSS_D47":   PN = "D47"  !CDS_PN = "D47";
"VSS_D48":   PN = "D48"  !CDS_PN = "D48";
"VSS_D49":   PN = "D49"  !CDS_PN = "D49";
"VSS_D50":   PN = "D50"  !CDS_PN = "D50";
"VSS_D51":   PN = "D51"  !CDS_PN = "D51";
"VSS_D52":   PN = "D52"  !CDS_PN = "D52";
"VSS_D53":   PN = "D53"  !CDS_PN = "D53";
"VSS_D54":   PN = "D54"  !CDS_PN = "D54";
"VSS_D57":   PN = "D57"  !CDS_PN = "D57";
"VSS_D59":   PN = "D59"  !CDS_PN = "D59";
"VSS_D60":   PN = "D60"  !CDS_PN = "D60";
"VSS_D61":   PN = "D61"  !CDS_PN = "D61";
"VSS_D63":   PN = "D63"  !CDS_PN = "D63";
"VSS_D64":   PN = "D64"  !CDS_PN = "D64";
"VSS_D66":   PN = "D66"  !CDS_PN = "D66";
"VSS_D67":   PN = "D67"  !CDS_PN = "D67";
"VSS_D70":   PN = "D70"  !CDS_PN = "D70";
"VSS_D71":   PN = "D71"  !CDS_PN = "D71";
"VSS_D73":   PN = "D73"  !CDS_PN = "D73";
"VSS_D74":   PN = "D74"  !CDS_PN = "D74";
"VSS_E1":   PN = "E1"  !CDS_PN = "E1";
"VSS_E3":   PN = "E3"  !CDS_PN = "E3";
"VSS_E6":   PN = "E6"  !CDS_PN = "E6";
"VSS_E7":   PN = "E7"  !CDS_PN = "E7";
"VSS_E8":   PN = "E8"  !CDS_PN = "E8";
"VSS_E10":   PN = "E10"  !CDS_PN = "E10";
"VSS_E13":   PN = "E13"  !CDS_PN = "E13";
"VSS_E14":   PN = "E14"  !CDS_PN = "E14";
"VSS_E15":   PN = "E15"  !CDS_PN = "E15";
"VSS_E17":   PN = "E17"  !CDS_PN = "E17";
"VSS_E18":   PN = "E18"  !CDS_PN = "E18";
"VSS_E20":   PN = "E20"  !CDS_PN = "E20";
"VSS_E21":   PN = "E21"  !CDS_PN = "E21";
"VSS_E52":   PN = "E52"  !CDS_PN = "E52";
"VSS_E53":   PN = "E53"  !CDS_PN = "E53";
"VSS_E55":   PN = "E55"  !CDS_PN = "E55";
"VSS_E56":   PN = "E56"  !CDS_PN = "E56";
"VSS_E58":   PN = "E58"  !CDS_PN = "E58";
"VSS_E59":   PN = "E59"  !CDS_PN = "E59";
"VSS_E61":   PN = "E61"  !CDS_PN = "E61";
"VSS_E62":   PN = "E62"  !CDS_PN = "E62";
"VSS_E63":   PN = "E63"  !CDS_PN = "E63";
"VSS_E65":   PN = "E65"  !CDS_PN = "E65";
"VSS_E66":   PN = "E66"  !CDS_PN = "E66";
"VSS_E68":   PN = "E68"  !CDS_PN = "E68";
"VSS_E69":   PN = "E69"  !CDS_PN = "E69";
"VSS_E70":   PN = "E70"  !CDS_PN = "E70";
"VSS_E72":   PN = "E72"  !CDS_PN = "E72";
"VSS_E73":   PN = "E73"  !CDS_PN = "E73";
"VSS_E75":   PN = "E75"  !CDS_PN = "E75";
"VSS_F3":   PN = "F3"  !CDS_PN = "F3";
"VSS_F5":   PN = "F5"  !CDS_PN = "F5";
"VSS_F8":   PN = "F8"  !CDS_PN = "F8";
"VSS_F10":   PN = "F10"  !CDS_PN = "F10";
"VSS_F12":   PN = "F12"  !CDS_PN = "F12";
"VSS_F15":   PN = "F15"  !CDS_PN = "F15";
"VSS_F17":   PN = "F17"  !CDS_PN = "F17";
"VSS_F19":   PN = "F19"  !CDS_PN = "F19";
"VSS_F23":   PN = "F23"  !CDS_PN = "F23";
"VSS_F24":   PN = "F24"  !CDS_PN = "F24";
"VSS_F26":   PN = "F26"  !CDS_PN = "F26";
"VSS_F27":   PN = "F27"  !CDS_PN = "F27";
"VSS_F29":   PN = "F29"  !CDS_PN = "F29";
"VSS_F30":   PN = "F30"  !CDS_PN = "F30";
"VSS_F32":   PN = "F32"  !CDS_PN = "F32";
"VSS_F33":   PN = "F33"  !CDS_PN = "F33";
"VSS_F35":   PN = "F35"  !CDS_PN = "F35";
"VSS_F36":   PN = "F36"  !CDS_PN = "F36";
"VSS_F37":   PN = "F37"  !CDS_PN = "F37";
"VSS_F39":   PN = "F39"  !CDS_PN = "F39";
"VSS_F40":   PN = "F40"  !CDS_PN = "F40";
"VSS_F41":   PN = "F41"  !CDS_PN = "F41";
"VSS_F43":   PN = "F43"  !CDS_PN = "F43";
"VSS_F44":   PN = "F44"  !CDS_PN = "F44";
"VSS_F46":   PN = "F46"  !CDS_PN = "F46";
"VSS_F47":   PN = "F47"  !CDS_PN = "F47";
"VSS_F49":   PN = "F49"  !CDS_PN = "F49";
"VSS_F50":   PN = "F50"  !CDS_PN = "F50";
"VSS_F52":   PN = "F52"  !CDS_PN = "F52";
"VSS_F53":   PN = "F53"  !CDS_PN = "F53";
"VSS_F57":   PN = "F57"  !CDS_PN = "F57";
"VSS_F59":   PN = "F59"  !CDS_PN = "F59";
"VSS_F61":   PN = "F61"  !CDS_PN = "F61";
"VSS_F64":   PN = "F64"  !CDS_PN = "F64";
"VSS_F66":   PN = "F66"  !CDS_PN = "F66";
"VSS_F68":   PN = "F68"  !CDS_PN = "F68";
"VSS_F71":   PN = "F71"  !CDS_PN = "F71";
"VSS_F73":   PN = "F73"  !CDS_PN = "F73";
"VSS_G1":   PN = "G1"  !CDS_PN = "G1";
"VSS_G4":   PN = "G4"  !CDS_PN = "G4";
"VSS_G6":   PN = "G6"  !CDS_PN = "G6";
"VSS_G8":   PN = "G8"  !CDS_PN = "G8";
"VSS_G11":   PN = "G11"  !CDS_PN = "G11";
"VSS_G13":   PN = "G13"  !CDS_PN = "G13";
"VSS_G15":   PN = "G15"  !CDS_PN = "G15";
"VSS_G18":   PN = "G18"  !CDS_PN = "G18";
"VSS_G20":   PN = "G20"  !CDS_PN = "G20";
"VSS_G22":   PN = "G22"  !CDS_PN = "G22";
"VSS_G25":   PN = "G25"  !CDS_PN = "G25";
"VSS_G28":   PN = "G28"  !CDS_PN = "G28";
"VSS_G31":   PN = "G31"  !CDS_PN = "G31";
"VSS_G34":   PN = "G34"  !CDS_PN = "G34";
"VSS_G42":   PN = "G42"  !CDS_PN = "G42";
"VSS_G45":   PN = "G45"  !CDS_PN = "G45";
"VSS_G48":   PN = "G48"  !CDS_PN = "G48";
"VSS_G51":   PN = "G51"  !CDS_PN = "G51";
"VSS_G54":   PN = "G54"  !CDS_PN = "G54";
"VSS_G56":   PN = "G56"  !CDS_PN = "G56";
"VSS_G58":   PN = "G58"  !CDS_PN = "G58";
"VSS_G61":   PN = "G61"  !CDS_PN = "G61";
"VSS_G63":   PN = "G63"  !CDS_PN = "G63";
"VSS_G65":   PN = "G65"  !CDS_PN = "G65";
"VSS_G68":   PN = "G68"  !CDS_PN = "G68";
"VSS_G70":   PN = "G70"  !CDS_PN = "G70";
"VSS_G72":   PN = "G72"  !CDS_PN = "G72";
"VSS_G75":   PN = "G75"  !CDS_PN = "G75";
"VSS_H3":   PN = "H3"  !CDS_PN = "H3";
"VSS_H8":   PN = "H8"  !CDS_PN = "H8";
"VSS_H10":   PN = "H10"  !CDS_PN = "H10";
"VSS_H15":   PN = "H15"  !CDS_PN = "H15";
"VSS_H17":   PN = "H17"  !CDS_PN = "H17";
"VSS_H22":   PN = "H22"  !CDS_PN = "H22";
"VSS_H25":   PN = "H25"  !CDS_PN = "H25";
"VSS_H28":   PN = "H28"  !CDS_PN = "H28";
"VSS_H31":   PN = "H31"  !CDS_PN = "H31";
"VSS_H34":   PN = "H34"  !CDS_PN = "H34";
"VSS_H37":   PN = "H37"  !CDS_PN = "H37";
"VSS_H39":   PN = "H39"  !CDS_PN = "H39";
"VSS_H42":   PN = "H42"  !CDS_PN = "H42";
"VSS_H45":   PN = "H45"  !CDS_PN = "H45";
"VSS_H48":   PN = "H48"  !CDS_PN = "H48";
"VSS_H51":   PN = "H51"  !CDS_PN = "H51";
"VSS_H54":   PN = "H54"  !CDS_PN = "H54";
"VSS_H59":   PN = "H59"  !CDS_PN = "H59";
"VSS_H61":   PN = "H61"  !CDS_PN = "H61";
"VSS_H66":   PN = "H66"  !CDS_PN = "H66";
"VSS_H68":   PN = "H68"  !CDS_PN = "H68";
"VSS_H73":   PN = "H73"  !CDS_PN = "H73";
"VSS_J1":   PN = "J1"  !CDS_PN = "J1";
"VSS_J4":   PN = "J4"  !CDS_PN = "J4";
"VSS_J6":   PN = "J6"  !CDS_PN = "J6";
"VSS_J8":   PN = "J8"  !CDS_PN = "J8";
"VSS_J11":   PN = "J11"  !CDS_PN = "J11";
"VSS_J13":   PN = "J13"  !CDS_PN = "J13";
BODY = "GENOA_SP5","I3": #LOCATION = "U26" !CDS_LOCATION = "U26" &SEC = "33" #&CDS_SEC = "33";
"VSS_AW63":   PN = "AW63"  !CDS_PN = "AW63";
"VSS_AW65":   PN = "AW65"  !CDS_PN = "AW65";
"VSS_AW68":   PN = "AW68"  !CDS_PN = "AW68";
"VSS_AW70":   PN = "AW70"  !CDS_PN = "AW70";
"VSS_AW72":   PN = "AW72"  !CDS_PN = "AW72";
"VSS_AW75":   PN = "AW75"  !CDS_PN = "AW75";
"VSS_AY3":   PN = "AY3"  !CDS_PN = "AY3";
"VSS_AY5":   PN = "AY5"  !CDS_PN = "AY5";
"VSS_AY8":   PN = "AY8"  !CDS_PN = "AY8";
"VSS_AY10":   PN = "AY10"  !CDS_PN = "AY10";
"VSS_AY12":   PN = "AY12"  !CDS_PN = "AY12";
"VSS_AY15":   PN = "AY15"  !CDS_PN = "AY15";
"VSS_AY17":   PN = "AY17"  !CDS_PN = "AY17";
"VSS_AY19":   PN = "AY19"  !CDS_PN = "AY19";
"VSS_AY23":   PN = "AY23"  !CDS_PN = "AY23";
"VSS_AY25":   PN = "AY25"  !CDS_PN = "AY25";
"VSS_AY27":   PN = "AY27"  !CDS_PN = "AY27";
"VSS_AY48":   PN = "AY48"  !CDS_PN = "AY48";
"VSS_AY50":   PN = "AY50"  !CDS_PN = "AY50";
"VSS_AY52":   PN = "AY52"  !CDS_PN = "AY52";
"VSS_AY54":   PN = "AY54"  !CDS_PN = "AY54";
"VSS_AY57":   PN = "AY57"  !CDS_PN = "AY57";
"VSS_AY59":   PN = "AY59"  !CDS_PN = "AY59";
"VSS_AY61":   PN = "AY61"  !CDS_PN = "AY61";
"VSS_AY64":   PN = "AY64"  !CDS_PN = "AY64";
"VSS_AY66":   PN = "AY66"  !CDS_PN = "AY66";
"VSS_AY68":   PN = "AY68"  !CDS_PN = "AY68";
"VSS_AY71":   PN = "AY71"  !CDS_PN = "AY71";
"VSS_AY73":   PN = "AY73"  !CDS_PN = "AY73";
"VSS_BA1":   PN = "BA1"  !CDS_PN = "BA1";
"VSS_BA6":   PN = "BA6"  !CDS_PN = "BA6";
"VSS_BA8":   PN = "BA8"  !CDS_PN = "BA8";
"VSS_BA13":   PN = "BA13"  !CDS_PN = "BA13";
"VSS_BA15":   PN = "BA15"  !CDS_PN = "BA15";
"VSS_BA20":   PN = "BA20"  !CDS_PN = "BA20";
"VSS_BA22":   PN = "BA22"  !CDS_PN = "BA22";
"VSS_BA24":   PN = "BA24"  !CDS_PN = "BA24";
"VSS_BA26":   PN = "BA26"  !CDS_PN = "BA26";
"VSS_BA28":   PN = "BA28"  !CDS_PN = "BA28";
"VSS_BA49":   PN = "BA49"  !CDS_PN = "BA49";
"VSS_BA51":   PN = "BA51"  !CDS_PN = "BA51";
"VSS_BA53":   PN = "BA53"  !CDS_PN = "BA53";
"VSS_BA56":   PN = "BA56"  !CDS_PN = "BA56";
"VSS_BA61":   PN = "BA61"  !CDS_PN = "BA61";
"VSS_BA63":   PN = "BA63"  !CDS_PN = "BA63";
"VSS_BA68":   PN = "BA68"  !CDS_PN = "BA68";
"VSS_BA70":   PN = "BA70"  !CDS_PN = "BA70";
"VSS_BA75":   PN = "BA75"  !CDS_PN = "BA75";
"VSS_BB3":   PN = "BB3"  !CDS_PN = "BB3";
"VSS_BB5":   PN = "BB5"  !CDS_PN = "BB5";
"VSS_BB8":   PN = "BB8"  !CDS_PN = "BB8";
"VSS_BB10":   PN = "BB10"  !CDS_PN = "BB10";
"VSS_BB12":   PN = "BB12"  !CDS_PN = "BB12";
"VSS_BB15":   PN = "BB15"  !CDS_PN = "BB15";
"VSS_BB17":   PN = "BB17"  !CDS_PN = "BB17";
"VSS_BB19":   PN = "BB19"  !CDS_PN = "BB19";
"VSS_BB23":   PN = "BB23"  !CDS_PN = "BB23";
"VSS_BB25":   PN = "BB25"  !CDS_PN = "BB25";
"VSS_BB27":   PN = "BB27"  !CDS_PN = "BB27";
"VSS_BB48":   PN = "BB48"  !CDS_PN = "BB48";
"VSS_BB50":   PN = "BB50"  !CDS_PN = "BB50";
"VSS_BB52":   PN = "BB52"  !CDS_PN = "BB52";
"VSS_BB54":   PN = "BB54"  !CDS_PN = "BB54";
"VSS_BB57":   PN = "BB57"  !CDS_PN = "BB57";
"VSS_BB59":   PN = "BB59"  !CDS_PN = "BB59";
"VSS_BB61":   PN = "BB61"  !CDS_PN = "BB61";
"VSS_BB64":   PN = "BB64"  !CDS_PN = "BB64";
"VSS_BB66":   PN = "BB66"  !CDS_PN = "BB66";
"VSS_BB68":   PN = "BB68"  !CDS_PN = "BB68";
"VSS_BB71":   PN = "BB71"  !CDS_PN = "BB71";
"VSS_BB73":   PN = "BB73"  !CDS_PN = "BB73";
"VSS_BC1":   PN = "BC1"  !CDS_PN = "BC1";
"VSS_BC4":   PN = "BC4"  !CDS_PN = "BC4";
"VSS_BC6":   PN = "BC6"  !CDS_PN = "BC6";
"VSS_BC8":   PN = "BC8"  !CDS_PN = "BC8";
"VSS_BC11":   PN = "BC11"  !CDS_PN = "BC11";
"VSS_BC13":   PN = "BC13"  !CDS_PN = "BC13";
"VSS_BC15":   PN = "BC15"  !CDS_PN = "BC15";
"VSS_BC18":   PN = "BC18"  !CDS_PN = "BC18";
"VSS_BC20":   PN = "BC20"  !CDS_PN = "BC20";
"VSS_BC22":   PN = "BC22"  !CDS_PN = "BC22";
"VSS_BC24":   PN = "BC24"  !CDS_PN = "BC24";
"VSS_BC26":   PN = "BC26"  !CDS_PN = "BC26";
"VSS_BC28":   PN = "BC28"  !CDS_PN = "BC28";
"VSS_BC49":   PN = "BC49"  !CDS_PN = "BC49";
"VSS_BC50":   PN = "BC50"  !CDS_PN = "BC50";
"VSS_BC51":   PN = "BC51"  !CDS_PN = "BC51";
"VSS_BC53":   PN = "BC53"  !CDS_PN = "BC53";
"VSS_BC56":   PN = "BC56"  !CDS_PN = "BC56";
"VSS_BC58":   PN = "BC58"  !CDS_PN = "BC58";
"VSS_BC61":   PN = "BC61"  !CDS_PN = "BC61";
"VSS_BC63":   PN = "BC63"  !CDS_PN = "BC63";
"VSS_BC65":   PN = "BC65"  !CDS_PN = "BC65";
"VSS_BC68":   PN = "BC68"  !CDS_PN = "BC68";
"VSS_BC70":   PN = "BC70"  !CDS_PN = "BC70";
"VSS_BC72":   PN = "BC72"  !CDS_PN = "BC72";
"VSS_BC75":   PN = "BC75"  !CDS_PN = "BC75";
"VSS_BD3":   PN = "BD3"  !CDS_PN = "BD3";
"VSS_BD8":   PN = "BD8"  !CDS_PN = "BD8";
"VSS_BD10":   PN = "BD10"  !CDS_PN = "BD10";
"VSS_BD15":   PN = "BD15"  !CDS_PN = "BD15";
"VSS_BD17":   PN = "BD17"  !CDS_PN = "BD17";
"VSS_BD23":   PN = "BD23"  !CDS_PN = "BD23";
"VSS_BD25":   PN = "BD25"  !CDS_PN = "BD25";
"VSS_BD27":   PN = "BD27"  !CDS_PN = "BD27";
"VSS_BD49":   PN = "BD49"  !CDS_PN = "BD49";
"VSS_BD51":   PN = "BD51"  !CDS_PN = "BD51";
"VSS_BD53":   PN = "BD53"  !CDS_PN = "BD53";
"VSS_BD57":   PN = "BD57"  !CDS_PN = "BD57";
"VSS_BD59":   PN = "BD59"  !CDS_PN = "BD59";
"VSS_BD61":   PN = "BD61"  !CDS_PN = "BD61";
"VSS_BD64":   PN = "BD64"  !CDS_PN = "BD64";
"VSS_BD66":   PN = "BD66"  !CDS_PN = "BD66";
"VSS_BD68":   PN = "BD68"  !CDS_PN = "BD68";
"VSS_BD71":   PN = "BD71"  !CDS_PN = "BD71";
"VSS_BD73":   PN = "BD73"  !CDS_PN = "BD73";
"VSS_BF3":   PN = "BF3"  !CDS_PN = "BF3";
"VSS_BF5":   PN = "BF5"  !CDS_PN = "BF5";
"VSS_BF8":   PN = "BF8"  !CDS_PN = "BF8";
"VSS_BF10":   PN = "BF10"  !CDS_PN = "BF10";
"VSS_BF12":   PN = "BF12"  !CDS_PN = "BF12";
"VSS_BF15":   PN = "BF15"  !CDS_PN = "BF15";
"VSS_BF17":   PN = "BF17"  !CDS_PN = "BF17";
"VSS_BF19":   PN = "BF19"  !CDS_PN = "BF19";
"VSS_BF22":   PN = "BF22"  !CDS_PN = "BF22";
"VSS_BF24":   PN = "BF24"  !CDS_PN = "BF24";
"VSS_BF26":   PN = "BF26"  !CDS_PN = "BF26";
"VSS_BF28":   PN = "BF28"  !CDS_PN = "BF28";
"VSS_BF49":   PN = "BF49"  !CDS_PN = "BF49";
"VSS_BF50":   PN = "BF50"  !CDS_PN = "BF50";
"VSS_BF52":   PN = "BF52"  !CDS_PN = "BF52";
"VSS_BF54":   PN = "BF54"  !CDS_PN = "BF54";
"VSS_BF59":   PN = "BF59"  !CDS_PN = "BF59";
"VSS_BF61":   PN = "BF61"  !CDS_PN = "BF61";
"VSS_BF66":   PN = "BF66"  !CDS_PN = "BF66";
"VSS_BF68":   PN = "BF68"  !CDS_PN = "BF68";
"VSS_BF73":   PN = "BF73"  !CDS_PN = "BF73";
"VSS_BG1":   PN = "BG1"  !CDS_PN = "BG1";
"VSS_BG4":   PN = "BG4"  !CDS_PN = "BG4";
"VSS_BG6":   PN = "BG6"  !CDS_PN = "BG6";
"VSS_BG8":   PN = "BG8"  !CDS_PN = "BG8";
"VSS_BG11":   PN = "BG11"  !CDS_PN = "BG11";
"VSS_BG13":   PN = "BG13"  !CDS_PN = "BG13";
"VSS_BG15":   PN = "BG15"  !CDS_PN = "BG15";
"VSS_BG18":   PN = "BG18"  !CDS_PN = "BG18";
"VSS_BG20":   PN = "BG20"  !CDS_PN = "BG20";
"VSS_BG23":   PN = "BG23"  !CDS_PN = "BG23";
"VSS_BG25":   PN = "BG25"  !CDS_PN = "BG25";
"VSS_BG27":   PN = "BG27"  !CDS_PN = "BG27";
"VSS_BG49":   PN = "BG49"  !CDS_PN = "BG49";
"VSS_BG51":   PN = "BG51"  !CDS_PN = "BG51";
"VSS_BG53":   PN = "BG53"  !CDS_PN = "BG53";
"VSS_BG56":   PN = "BG56"  !CDS_PN = "BG56";
"VSS_BG58":   PN = "BG58"  !CDS_PN = "BG58";
"VSS_BG61":   PN = "BG61"  !CDS_PN = "BG61";
"VSS_BG63":   PN = "BG63"  !CDS_PN = "BG63";
"VSS_BG65":   PN = "BG65"  !CDS_PN = "BG65";
"VSS_BG68":   PN = "BG68"  !CDS_PN = "BG68";
"VSS_BG70":   PN = "BG70"  !CDS_PN = "BG70";
"VSS_BG72":   PN = "BG72"  !CDS_PN = "BG72";
"VSS_BG75":   PN = "BG75"  !CDS_PN = "BG75";
"VSS_BH3":   PN = "BH3"  !CDS_PN = "BH3";
"VSS_BH5":   PN = "BH5"  !CDS_PN = "BH5";
"VSS_BH8":   PN = "BH8"  !CDS_PN = "BH8";
"VSS_BH10":   PN = "BH10"  !CDS_PN = "BH10";
"VSS_BH12":   PN = "BH12"  !CDS_PN = "BH12";
"VSS_BH15":   PN = "BH15"  !CDS_PN = "BH15";
"VSS_BH17":   PN = "BH17"  !CDS_PN = "BH17";
"VSS_BH19":   PN = "BH19"  !CDS_PN = "BH19";
"VSS_BH22":   PN = "BH22"  !CDS_PN = "BH22";
"VSS_BH24":   PN = "BH24"  !CDS_PN = "BH24";
"VSS_BH26":   PN = "BH26"  !CDS_PN = "BH26";
"VSS_BH28":   PN = "BH28"  !CDS_PN = "BH28";
"VSS_BH49":   PN = "BH49"  !CDS_PN = "BH49";
"VSS_BH50":   PN = "BH50"  !CDS_PN = "BH50";
"VSS_BH52":   PN = "BH52"  !CDS_PN = "BH52";
"VSS_BH54":   PN = "BH54"  !CDS_PN = "BH54";
"VSS_BH57":   PN = "BH57"  !CDS_PN = "BH57";
"VSS_BH59":   PN = "BH59"  !CDS_PN = "BH59";
"VSS_BH61":   PN = "BH61"  !CDS_PN = "BH61";
"VSS_BH64":   PN = "BH64"  !CDS_PN = "BH64";
"VSS_BH66":   PN = "BH66"  !CDS_PN = "BH66";
"VSS_BH68":   PN = "BH68"  !CDS_PN = "BH68";
"VSS_BH71":   PN = "BH71"  !CDS_PN = "BH71";
"VSS_BH73":   PN = "BH73"  !CDS_PN = "BH73";
"VSS_BJ1":   PN = "BJ1"  !CDS_PN = "BJ1";
"VSS_BJ6":   PN = "BJ6"  !CDS_PN = "BJ6";
"VSS_BJ8":   PN = "BJ8"  !CDS_PN = "BJ8";
"VSS_BJ13":   PN = "BJ13"  !CDS_PN = "BJ13";
"VSS_BJ15":   PN = "BJ15"  !CDS_PN = "BJ15";
"VSS_BJ20":   PN = "BJ20"  !CDS_PN = "BJ20";
"VSS_BJ22":   PN = "BJ22"  !CDS_PN = "BJ22";
"VSS_BJ24":   PN = "BJ24"  !CDS_PN = "BJ24";
"VSS_BJ26":   PN = "BJ26"  !CDS_PN = "BJ26";
"VSS_BJ28":   PN = "BJ28"  !CDS_PN = "BJ28";
"VSS_BJ49":   PN = "BJ49"  !CDS_PN = "BJ49";
"VSS_BJ51":   PN = "BJ51"  !CDS_PN = "BJ51";
"VSS_BJ53":   PN = "BJ53"  !CDS_PN = "BJ53";
"VSS_BJ56":   PN = "BJ56"  !CDS_PN = "BJ56";
"VSS_BJ61":   PN = "BJ61"  !CDS_PN = "BJ61";
"VSS_BJ63":   PN = "BJ63"  !CDS_PN = "BJ63";
"VSS_BJ68":   PN = "BJ68"  !CDS_PN = "BJ68";
"VSS_BJ70":   PN = "BJ70"  !CDS_PN = "BJ70";
"VSS_BJ75":   PN = "BJ75"  !CDS_PN = "BJ75";
"VSS_BK3":   PN = "BK3"  !CDS_PN = "BK3";
"VSS_BK5":   PN = "BK5"  !CDS_PN = "BK5";
"VSS_BK8":   PN = "BK8"  !CDS_PN = "BK8";
"VSS_BK10":   PN = "BK10"  !CDS_PN = "BK10";
"VSS_BK12":   PN = "BK12"  !CDS_PN = "BK12";
"VSS_BK15":   PN = "BK15"  !CDS_PN = "BK15";
"VSS_BK17":   PN = "BK17"  !CDS_PN = "BK17";
"VSS_BK19":   PN = "BK19"  !CDS_PN = "BK19";
"VSS_BK23":   PN = "BK23"  !CDS_PN = "BK23";
"VSS_BK25":   PN = "BK25"  !CDS_PN = "BK25";
"VSS_BK27":   PN = "BK27"  !CDS_PN = "BK27";
"VSS_BK48":   PN = "BK48"  !CDS_PN = "BK48";
"VSS_BK50":   PN = "BK50"  !CDS_PN = "BK50";
"VSS_BK52":   PN = "BK52"  !CDS_PN = "BK52";
"VSS_BK54":   PN = "BK54"  !CDS_PN = "BK54";
"VSS_BK57":   PN = "BK57"  !CDS_PN = "BK57";
"VSS_BK59":   PN = "BK59"  !CDS_PN = "BK59";
"VSS_BK61":   PN = "BK61"  !CDS_PN = "BK61";
"VSS_BK64":   PN = "BK64"  !CDS_PN = "BK64";
"VSS_BK66":   PN = "BK66"  !CDS_PN = "BK66";
"VSS_BK68":   PN = "BK68"  !CDS_PN = "BK68";
"VSS_BK71":   PN = "BK71"  !CDS_PN = "BK71";
"VSS_BK73":   PN = "BK73"  !CDS_PN = "BK73";
"VSS_BL1":   PN = "BL1"  !CDS_PN = "BL1";
"VSS_BL4":   PN = "BL4"  !CDS_PN = "BL4";
"VSS_BL6":   PN = "BL6"  !CDS_PN = "BL6";
"VSS_BL8":   PN = "BL8"  !CDS_PN = "BL8";
"VSS_BL11":   PN = "BL11"  !CDS_PN = "BL11";
"VSS_BL13":   PN = "BL13"  !CDS_PN = "BL13";
"VSS_BL15":   PN = "BL15"  !CDS_PN = "BL15";
"VSS_BL18":   PN = "BL18"  !CDS_PN = "BL18";
"VSS_BL20":   PN = "BL20"  !CDS_PN = "BL20";
"VSS_BL22":   PN = "BL22"  !CDS_PN = "BL22";
"VSS_BL24":   PN = "BL24"  !CDS_PN = "BL24";
BODY = "GENOA_SP5","I6": #LOCATION = "U26" !CDS_LOCATION = "U26" &SEC = "32" #&CDS_SEC = "32";
"VSS_AM42":   PN = "AM42"  !CDS_PN = "AM42";
"VSS_AM43":   PN = "AM43"  !CDS_PN = "AM43";
"VSS_AM44":   PN = "AM44"  !CDS_PN = "AM44";
"VSS_AM45":   PN = "AM45"  !CDS_PN = "AM45";
"VSS_AM46":   PN = "AM46"  !CDS_PN = "AM46";
"VSS_AM47":   PN = "AM47"  !CDS_PN = "AM47";
"VSS_AM48":   PN = "AM48"  !CDS_PN = "AM48";
"VSS_AM49":   PN = "AM49"  !CDS_PN = "AM49";
"VSS_AM50":   PN = "AM50"  !CDS_PN = "AM50";
"VSS_AM51":   PN = "AM51"  !CDS_PN = "AM51";
"VSS_AM52":   PN = "AM52"  !CDS_PN = "AM52";
"VSS_AM53":   PN = "AM53"  !CDS_PN = "AM53";
"VSS_AM59":   PN = "AM59"  !CDS_PN = "AM59";
"VSS_AM61":   PN = "AM61"  !CDS_PN = "AM61";
"VSS_AM66":   PN = "AM66"  !CDS_PN = "AM66";
"VSS_AM68":   PN = "AM68"  !CDS_PN = "AM68";
"VSS_AM73":   PN = "AM73"  !CDS_PN = "AM73";
"VSS_AN1":   PN = "AN1"  !CDS_PN = "AN1";
"VSS_AN4":   PN = "AN4"  !CDS_PN = "AN4";
"VSS_AN6":   PN = "AN6"  !CDS_PN = "AN6";
"VSS_AN8":   PN = "AN8"  !CDS_PN = "AN8";
"VSS_AN11":   PN = "AN11"  !CDS_PN = "AN11";
"VSS_AN13":   PN = "AN13"  !CDS_PN = "AN13";
"VSS_AN15":   PN = "AN15"  !CDS_PN = "AN15";
"VSS_AN18":   PN = "AN18"  !CDS_PN = "AN18";
"VSS_AN22":   PN = "AN22"  !CDS_PN = "AN22";
"VSS_AN25":   PN = "AN25"  !CDS_PN = "AN25";
"VSS_AN28":   PN = "AN28"  !CDS_PN = "AN28";
"VSS_AN31":   PN = "AN31"  !CDS_PN = "AN31";
"VSS_AN34":   PN = "AN34"  !CDS_PN = "AN34";
"VSS_AN35":   PN = "AN35"  !CDS_PN = "AN35";
"VSS_AN36":   PN = "AN36"  !CDS_PN = "AN36";
"VSS_AN40":   PN = "AN40"  !CDS_PN = "AN40";
"VSS_AN41":   PN = "AN41"  !CDS_PN = "AN41";
"VSS_AN42":   PN = "AN42"  !CDS_PN = "AN42";
"VSS_AN45":   PN = "AN45"  !CDS_PN = "AN45";
"VSS_AN48":   PN = "AN48"  !CDS_PN = "AN48";
"VSS_AN51":   PN = "AN51"  !CDS_PN = "AN51";
"VSS_AN54":   PN = "AN54"  !CDS_PN = "AN54";
"VSS_AN56":   PN = "AN56"  !CDS_PN = "AN56";
"VSS_AN58":   PN = "AN58"  !CDS_PN = "AN58";
"VSS_AN61":   PN = "AN61"  !CDS_PN = "AN61";
"VSS_AN63":   PN = "AN63"  !CDS_PN = "AN63";
"VSS_AN65":   PN = "AN65"  !CDS_PN = "AN65";
"VSS_AN68":   PN = "AN68"  !CDS_PN = "AN68";
"VSS_AN70":   PN = "AN70"  !CDS_PN = "AN70";
"VSS_AN72":   PN = "AN72"  !CDS_PN = "AN72";
"VSS_AN75":   PN = "AN75"  !CDS_PN = "AN75";
"VSS_AP3":   PN = "AP3"  !CDS_PN = "AP3";
"VSS_AP5":   PN = "AP5"  !CDS_PN = "AP5";
"VSS_AP8":   PN = "AP8"  !CDS_PN = "AP8";
"VSS_AP10":   PN = "AP10"  !CDS_PN = "AP10";
"VSS_AP12":   PN = "AP12"  !CDS_PN = "AP12";
"VSS_AP15":   PN = "AP15"  !CDS_PN = "AP15";
"VSS_AP17":   PN = "AP17"  !CDS_PN = "AP17";
"VSS_AP19":   PN = "AP19"  !CDS_PN = "AP19";
"VSS_AP22":   PN = "AP22"  !CDS_PN = "AP22";
"VSS_AP25":   PN = "AP25"  !CDS_PN = "AP25";
"VSS_AP28":   PN = "AP28"  !CDS_PN = "AP28";
"VSS_AP31":   PN = "AP31"  !CDS_PN = "AP31";
"VSS_AP34":   PN = "AP34"  !CDS_PN = "AP34";
"VSS_AP37":   PN = "AP37"  !CDS_PN = "AP37";
"VSS_AP39":   PN = "AP39"  !CDS_PN = "AP39";
"VSS_AP42":   PN = "AP42"  !CDS_PN = "AP42";
"VSS_AP45":   PN = "AP45"  !CDS_PN = "AP45";
"VSS_AP48":   PN = "AP48"  !CDS_PN = "AP48";
"VSS_AP51":   PN = "AP51"  !CDS_PN = "AP51";
"VSS_AP54":   PN = "AP54"  !CDS_PN = "AP54";
"VSS_AP57":   PN = "AP57"  !CDS_PN = "AP57";
"VSS_AP59":   PN = "AP59"  !CDS_PN = "AP59";
"VSS_AP61":   PN = "AP61"  !CDS_PN = "AP61";
"VSS_AP64":   PN = "AP64"  !CDS_PN = "AP64";
"VSS_AP66":   PN = "AP66"  !CDS_PN = "AP66";
"VSS_AP68":   PN = "AP68"  !CDS_PN = "AP68";
"VSS_AP71":   PN = "AP71"  !CDS_PN = "AP71";
"VSS_AP73":   PN = "AP73"  !CDS_PN = "AP73";
"VSS_AR1":   PN = "AR1"  !CDS_PN = "AR1";
"VSS_AR5":   PN = "AR5"  !CDS_PN = "AR5";
"VSS_AR6":   PN = "AR6"  !CDS_PN = "AR6";
"VSS_AR8":   PN = "AR8"  !CDS_PN = "AR8";
"VSS_AR9":   PN = "AR9"  !CDS_PN = "AR9";
"VSS_AR12":   PN = "AR12"  !CDS_PN = "AR12";
"VSS_AR13":   PN = "AR13"  !CDS_PN = "AR13";
"VSS_AR15":   PN = "AR15"  !CDS_PN = "AR15";
"VSS_AR16":   PN = "AR16"  !CDS_PN = "AR16";
"VSS_AR19":   PN = "AR19"  !CDS_PN = "AR19";
"VSS_AR20":   PN = "AR20"  !CDS_PN = "AR20";
"VSS_AR22":   PN = "AR22"  !CDS_PN = "AR22";
"VSS_AR24":   PN = "AR24"  !CDS_PN = "AR24";
"VSS_AR26":   PN = "AR26"  !CDS_PN = "AR26";
"VSS_AR28":   PN = "AR28"  !CDS_PN = "AR28";
"VSS_AR30":   PN = "AR30"  !CDS_PN = "AR30";
"VSS_AR32":   PN = "AR32"  !CDS_PN = "AR32";
"VSS_AR34":   PN = "AR34"  !CDS_PN = "AR34";
"VSS_AR36":   PN = "AR36"  !CDS_PN = "AR36";
"VSS_AR41":   PN = "AR41"  !CDS_PN = "AR41";
"VSS_AR43":   PN = "AR43"  !CDS_PN = "AR43";
"VSS_AR45":   PN = "AR45"  !CDS_PN = "AR45";
"VSS_AR47":   PN = "AR47"  !CDS_PN = "AR47";
"VSS_AR49":   PN = "AR49"  !CDS_PN = "AR49";
"VSS_AR51":   PN = "AR51"  !CDS_PN = "AR51";
"VSS_AR53":   PN = "AR53"  !CDS_PN = "AR53";
"VSS_AR56":   PN = "AR56"  !CDS_PN = "AR56";
"VSS_AR57":   PN = "AR57"  !CDS_PN = "AR57";
"VSS_AR60":   PN = "AR60"  !CDS_PN = "AR60";
"VSS_AR61":   PN = "AR61"  !CDS_PN = "AR61";
"VSS_AR63":   PN = "AR63"  !CDS_PN = "AR63";
"VSS_AR64":   PN = "AR64"  !CDS_PN = "AR64";
"VSS_AR67":   PN = "AR67"  !CDS_PN = "AR67";
"VSS_AR68":   PN = "AR68"  !CDS_PN = "AR68";
"VSS_AR70":   PN = "AR70"  !CDS_PN = "AR70";
"VSS_AR71":   PN = "AR71"  !CDS_PN = "AR71";
"VSS_AR75":   PN = "AR75"  !CDS_PN = "AR75";
"VSS_AT3":   PN = "AT3"  !CDS_PN = "AT3";
"VSS_AT4":   PN = "AT4"  !CDS_PN = "AT4";
"VSS_AT5":   PN = "AT5"  !CDS_PN = "AT5";
"VSS_AT6":   PN = "AT6"  !CDS_PN = "AT6";
"VSS_AT8":   PN = "AT8"  !CDS_PN = "AT8";
"VSS_AT9":   PN = "AT9"  !CDS_PN = "AT9";
"VSS_AT10":   PN = "AT10"  !CDS_PN = "AT10";
"VSS_AT12":   PN = "AT12"  !CDS_PN = "AT12";
"VSS_AT13":   PN = "AT13"  !CDS_PN = "AT13";
"VSS_AT15":   PN = "AT15"  !CDS_PN = "AT15";
"VSS_AT16":   PN = "AT16"  !CDS_PN = "AT16";
"VSS_AT17":   PN = "AT17"  !CDS_PN = "AT17";
"VSS_AT19":   PN = "AT19"  !CDS_PN = "AT19";
"VSS_AT20":   PN = "AT20"  !CDS_PN = "AT20";
"VSS_AT23":   PN = "AT23"  !CDS_PN = "AT23";
"VSS_AT25":   PN = "AT25"  !CDS_PN = "AT25";
"VSS_AT27":   PN = "AT27"  !CDS_PN = "AT27";
"VSS_AT29":   PN = "AT29"  !CDS_PN = "AT29";
"VSS_AT31":   PN = "AT31"  !CDS_PN = "AT31";
"VSS_AT33":   PN = "AT33"  !CDS_PN = "AT33";
"VSS_AT35":   PN = "AT35"  !CDS_PN = "AT35";
"VSS_AT37":   PN = "AT37"  !CDS_PN = "AT37";
"VSS_AT40":   PN = "AT40"  !CDS_PN = "AT40";
"VSS_AT42":   PN = "AT42"  !CDS_PN = "AT42";
"VSS_AT44":   PN = "AT44"  !CDS_PN = "AT44";
"VSS_AT46":   PN = "AT46"  !CDS_PN = "AT46";
"VSS_AT48":   PN = "AT48"  !CDS_PN = "AT48";
"VSS_AT50":   PN = "AT50"  !CDS_PN = "AT50";
"VSS_AT52":   PN = "AT52"  !CDS_PN = "AT52";
"VSS_AT54":   PN = "AT54"  !CDS_PN = "AT54";
"VSS_AT56":   PN = "AT56"  !CDS_PN = "AT56";
"VSS_AT57":   PN = "AT57"  !CDS_PN = "AT57";
"VSS_AT59":   PN = "AT59"  !CDS_PN = "AT59";
"VSS_AT60":   PN = "AT60"  !CDS_PN = "AT60";
"VSS_AT61":   PN = "AT61"  !CDS_PN = "AT61";
"VSS_AT63":   PN = "AT63"  !CDS_PN = "AT63";
"VSS_AT64":   PN = "AT64"  !CDS_PN = "AT64";
"VSS_AT66":   PN = "AT66"  !CDS_PN = "AT66";
"VSS_AT67":   PN = "AT67"  !CDS_PN = "AT67";
"VSS_AT68":   PN = "AT68"  !CDS_PN = "AT68";
"VSS_AT70":   PN = "AT70"  !CDS_PN = "AT70";
"VSS_AT71":   PN = "AT71"  !CDS_PN = "AT71";
"VSS_AT72":   PN = "AT72"  !CDS_PN = "AT72";
"VSS_AT73":   PN = "AT73"  !CDS_PN = "AT73";
"VSS_AU1":   PN = "AU1"  !CDS_PN = "AU1";
"VSS_AU3":   PN = "AU3"  !CDS_PN = "AU3";
"VSS_AU4":   PN = "AU4"  !CDS_PN = "AU4";
"VSS_AU6":   PN = "AU6"  !CDS_PN = "AU6";
"VSS_AU8":   PN = "AU8"  !CDS_PN = "AU8";
"VSS_AU11":   PN = "AU11"  !CDS_PN = "AU11";
"VSS_AU13":   PN = "AU13"  !CDS_PN = "AU13";
"VSS_AU15":   PN = "AU15"  !CDS_PN = "AU15";
"VSS_AU18":   PN = "AU18"  !CDS_PN = "AU18";
"VSS_AU20":   PN = "AU20"  !CDS_PN = "AU20";
"VSS_AU22":   PN = "AU22"  !CDS_PN = "AU22";
"VSS_AU24":   PN = "AU24"  !CDS_PN = "AU24";
"VSS_AU26":   PN = "AU26"  !CDS_PN = "AU26";
"VSS_AU28":   PN = "AU28"  !CDS_PN = "AU28";
"VSS_AU30":   PN = "AU30"  !CDS_PN = "AU30";
"VSS_AU32":   PN = "AU32"  !CDS_PN = "AU32";
"VSS_AU34":   PN = "AU34"  !CDS_PN = "AU34";
"VSS_AU36":   PN = "AU36"  !CDS_PN = "AU36";
"VSS_AU41":   PN = "AU41"  !CDS_PN = "AU41";
"VSS_AU43":   PN = "AU43"  !CDS_PN = "AU43";
"VSS_AU45":   PN = "AU45"  !CDS_PN = "AU45";
"VSS_AU47":   PN = "AU47"  !CDS_PN = "AU47";
"VSS_AU49":   PN = "AU49"  !CDS_PN = "AU49";
"VSS_AU51":   PN = "AU51"  !CDS_PN = "AU51";
"VSS_AU53":   PN = "AU53"  !CDS_PN = "AU53";
"VSS_AU56":   PN = "AU56"  !CDS_PN = "AU56";
"VSS_AU58":   PN = "AU58"  !CDS_PN = "AU58";
"VSS_AU61":   PN = "AU61"  !CDS_PN = "AU61";
"VSS_AU63":   PN = "AU63"  !CDS_PN = "AU63";
"VSS_AU65":   PN = "AU65"  !CDS_PN = "AU65";
"VSS_AU68":   PN = "AU68"  !CDS_PN = "AU68";
"VSS_AU70":   PN = "AU70"  !CDS_PN = "AU70";
"VSS_AU72":   PN = "AU72"  !CDS_PN = "AU72";
"VSS_AU73":   PN = "AU73"  !CDS_PN = "AU73";
"VSS_AU75":   PN = "AU75"  !CDS_PN = "AU75";
"VSS_AV3":   PN = "AV3"  !CDS_PN = "AV3";
"VSS_AV8":   PN = "AV8"  !CDS_PN = "AV8";
"VSS_AV10":   PN = "AV10"  !CDS_PN = "AV10";
"VSS_AV15":   PN = "AV15"  !CDS_PN = "AV15";
"VSS_AV17":   PN = "AV17"  !CDS_PN = "AV17";
"VSS_AV23":   PN = "AV23"  !CDS_PN = "AV23";
"VSS_AV25":   PN = "AV25"  !CDS_PN = "AV25";
"VSS_AV27":   PN = "AV27"  !CDS_PN = "AV27";
"VSS_AV29":   PN = "AV29"  !CDS_PN = "AV29";
"VSS_AV31":   PN = "AV31"  !CDS_PN = "AV31";
"VSS_AV33":   PN = "AV33"  !CDS_PN = "AV33";
"VSS_AV35":   PN = "AV35"  !CDS_PN = "AV35";
"VSS_AV37":   PN = "AV37"  !CDS_PN = "AV37";
"VSS_AV40":   PN = "AV40"  !CDS_PN = "AV40";
"VSS_AV42":   PN = "AV42"  !CDS_PN = "AV42";
"VSS_AV44":   PN = "AV44"  !CDS_PN = "AV44";
"VSS_AV46":   PN = "AV46"  !CDS_PN = "AV46";
"VSS_AV48":   PN = "AV48"  !CDS_PN = "AV48";
"VSS_AV50":   PN = "AV50"  !CDS_PN = "AV50";
"VSS_AV52":   PN = "AV52"  !CDS_PN = "AV52";
"VSS_AV54":   PN = "AV54"  !CDS_PN = "AV54";
"VSS_AV59":   PN = "AV59"  !CDS_PN = "AV59";
"VSS_AV61":   PN = "AV61"  !CDS_PN = "AV61";
"VSS_AV66":   PN = "AV66"  !CDS_PN = "AV66";
"VSS_AV68":   PN = "AV68"  !CDS_PN = "AV68";
"VSS_AV73":   PN = "AV73"  !CDS_PN = "AV73";
"VSS_AW1":   PN = "AW1"  !CDS_PN = "AW1";
"VSS_AW4":   PN = "AW4"  !CDS_PN = "AW4";
"VSS_AW6":   PN = "AW6"  !CDS_PN = "AW6";
"VSS_AW8":   PN = "AW8"  !CDS_PN = "AW8";
"VSS_AW11":   PN = "AW11"  !CDS_PN = "AW11";
"VSS_AW13":   PN = "AW13"  !CDS_PN = "AW13";
"VSS_AW15":   PN = "AW15"  !CDS_PN = "AW15";
"VSS_AW18":   PN = "AW18"  !CDS_PN = "AW18";
"VSS_AW20":   PN = "AW20"  !CDS_PN = "AW20";
"VSS_AW22":   PN = "AW22"  !CDS_PN = "AW22";
"VSS_AW24":   PN = "AW24"  !CDS_PN = "AW24";
"VSS_AW26":   PN = "AW26"  !CDS_PN = "AW26";
"VSS_AW28":   PN = "AW28"  !CDS_PN = "AW28";
"VSS_AW49":   PN = "AW49"  !CDS_PN = "AW49";
"VSS_AW51":   PN = "AW51"  !CDS_PN = "AW51";
"VSS_AW53":   PN = "AW53"  !CDS_PN = "AW53";
"VSS_AW56":   PN = "AW56"  !CDS_PN = "AW56";
"VSS_AW58":   PN = "AW58"  !CDS_PN = "AW58";
"VSS_AW61":   PN = "AW61"  !CDS_PN = "AW61";
BODY = "GENOA_SP5","I9": #LOCATION = "U26" !CDS_LOCATION = "U26" &SEC = "31" #&CDS_SEC = "31";
"VSS_AD49":   PN = "AD49"  !CDS_PN = "AD49";
"VSS_AD50":   PN = "AD50"  !CDS_PN = "AD50";
"VSS_AD51":   PN = "AD51"  !CDS_PN = "AD51";
"VSS_AD52":   PN = "AD52"  !CDS_PN = "AD52";
"VSS_AD53":   PN = "AD53"  !CDS_PN = "AD53";
"VSS_AD57":   PN = "AD57"  !CDS_PN = "AD57";
"VSS_AD59":   PN = "AD59"  !CDS_PN = "AD59";
"VSS_AD61":   PN = "AD61"  !CDS_PN = "AD61";
"VSS_AD64":   PN = "AD64"  !CDS_PN = "AD64";
"VSS_AD66":   PN = "AD66"  !CDS_PN = "AD66";
"VSS_AD68":   PN = "AD68"  !CDS_PN = "AD68";
"VSS_AD71":   PN = "AD71"  !CDS_PN = "AD71";
"VSS_AD73":   PN = "AD73"  !CDS_PN = "AD73";
"VSS_AE1":   PN = "AE1"  !CDS_PN = "AE1";
"VSS_AE6":   PN = "AE6"  !CDS_PN = "AE6";
"VSS_AE8":   PN = "AE8"  !CDS_PN = "AE8";
"VSS_AE11":   PN = "AE11"  !CDS_PN = "AE11";
"VSS_AE13":   PN = "AE13"  !CDS_PN = "AE13";
"VSS_AE15":   PN = "AE15"  !CDS_PN = "AE15";
"VSS_AE18":   PN = "AE18"  !CDS_PN = "AE18";
"VSS_AE20":   PN = "AE20"  !CDS_PN = "AE20";
"VSS_AE22":   PN = "AE22"  !CDS_PN = "AE22";
"VSS_AE25":   PN = "AE25"  !CDS_PN = "AE25";
"VSS_AE28":   PN = "AE28"  !CDS_PN = "AE28";
"VSS_AE31":   PN = "AE31"  !CDS_PN = "AE31";
"VSS_AE34":   PN = "AE34"  !CDS_PN = "AE34";
"VSS_AE35":   PN = "AE35"  !CDS_PN = "AE35";
"VSS_AE36":   PN = "AE36"  !CDS_PN = "AE36";
"VSS_AE40":   PN = "AE40"  !CDS_PN = "AE40";
"VSS_AE41":   PN = "AE41"  !CDS_PN = "AE41";
"VSS_AE42":   PN = "AE42"  !CDS_PN = "AE42";
"VSS_AE45":   PN = "AE45"  !CDS_PN = "AE45";
"VSS_AE48":   PN = "AE48"  !CDS_PN = "AE48";
"VSS_AE51":   PN = "AE51"  !CDS_PN = "AE51";
"VSS_AE54":   PN = "AE54"  !CDS_PN = "AE54";
"VSS_AE56":   PN = "AE56"  !CDS_PN = "AE56";
"VSS_AE58":   PN = "AE58"  !CDS_PN = "AE58";
"VSS_AE61":   PN = "AE61"  !CDS_PN = "AE61";
"VSS_AE63":   PN = "AE63"  !CDS_PN = "AE63";
"VSS_AE65":   PN = "AE65"  !CDS_PN = "AE65";
"VSS_AE68":   PN = "AE68"  !CDS_PN = "AE68";
"VSS_AE70":   PN = "AE70"  !CDS_PN = "AE70";
"VSS_AE72":   PN = "AE72"  !CDS_PN = "AE72";
"VSS_AE75":   PN = "AE75"  !CDS_PN = "AE75";
"VSS_AF3":   PN = "AF3"  !CDS_PN = "AF3";
"VSS_AF8":   PN = "AF8"  !CDS_PN = "AF8";
"VSS_AF10":   PN = "AF10"  !CDS_PN = "AF10";
"VSS_AF15":   PN = "AF15"  !CDS_PN = "AF15";
"VSS_AF17":   PN = "AF17"  !CDS_PN = "AF17";
"VSS_AF22":   PN = "AF22"  !CDS_PN = "AF22";
"VSS_AF25":   PN = "AF25"  !CDS_PN = "AF25";
"VSS_AF28":   PN = "AF28"  !CDS_PN = "AF28";
"VSS_AF31":   PN = "AF31"  !CDS_PN = "AF31";
"VSS_AF34":   PN = "AF34"  !CDS_PN = "AF34";
"VSS_AF37":   PN = "AF37"  !CDS_PN = "AF37";
"VSS_AF39":   PN = "AF39"  !CDS_PN = "AF39";
"VSS_AF42":   PN = "AF42"  !CDS_PN = "AF42";
"VSS_AF45":   PN = "AF45"  !CDS_PN = "AF45";
"VSS_AF48":   PN = "AF48"  !CDS_PN = "AF48";
"VSS_AF51":   PN = "AF51"  !CDS_PN = "AF51";
"VSS_AF54":   PN = "AF54"  !CDS_PN = "AF54";
"VSS_AF59":   PN = "AF59"  !CDS_PN = "AF59";
"VSS_AF61":   PN = "AF61"  !CDS_PN = "AF61";
"VSS_AF66":   PN = "AF66"  !CDS_PN = "AF66";
"VSS_AF68":   PN = "AF68"  !CDS_PN = "AF68";
"VSS_AF73":   PN = "AF73"  !CDS_PN = "AF73";
"VSS_AG1":   PN = "AG1"  !CDS_PN = "AG1";
"VSS_AG4":   PN = "AG4"  !CDS_PN = "AG4";
"VSS_AG6":   PN = "AG6"  !CDS_PN = "AG6";
"VSS_AG8":   PN = "AG8"  !CDS_PN = "AG8";
"VSS_AG11":   PN = "AG11"  !CDS_PN = "AG11";
"VSS_AG13":   PN = "AG13"  !CDS_PN = "AG13";
"VSS_AG15":   PN = "AG15"  !CDS_PN = "AG15";
"VSS_AG18":   PN = "AG18"  !CDS_PN = "AG18";
"VSS_AG20":   PN = "AG20"  !CDS_PN = "AG20";
"VSS_AG22":   PN = "AG22"  !CDS_PN = "AG22";
"VSS_AG25":   PN = "AG25"  !CDS_PN = "AG25";
"VSS_AG28":   PN = "AG28"  !CDS_PN = "AG28";
"VSS_AG31":   PN = "AG31"  !CDS_PN = "AG31";
"VSS_AG34":   PN = "AG34"  !CDS_PN = "AG34";
"VSS_AG42":   PN = "AG42"  !CDS_PN = "AG42";
"VSS_AG45":   PN = "AG45"  !CDS_PN = "AG45";
"VSS_AG48":   PN = "AG48"  !CDS_PN = "AG48";
"VSS_AG51":   PN = "AG51"  !CDS_PN = "AG51";
"VSS_AG54":   PN = "AG54"  !CDS_PN = "AG54";
"VSS_AG56":   PN = "AG56"  !CDS_PN = "AG56";
"VSS_AG58":   PN = "AG58"  !CDS_PN = "AG58";
"VSS_AG61":   PN = "AG61"  !CDS_PN = "AG61";
"VSS_AG63":   PN = "AG63"  !CDS_PN = "AG63";
"VSS_AG65":   PN = "AG65"  !CDS_PN = "AG65";
"VSS_AG68":   PN = "AG68"  !CDS_PN = "AG68";
"VSS_AG70":   PN = "AG70"  !CDS_PN = "AG70";
"VSS_AG72":   PN = "AG72"  !CDS_PN = "AG72";
"VSS_AG75":   PN = "AG75"  !CDS_PN = "AG75";
"VSS_AH3":   PN = "AH3"  !CDS_PN = "AH3";
"VSS_AH5":   PN = "AH5"  !CDS_PN = "AH5";
"VSS_AH8":   PN = "AH8"  !CDS_PN = "AH8";
"VSS_AH10":   PN = "AH10"  !CDS_PN = "AH10";
"VSS_AH12":   PN = "AH12"  !CDS_PN = "AH12";
"VSS_AH15":   PN = "AH15"  !CDS_PN = "AH15";
"VSS_AH17":   PN = "AH17"  !CDS_PN = "AH17";
"VSS_AH19":   PN = "AH19"  !CDS_PN = "AH19";
"VSS_AH23":   PN = "AH23"  !CDS_PN = "AH23";
"VSS_AH24":   PN = "AH24"  !CDS_PN = "AH24";
"VSS_AH25":   PN = "AH25"  !CDS_PN = "AH25";
"VSS_AH26":   PN = "AH26"  !CDS_PN = "AH26";
"VSS_AH27":   PN = "AH27"  !CDS_PN = "AH27";
"VSS_AH28":   PN = "AH28"  !CDS_PN = "AH28";
"VSS_AH29":   PN = "AH29"  !CDS_PN = "AH29";
"VSS_AH30":   PN = "AH30"  !CDS_PN = "AH30";
"VSS_AH31":   PN = "AH31"  !CDS_PN = "AH31";
"VSS_AH32":   PN = "AH32"  !CDS_PN = "AH32";
"VSS_AH34":   PN = "AH34"  !CDS_PN = "AH34";
"VSS_AH37":   PN = "AH37"  !CDS_PN = "AH37";
"VSS_AH39":   PN = "AH39"  !CDS_PN = "AH39";
"VSS_AH42":   PN = "AH42"  !CDS_PN = "AH42";
"VSS_AH43":   PN = "AH43"  !CDS_PN = "AH43";
"VSS_AH44":   PN = "AH44"  !CDS_PN = "AH44";
"VSS_AH45":   PN = "AH45"  !CDS_PN = "AH45";
"VSS_AH46":   PN = "AH46"  !CDS_PN = "AH46";
"VSS_AH47":   PN = "AH47"  !CDS_PN = "AH47";
"VSS_AH48":   PN = "AH48"  !CDS_PN = "AH48";
"VSS_AH49":   PN = "AH49"  !CDS_PN = "AH49";
"VSS_AH50":   PN = "AH50"  !CDS_PN = "AH50";
"VSS_AH51":   PN = "AH51"  !CDS_PN = "AH51";
"VSS_AH52":   PN = "AH52"  !CDS_PN = "AH52";
"VSS_AH53":   PN = "AH53"  !CDS_PN = "AH53";
"VSS_AH57":   PN = "AH57"  !CDS_PN = "AH57";
"VSS_AH59":   PN = "AH59"  !CDS_PN = "AH59";
"VSS_AH61":   PN = "AH61"  !CDS_PN = "AH61";
"VSS_AH64":   PN = "AH64"  !CDS_PN = "AH64";
"VSS_AH66":   PN = "AH66"  !CDS_PN = "AH66";
"VSS_AH68":   PN = "AH68"  !CDS_PN = "AH68";
"VSS_AH71":   PN = "AH71"  !CDS_PN = "AH71";
"VSS_AH73":   PN = "AH73"  !CDS_PN = "AH73";
"VSS_AJ1":   PN = "AJ1"  !CDS_PN = "AJ1";
"VSS_AJ6":   PN = "AJ6"  !CDS_PN = "AJ6";
"VSS_AJ8":   PN = "AJ8"  !CDS_PN = "AJ8";
"VSS_AJ15":   PN = "AJ15"  !CDS_PN = "AJ15";
"VSS_AJ20":   PN = "AJ20"  !CDS_PN = "AJ20";
"VSS_AJ22":   PN = "AJ22"  !CDS_PN = "AJ22";
"VSS_AJ25":   PN = "AJ25"  !CDS_PN = "AJ25";
"VSS_AJ28":   PN = "AJ28"  !CDS_PN = "AJ28";
"VSS_AJ31":   PN = "AJ31"  !CDS_PN = "AJ31";
"VSS_AJ34":   PN = "AJ34"  !CDS_PN = "AJ34";
"VSS_AJ35":   PN = "AJ35"  !CDS_PN = "AJ35";
"VSS_AJ36":   PN = "AJ36"  !CDS_PN = "AJ36";
"VSS_AJ40":   PN = "AJ40"  !CDS_PN = "AJ40";
"VSS_AJ41":   PN = "AJ41"  !CDS_PN = "AJ41";
"VSS_AJ42":   PN = "AJ42"  !CDS_PN = "AJ42";
"VSS_AJ45":   PN = "AJ45"  !CDS_PN = "AJ45";
"VSS_AJ48":   PN = "AJ48"  !CDS_PN = "AJ48";
"VSS_AJ51":   PN = "AJ51"  !CDS_PN = "AJ51";
"VSS_AJ54":   PN = "AJ54"  !CDS_PN = "AJ54";
"VSS_AJ56":   PN = "AJ56"  !CDS_PN = "AJ56";
"VSS_AJ61":   PN = "AJ61"  !CDS_PN = "AJ61";
"VSS_AJ63":   PN = "AJ63"  !CDS_PN = "AJ63";
"VSS_AJ68":   PN = "AJ68"  !CDS_PN = "AJ68";
"VSS_AJ70":   PN = "AJ70"  !CDS_PN = "AJ70";
"VSS_AJ75":   PN = "AJ75"  !CDS_PN = "AJ75";
"VSS_AK3":   PN = "AK3"  !CDS_PN = "AK3";
"VSS_AK5":   PN = "AK5"  !CDS_PN = "AK5";
"VSS_AK8":   PN = "AK8"  !CDS_PN = "AK8";
"VSS_AK10":   PN = "AK10"  !CDS_PN = "AK10";
"VSS_AK12":   PN = "AK12"  !CDS_PN = "AK12";
"VSS_AK15":   PN = "AK15"  !CDS_PN = "AK15";
"VSS_AK17":   PN = "AK17"  !CDS_PN = "AK17";
"VSS_AK19":   PN = "AK19"  !CDS_PN = "AK19";
"VSS_AK22":   PN = "AK22"  !CDS_PN = "AK22";
"VSS_AK25":   PN = "AK25"  !CDS_PN = "AK25";
"VSS_AK28":   PN = "AK28"  !CDS_PN = "AK28";
"VSS_AK31":   PN = "AK31"  !CDS_PN = "AK31";
"VSS_AK34":   PN = "AK34"  !CDS_PN = "AK34";
"VSS_AK37":   PN = "AK37"  !CDS_PN = "AK37";
"VSS_AK39":   PN = "AK39"  !CDS_PN = "AK39";
"VSS_AK42":   PN = "AK42"  !CDS_PN = "AK42";
"VSS_AK45":   PN = "AK45"  !CDS_PN = "AK45";
"VSS_AK48":   PN = "AK48"  !CDS_PN = "AK48";
"VSS_AK51":   PN = "AK51"  !CDS_PN = "AK51";
"VSS_AK54":   PN = "AK54"  !CDS_PN = "AK54";
"VSS_AK57":   PN = "AK57"  !CDS_PN = "AK57";
"VSS_AK59":   PN = "AK59"  !CDS_PN = "AK59";
"VSS_AK61":   PN = "AK61"  !CDS_PN = "AK61";
"VSS_AK64":   PN = "AK64"  !CDS_PN = "AK64";
"VSS_AK66":   PN = "AK66"  !CDS_PN = "AK66";
"VSS_AK68":   PN = "AK68"  !CDS_PN = "AK68";
"VSS_AK71":   PN = "AK71"  !CDS_PN = "AK71";
"VSS_AK73":   PN = "AK73"  !CDS_PN = "AK73";
"VSS_AL1":   PN = "AL1"  !CDS_PN = "AL1";
"VSS_AL4":   PN = "AL4"  !CDS_PN = "AL4";
"VSS_AL6":   PN = "AL6"  !CDS_PN = "AL6";
"VSS_AL8":   PN = "AL8"  !CDS_PN = "AL8";
"VSS_AL11":   PN = "AL11"  !CDS_PN = "AL11";
"VSS_AL13":   PN = "AL13"  !CDS_PN = "AL13";
"VSS_AL15":   PN = "AL15"  !CDS_PN = "AL15";
"VSS_AL18":   PN = "AL18"  !CDS_PN = "AL18";
"VSS_AL20":   PN = "AL20"  !CDS_PN = "AL20";
"VSS_AL22":   PN = "AL22"  !CDS_PN = "AL22";
"VSS_AL25":   PN = "AL25"  !CDS_PN = "AL25";
"VSS_AL28":   PN = "AL28"  !CDS_PN = "AL28";
"VSS_AL31":   PN = "AL31"  !CDS_PN = "AL31";
"VSS_AL34":   PN = "AL34"  !CDS_PN = "AL34";
"VSS_AL42":   PN = "AL42"  !CDS_PN = "AL42";
"VSS_AL45":   PN = "AL45"  !CDS_PN = "AL45";
"VSS_AL48":   PN = "AL48"  !CDS_PN = "AL48";
"VSS_AL51":   PN = "AL51"  !CDS_PN = "AL51";
"VSS_AL54":   PN = "AL54"  !CDS_PN = "AL54";
"VSS_AL56":   PN = "AL56"  !CDS_PN = "AL56";
"VSS_AL58":   PN = "AL58"  !CDS_PN = "AL58";
"VSS_AL61":   PN = "AL61"  !CDS_PN = "AL61";
"VSS_AL63":   PN = "AL63"  !CDS_PN = "AL63";
"VSS_AL65":   PN = "AL65"  !CDS_PN = "AL65";
"VSS_AL68":   PN = "AL68"  !CDS_PN = "AL68";
"VSS_AL70":   PN = "AL70"  !CDS_PN = "AL70";
"VSS_AL72":   PN = "AL72"  !CDS_PN = "AL72";
"VSS_AL75":   PN = "AL75"  !CDS_PN = "AL75";
"VSS_AM3":   PN = "AM3"  !CDS_PN = "AM3";
"VSS_AM8":   PN = "AM8"  !CDS_PN = "AM8";
"VSS_AM10":   PN = "AM10"  !CDS_PN = "AM10";
"VSS_AM15":   PN = "AM15"  !CDS_PN = "AM15";
"VSS_AM17":   PN = "AM17"  !CDS_PN = "AM17";
"VSS_AM23":   PN = "AM23"  !CDS_PN = "AM23";
"VSS_AM24":   PN = "AM24"  !CDS_PN = "AM24";
"VSS_AM25":   PN = "AM25"  !CDS_PN = "AM25";
"VSS_AM26":   PN = "AM26"  !CDS_PN = "AM26";
"VSS_AM27":   PN = "AM27"  !CDS_PN = "AM27";
"VSS_AM28":   PN = "AM28"  !CDS_PN = "AM28";
"VSS_AM29":   PN = "AM29"  !CDS_PN = "AM29";
"VSS_AM30":   PN = "AM30"  !CDS_PN = "AM30";
"VSS_AM31":   PN = "AM31"  !CDS_PN = "AM31";
"VSS_AM32":   PN = "AM32"  !CDS_PN = "AM32";
"VSS_AM33":   PN = "AM33"  !CDS_PN = "AM33";
"VSS_AM34":   PN = "AM34"  !CDS_PN = "AM34";
"VSS_AM39":   PN = "AM39"  !CDS_PN = "AM39";
BODY = "GENOA_SP5","I12": #LOCATION = "U26" !CDS_LOCATION = "U26" &SEC = "30" #&CDS_SEC = "30";
"VSS_AA1":   PN = "AA1"  !CDS_PN = "AA1";
"VSS_AA4":   PN = "AA4"  !CDS_PN = "AA4";
"VSS_AA6":   PN = "AA6"  !CDS_PN = "AA6";
"VSS_AA8":   PN = "AA8"  !CDS_PN = "AA8";
"VSS_AA11":   PN = "AA11"  !CDS_PN = "AA11";
"VSS_AA13":   PN = "AA13"  !CDS_PN = "AA13";
"VSS_AA15":   PN = "AA15"  !CDS_PN = "AA15";
"VSS_AA18":   PN = "AA18"  !CDS_PN = "AA18";
"VSS_AA20":   PN = "AA20"  !CDS_PN = "AA20";
"VSS_AA31":   PN = "AA31"  !CDS_PN = "AA31";
"VSS_AA34":   PN = "AA34"  !CDS_PN = "AA34";
"VSS_AA35":   PN = "AA35"  !CDS_PN = "AA35";
"VSS_AA36":   PN = "AA36"  !CDS_PN = "AA36";
"VSS_AA40":   PN = "AA40"  !CDS_PN = "AA40";
"VSS_AA41":   PN = "AA41"  !CDS_PN = "AA41";
"VSS_AA45":   PN = "AA45"  !CDS_PN = "AA45";
"VSS_AA56":   PN = "AA56"  !CDS_PN = "AA56";
"VSS_AA58":   PN = "AA58"  !CDS_PN = "AA58";
"VSS_AA61":   PN = "AA61"  !CDS_PN = "AA61";
"VSS_AA63":   PN = "AA63"  !CDS_PN = "AA63";
"VSS_AA65":   PN = "AA65"  !CDS_PN = "AA65";
"VSS_AA68":   PN = "AA68"  !CDS_PN = "AA68";
"VSS_AA70":   PN = "AA70"  !CDS_PN = "AA70";
"VSS_AA75":   PN = "AA75"  !CDS_PN = "AA75";
"VSS_AB3":   PN = "AB3"  !CDS_PN = "AB3";
"VSS_AB5":   PN = "AB5"  !CDS_PN = "AB5";
"VSS_AB8":   PN = "AB8"  !CDS_PN = "AB8";
"VSS_AB10":   PN = "AB10"  !CDS_PN = "AB10";
"VSS_AB12":   PN = "AB12"  !CDS_PN = "AB12";
"VSS_AB15":   PN = "AB15"  !CDS_PN = "AB15";
"VSS_AB17":   PN = "AB17"  !CDS_PN = "AB17";
"VSS_AB19":   PN = "AB19"  !CDS_PN = "AB19";
"VSS_AB22":   PN = "AB22"  !CDS_PN = "AB22";
"VSS_AB25":   PN = "AB25"  !CDS_PN = "AB25";
"VSS_AB28":   PN = "AB28"  !CDS_PN = "AB28";
"VSS_AB31":   PN = "AB31"  !CDS_PN = "AB31";
"VSS_AB34":   PN = "AB34"  !CDS_PN = "AB34";
"VSS_AB37":   PN = "AB37"  !CDS_PN = "AB37";
"VSS_AB39":   PN = "AB39"  !CDS_PN = "AB39";
"VSS_AB42":   PN = "AB42"  !CDS_PN = "AB42";
"VSS_AB45":   PN = "AB45"  !CDS_PN = "AB45";
"VSS_AB48":   PN = "AB48"  !CDS_PN = "AB48";
"VSS_AB51":   PN = "AB51"  !CDS_PN = "AB51";
"VSS_AB54":   PN = "AB54"  !CDS_PN = "AB54";
"VSS_AB57":   PN = "AB57"  !CDS_PN = "AB57";
"VSS_AB59":   PN = "AB59"  !CDS_PN = "AB59";
"VSS_AB61":   PN = "AB61"  !CDS_PN = "AB61";
"VSS_AB64":   PN = "AB64"  !CDS_PN = "AB64";
"VSS_AB66":   PN = "AB66"  !CDS_PN = "AB66";
"VSS_AB68":   PN = "AB68"  !CDS_PN = "AB68";
"VSS_AB71":   PN = "AB71"  !CDS_PN = "AB71";
"VSS_AB73":   PN = "AB73"  !CDS_PN = "AB73";
"VSS_AC1":   PN = "AC1"  !CDS_PN = "AC1";
"VSS_AC6":   PN = "AC6"  !CDS_PN = "AC6";
"VSS_AC8":   PN = "AC8"  !CDS_PN = "AC8";
"VSS_AC13":   PN = "AC13"  !CDS_PN = "AC13";
"VSS_AC15":   PN = "AC15"  !CDS_PN = "AC15";
"VSS_AC20":   PN = "AC20"  !CDS_PN = "AC20";
"VSS_AC22":   PN = "AC22"  !CDS_PN = "AC22";
"VSS_AC25":   PN = "AC25"  !CDS_PN = "AC25";
"VSS_AC28":   PN = "AC28"  !CDS_PN = "AC28";
"VSS_AC31":   PN = "AC31"  !CDS_PN = "AC31";
"VSS_AC34":   PN = "AC34"  !CDS_PN = "AC34";
"VSS_AC42":   PN = "AC42"  !CDS_PN = "AC42";
"VSS_AC45":   PN = "AC45"  !CDS_PN = "AC45";
"VSS_AC48":   PN = "AC48"  !CDS_PN = "AC48";
"VSS_AC51":   PN = "AC51"  !CDS_PN = "AC51";
"VSS_AC54":   PN = "AC54"  !CDS_PN = "AC54";
"VSS_AC56":   PN = "AC56"  !CDS_PN = "AC56";
"VSS_AC61":   PN = "AC61"  !CDS_PN = "AC61";
"VSS_AC63":   PN = "AC63"  !CDS_PN = "AC63";
"VSS_AC68":   PN = "AC68"  !CDS_PN = "AC68";
"VSS_AC70":   PN = "AC70"  !CDS_PN = "AC70";
"VSS_AC75":   PN = "AC75"  !CDS_PN = "AC75";
"VSS_AD3":   PN = "AD3"  !CDS_PN = "AD3";
"VSS_AD5":   PN = "AD5"  !CDS_PN = "AD5";
"VSS_AD8":   PN = "AD8"  !CDS_PN = "AD8";
"VSS_AD10":   PN = "AD10"  !CDS_PN = "AD10";
"VSS_AD12":   PN = "AD12"  !CDS_PN = "AD12";
"VSS_AD15":   PN = "AD15"  !CDS_PN = "AD15";
"VSS_AD17":   PN = "AD17"  !CDS_PN = "AD17";
"VSS_AD19":   PN = "AD19"  !CDS_PN = "AD19";
"VSS_AD23":   PN = "AD23"  !CDS_PN = "AD23";
"VSS_AD24":   PN = "AD24"  !CDS_PN = "AD24";
"VSS_AD25":   PN = "AD25"  !CDS_PN = "AD25";
"VSS_AD26":   PN = "AD26"  !CDS_PN = "AD26";
"VSS_AD27":   PN = "AD27"  !CDS_PN = "AD27";
"VSS_AD28":   PN = "AD28"  !CDS_PN = "AD28";
"VSS_AD29":   PN = "AD29"  !CDS_PN = "AD29";
"VSS_AD30":   PN = "AD30"  !CDS_PN = "AD30";
"VSS_AD32":   PN = "AD32"  !CDS_PN = "AD32";
"VSS_AD33":   PN = "AD33"  !CDS_PN = "AD33";
"VSS_AD34":   PN = "AD34"  !CDS_PN = "AD34";
"VSS_AD37":   PN = "AD37"  !CDS_PN = "AD37";
"VSS_AD39":   PN = "AD39"  !CDS_PN = "AD39";
"VSS_AD42":   PN = "AD42"  !CDS_PN = "AD42";
"VSS_AD43":   PN = "AD43"  !CDS_PN = "AD43";
"VSS_AD44":   PN = "AD44"  !CDS_PN = "AD44";
"VSS_AD45":   PN = "AD45"  !CDS_PN = "AD45";
"VSS_AD46":   PN = "AD46"  !CDS_PN = "AD46";
"VSS_AD47":   PN = "AD47"  !CDS_PN = "AD47";
"VSS_AD48":   PN = "AD48"  !CDS_PN = "AD48";
"VSS_T66":   PN = "T66"  !CDS_PN = "T66";
"VSS_T68":   PN = "T68"  !CDS_PN = "T68";
"VSS_T71":   PN = "T71"  !CDS_PN = "T71";
"VSS_T73":   PN = "T73"  !CDS_PN = "T73";
"VSS_U1":   PN = "U1"  !CDS_PN = "U1";
"VSS_U6":   PN = "U6"  !CDS_PN = "U6";
"VSS_U8":   PN = "U8"  !CDS_PN = "U8";
"VSS_U13":   PN = "U13"  !CDS_PN = "U13";
"VSS_U15":   PN = "U15"  !CDS_PN = "U15";
"VSS_U20":   PN = "U20"  !CDS_PN = "U20";
"VSS_U22":   PN = "U22"  !CDS_PN = "U22";
"VSS_U25":   PN = "U25"  !CDS_PN = "U25";
"VSS_U28":   PN = "U28"  !CDS_PN = "U28";
"VSS_U31":   PN = "U31"  !CDS_PN = "U31";
"VSS_U34":   PN = "U34"  !CDS_PN = "U34";
"VSS_U42":   PN = "U42"  !CDS_PN = "U42";
"VSS_U45":   PN = "U45"  !CDS_PN = "U45";
"VSS_U48":   PN = "U48"  !CDS_PN = "U48";
"VSS_U51":   PN = "U51"  !CDS_PN = "U51";
"VSS_U54":   PN = "U54"  !CDS_PN = "U54";
"VSS_U56":   PN = "U56"  !CDS_PN = "U56";
"VSS_U61":   PN = "U61"  !CDS_PN = "U61";
"VSS_U63":   PN = "U63"  !CDS_PN = "U63";
"VSS_U68":   PN = "U68"  !CDS_PN = "U68";
"VSS_U70":   PN = "U70"  !CDS_PN = "U70";
"VSS_U75":   PN = "U75"  !CDS_PN = "U75";
"VSS_V3":   PN = "V3"  !CDS_PN = "V3";
"VSS_V5":   PN = "V5"  !CDS_PN = "V5";
"VSS_V8":   PN = "V8"  !CDS_PN = "V8";
"VSS_V10":   PN = "V10"  !CDS_PN = "V10";
"VSS_V12":   PN = "V12"  !CDS_PN = "V12";
"VSS_V15":   PN = "V15"  !CDS_PN = "V15";
"VSS_V17":   PN = "V17"  !CDS_PN = "V17";
"VSS_V19":   PN = "V19"  !CDS_PN = "V19";
"VSS_V23":   PN = "V23"  !CDS_PN = "V23";
"VSS_V24":   PN = "V24"  !CDS_PN = "V24";
"VSS_V25":   PN = "V25"  !CDS_PN = "V25";
"VSS_V26":   PN = "V26"  !CDS_PN = "V26";
"VSS_V28":   PN = "V28"  !CDS_PN = "V28";
"VSS_V29":   PN = "V29"  !CDS_PN = "V29";
"VSS_V30":   PN = "V30"  !CDS_PN = "V30";
"VSS_V31":   PN = "V31"  !CDS_PN = "V31";
"VSS_V32":   PN = "V32"  !CDS_PN = "V32";
"VSS_V33":   PN = "V33"  !CDS_PN = "V33";
"VSS_V34":   PN = "V34"  !CDS_PN = "V34";
"VSS_V37":   PN = "V37"  !CDS_PN = "V37";
"VSS_V39":   PN = "V39"  !CDS_PN = "V39";
"VSS_V42":   PN = "V42"  !CDS_PN = "V42";
"VSS_V43":   PN = "V43"  !CDS_PN = "V43";
"VSS_V44":   PN = "V44"  !CDS_PN = "V44";
"VSS_V45":   PN = "V45"  !CDS_PN = "V45";
"VSS_V46":   PN = "V46"  !CDS_PN = "V46";
"VSS_V47":   PN = "V47"  !CDS_PN = "V47";
"VSS_V48":   PN = "V48"  !CDS_PN = "V48";
"VSS_V49":   PN = "V49"  !CDS_PN = "V49";
"VSS_V50":   PN = "V50"  !CDS_PN = "V50";
"VSS_V51":   PN = "V51"  !CDS_PN = "V51";
"VSS_V52":   PN = "V52"  !CDS_PN = "V52";
"VSS_V53":   PN = "V53"  !CDS_PN = "V53";
"VSS_V57":   PN = "V57"  !CDS_PN = "V57";
"VSS_V59":   PN = "V59"  !CDS_PN = "V59";
"VSS_V61":   PN = "V61"  !CDS_PN = "V61";
"VSS_V64":   PN = "V64"  !CDS_PN = "V64";
"VSS_V66":   PN = "V66"  !CDS_PN = "V66";
"VSS_V71":   PN = "V71"  !CDS_PN = "V71";
"VSS_V73":   PN = "V73"  !CDS_PN = "V73";
"VSS_W1":   PN = "W1"  !CDS_PN = "W1";
"VSS_W4":   PN = "W4"  !CDS_PN = "W4";
"VSS_W6":   PN = "W6"  !CDS_PN = "W6";
"VSS_W8":   PN = "W8"  !CDS_PN = "W8";
"VSS_W11":   PN = "W11"  !CDS_PN = "W11";
"VSS_W13":   PN = "W13"  !CDS_PN = "W13";
"VSS_W15":   PN = "W15"  !CDS_PN = "W15";
"VSS_W18":   PN = "W18"  !CDS_PN = "W18";
"VSS_W20":   PN = "W20"  !CDS_PN = "W20";
"VSS_W22":   PN = "W22"  !CDS_PN = "W22";
"VSS_W25":   PN = "W25"  !CDS_PN = "W25";
"VSS_W28":   PN = "W28"  !CDS_PN = "W28";
"VSS_W34":   PN = "W34"  !CDS_PN = "W34";
"VSS_W35":   PN = "W35"  !CDS_PN = "W35";
"VSS_W36":   PN = "W36"  !CDS_PN = "W36";
"VSS_W40":   PN = "W40"  !CDS_PN = "W40";
"VSS_W41":   PN = "W41"  !CDS_PN = "W41";
"VSS_W42":   PN = "W42"  !CDS_PN = "W42";
"VSS_W45":   PN = "W45"  !CDS_PN = "W45";
"VSS_W48":   PN = "W48"  !CDS_PN = "W48";
"VSS_W51":   PN = "W51"  !CDS_PN = "W51";
"VSS_W54":   PN = "W54"  !CDS_PN = "W54";
"VSS_W56":   PN = "W56"  !CDS_PN = "W56";
"VSS_W58":   PN = "W58"  !CDS_PN = "W58";
"VSS_W61":   PN = "W61"  !CDS_PN = "W61";
"VSS_W63":   PN = "W63"  !CDS_PN = "W63";
"VSS_W65":   PN = "W65"  !CDS_PN = "W65";
"VSS_W68":   PN = "W68"  !CDS_PN = "W68";
"VSS_W70":   PN = "W70"  !CDS_PN = "W70";
"VSS_W72":   PN = "W72"  !CDS_PN = "W72";
"VSS_W75":   PN = "W75"  !CDS_PN = "W75";
"VSS_Y3":   PN = "Y3"  !CDS_PN = "Y3";
"VSS_Y8":   PN = "Y8"  !CDS_PN = "Y8";
"VSS_Y10":   PN = "Y10"  !CDS_PN = "Y10";
"VSS_Y15":   PN = "Y15"  !CDS_PN = "Y15";
"VSS_Y17":   PN = "Y17"  !CDS_PN = "Y17";
"VSS_Y22":   PN = "Y22"  !CDS_PN = "Y22";
"VSS_Y23":   PN = "Y23"  !CDS_PN = "Y23";
"VSS_Y24":   PN = "Y24"  !CDS_PN = "Y24";
"VSS_Y25":   PN = "Y25"  !CDS_PN = "Y25";
"VSS_Y26":   PN = "Y26"  !CDS_PN = "Y26";
"VSS_Y27":   PN = "Y27"  !CDS_PN = "Y27";
"VSS_Y28":   PN = "Y28"  !CDS_PN = "Y28";
"VSS_Y31":   PN = "Y31"  !CDS_PN = "Y31";
"VSS_Y32":   PN = "Y32"  !CDS_PN = "Y32";
"VSS_Y33":   PN = "Y33"  !CDS_PN = "Y33";
"VSS_Y34":   PN = "Y34"  !CDS_PN = "Y34";
"VSS_Y37":   PN = "Y37"  !CDS_PN = "Y37";
"VSS_Y39":   PN = "Y39"  !CDS_PN = "Y39";
"VSS_Y42":   PN = "Y42"  !CDS_PN = "Y42";
"VSS_Y43":   PN = "Y43"  !CDS_PN = "Y43";
"VSS_Y44":   PN = "Y44"  !CDS_PN = "Y44";
"VSS_Y45":   PN = "Y45"  !CDS_PN = "Y45";
"VSS_Y48":   PN = "Y48"  !CDS_PN = "Y48";
"VSS_Y49":   PN = "Y49"  !CDS_PN = "Y49";
"VSS_Y50":   PN = "Y50"  !CDS_PN = "Y50";
"VSS_Y51":   PN = "Y51"  !CDS_PN = "Y51";
"VSS_Y52":   PN = "Y52"  !CDS_PN = "Y52";
"VSS_Y53":   PN = "Y53"  !CDS_PN = "Y53";
"VSS_Y54":   PN = "Y54"  !CDS_PN = "Y54";
"VSS_Y59":   PN = "Y59"  !CDS_PN = "Y59";
"VSS_Y61":   PN = "Y61"  !CDS_PN = "Y61";
"VSS_Y66":   PN = "Y66"  !CDS_PN = "Y66";
"VSS_Y68":   PN = "Y68"  !CDS_PN = "Y68";
"VSS_Y73":   PN = "Y73"  !CDS_PN = "Y73";
BODY = "GENOA_SP5","I15": #LOCATION = "U26" !CDS_LOCATION = "U26" &SEC = "29" #&CDS_SEC = "29";
"VSS_J15":   PN = "J15"  !CDS_PN = "J15";
"VSS_J18":   PN = "J18"  !CDS_PN = "J18";
"VSS_J20":   PN = "J20"  !CDS_PN = "J20";
"VSS_J22":   PN = "J22"  !CDS_PN = "J22";
"VSS_J25":   PN = "J25"  !CDS_PN = "J25";
"VSS_J28":   PN = "J28"  !CDS_PN = "J28";
"VSS_J31":   PN = "J31"  !CDS_PN = "J31";
"VSS_J34":   PN = "J34"  !CDS_PN = "J34";
"VSS_J42":   PN = "J42"  !CDS_PN = "J42";
"VSS_J45":   PN = "J45"  !CDS_PN = "J45";
"VSS_J48":   PN = "J48"  !CDS_PN = "J48";
"VSS_J51":   PN = "J51"  !CDS_PN = "J51";
"VSS_J54":   PN = "J54"  !CDS_PN = "J54";
"VSS_J56":   PN = "J56"  !CDS_PN = "J56";
"VSS_J58":   PN = "J58"  !CDS_PN = "J58";
"VSS_J61":   PN = "J61"  !CDS_PN = "J61";
"VSS_J63":   PN = "J63"  !CDS_PN = "J63";
"VSS_J65":   PN = "J65"  !CDS_PN = "J65";
"VSS_J68":   PN = "J68"  !CDS_PN = "J68";
"VSS_J70":   PN = "J70"  !CDS_PN = "J70";
"VSS_J72":   PN = "J72"  !CDS_PN = "J72";
"VSS_J75":   PN = "J75"  !CDS_PN = "J75";
"VSS_K3":   PN = "K3"  !CDS_PN = "K3";
"VSS_K5":   PN = "K5"  !CDS_PN = "K5";
"VSS_K8":   PN = "K8"  !CDS_PN = "K8";
"VSS_K10":   PN = "K10"  !CDS_PN = "K10";
"VSS_K12":   PN = "K12"  !CDS_PN = "K12";
"VSS_K15":   PN = "K15"  !CDS_PN = "K15";
"VSS_K17":   PN = "K17"  !CDS_PN = "K17";
"VSS_K19":   PN = "K19"  !CDS_PN = "K19";
"VSS_K24":   PN = "K24"  !CDS_PN = "K24";
"VSS_K25":   PN = "K25"  !CDS_PN = "K25";
"VSS_K26":   PN = "K26"  !CDS_PN = "K26";
"VSS_K27":   PN = "K27"  !CDS_PN = "K27";
"VSS_K28":   PN = "K28"  !CDS_PN = "K28";
"VSS_K29":   PN = "K29"  !CDS_PN = "K29";
"VSS_K30":   PN = "K30"  !CDS_PN = "K30";
"VSS_K31":   PN = "K31"  !CDS_PN = "K31";
"VSS_K32":   PN = "K32"  !CDS_PN = "K32";
"VSS_K33":   PN = "K33"  !CDS_PN = "K33";
"VSS_K34":   PN = "K34"  !CDS_PN = "K34";
"VSS_K37":   PN = "K37"  !CDS_PN = "K37";
"VSS_K39":   PN = "K39"  !CDS_PN = "K39";
"VSS_K42":   PN = "K42"  !CDS_PN = "K42";
"VSS_K43":   PN = "K43"  !CDS_PN = "K43";
"VSS_K44":   PN = "K44"  !CDS_PN = "K44";
"VSS_K45":   PN = "K45"  !CDS_PN = "K45";
"VSS_K46":   PN = "K46"  !CDS_PN = "K46";
"VSS_K47":   PN = "K47"  !CDS_PN = "K47";
"VSS_K48":   PN = "K48"  !CDS_PN = "K48";
"VSS_K49":   PN = "K49"  !CDS_PN = "K49";
"VSS_K50":   PN = "K50"  !CDS_PN = "K50";
"VSS_K51":   PN = "K51"  !CDS_PN = "K51";
"VSS_K52":   PN = "K52"  !CDS_PN = "K52";
"VSS_K53":   PN = "K53"  !CDS_PN = "K53";
"VSS_K57":   PN = "K57"  !CDS_PN = "K57";
"VSS_K61":   PN = "K61"  !CDS_PN = "K61";
"VSS_K64":   PN = "K64"  !CDS_PN = "K64";
"VSS_K66":   PN = "K66"  !CDS_PN = "K66";
"VSS_K68":   PN = "K68"  !CDS_PN = "K68";
"VSS_K71":   PN = "K71"  !CDS_PN = "K71";
"VSS_K73":   PN = "K73"  !CDS_PN = "K73";
"VSS_L1":   PN = "L1"  !CDS_PN = "L1";
"VSS_L6":   PN = "L6"  !CDS_PN = "L6";
"VSS_L8":   PN = "L8"  !CDS_PN = "L8";
"VSS_L13":   PN = "L13"  !CDS_PN = "L13";
"VSS_L15":   PN = "L15"  !CDS_PN = "L15";
"VSS_L20":   PN = "L20"  !CDS_PN = "L20";
"VSS_L22":   PN = "L22"  !CDS_PN = "L22";
"VSS_L25":   PN = "L25"  !CDS_PN = "L25";
"VSS_L28":   PN = "L28"  !CDS_PN = "L28";
"VSS_L31":   PN = "L31"  !CDS_PN = "L31";
"VSS_L34":   PN = "L34"  !CDS_PN = "L34";
"VSS_L35":   PN = "L35"  !CDS_PN = "L35";
"VSS_L36":   PN = "L36"  !CDS_PN = "L36";
"VSS_L40":   PN = "L40"  !CDS_PN = "L40";
"VSS_L41":   PN = "L41"  !CDS_PN = "L41";
"VSS_L42":   PN = "L42"  !CDS_PN = "L42";
"VSS_L45":   PN = "L45"  !CDS_PN = "L45";
"VSS_L48":   PN = "L48"  !CDS_PN = "L48";
"VSS_L51":   PN = "L51"  !CDS_PN = "L51";
"VSS_L54":   PN = "L54"  !CDS_PN = "L54";
"VSS_L56":   PN = "L56"  !CDS_PN = "L56";
"VSS_L61":   PN = "L61"  !CDS_PN = "L61";
"VSS_L63":   PN = "L63"  !CDS_PN = "L63";
"VSS_L68":   PN = "L68"  !CDS_PN = "L68";
"VSS_L70":   PN = "L70"  !CDS_PN = "L70";
"VSS_L75":   PN = "L75"  !CDS_PN = "L75";
"VSS_M3":   PN = "M3"  !CDS_PN = "M3";
"VSS_M5":   PN = "M5"  !CDS_PN = "M5";
"VSS_M8":   PN = "M8"  !CDS_PN = "M8";
"VSS_M10":   PN = "M10"  !CDS_PN = "M10";
"VSS_M12":   PN = "M12"  !CDS_PN = "M12";
"VSS_M15":   PN = "M15"  !CDS_PN = "M15";
"VSS_M17":   PN = "M17"  !CDS_PN = "M17";
"VSS_M19":   PN = "M19"  !CDS_PN = "M19";
"VSS_M22":   PN = "M22"  !CDS_PN = "M22";
"VSS_M25":   PN = "M25"  !CDS_PN = "M25";
"VSS_M28":   PN = "M28"  !CDS_PN = "M28";
"VSS_M31":   PN = "M31"  !CDS_PN = "M31";
"VSS_M34":   PN = "M34"  !CDS_PN = "M34";
"VSS_M37":   PN = "M37"  !CDS_PN = "M37";
"VSS_M39":   PN = "M39"  !CDS_PN = "M39";
"VSS_M42":   PN = "M42"  !CDS_PN = "M42";
"VSS_M45":   PN = "M45"  !CDS_PN = "M45";
"VSS_M48":   PN = "M48"  !CDS_PN = "M48";
"VSS_M51":   PN = "M51"  !CDS_PN = "M51";
"VSS_M54":   PN = "M54"  !CDS_PN = "M54";
"VSS_M57":   PN = "M57"  !CDS_PN = "M57";
"VSS_M59":   PN = "M59"  !CDS_PN = "M59";
"VSS_M61":   PN = "M61"  !CDS_PN = "M61";
"VSS_M64":   PN = "M64"  !CDS_PN = "M64";
"VSS_M66":   PN = "M66"  !CDS_PN = "M66";
"VSS_M68":   PN = "M68"  !CDS_PN = "M68";
"VSS_M71":   PN = "M71"  !CDS_PN = "M71";
"VSS_M73":   PN = "M73"  !CDS_PN = "M73";
"VSS_N1":   PN = "N1"  !CDS_PN = "N1";
"VSS_N4":   PN = "N4"  !CDS_PN = "N4";
"VSS_N6":   PN = "N6"  !CDS_PN = "N6";
"VSS_N8":   PN = "N8"  !CDS_PN = "N8";
"VSS_N11":   PN = "N11"  !CDS_PN = "N11";
"VSS_N13":   PN = "N13"  !CDS_PN = "N13";
"VSS_N15":   PN = "N15"  !CDS_PN = "N15";
"VSS_N18":   PN = "N18"  !CDS_PN = "N18";
"VSS_N20":   PN = "N20"  !CDS_PN = "N20";
"VSS_N22":   PN = "N22"  !CDS_PN = "N22";
"VSS_N25":   PN = "N25"  !CDS_PN = "N25";
"VSS_N28":   PN = "N28"  !CDS_PN = "N28";
"VSS_N31":   PN = "N31"  !CDS_PN = "N31";
"VSS_N34":   PN = "N34"  !CDS_PN = "N34";
"VSS_N42":   PN = "N42"  !CDS_PN = "N42";
"VSS_N45":   PN = "N45"  !CDS_PN = "N45";
"VSS_N48":   PN = "N48"  !CDS_PN = "N48";
"VSS_N51":   PN = "N51"  !CDS_PN = "N51";
"VSS_N54":   PN = "N54"  !CDS_PN = "N54";
"VSS_N56":   PN = "N56"  !CDS_PN = "N56";
"VSS_N58":   PN = "N58"  !CDS_PN = "N58";
"VSS_N61":   PN = "N61"  !CDS_PN = "N61";
"VSS_N63":   PN = "N63"  !CDS_PN = "N63";
"VSS_N65":   PN = "N65"  !CDS_PN = "N65";
"VSS_N68":   PN = "N68"  !CDS_PN = "N68";
"VSS_N70":   PN = "N70"  !CDS_PN = "N70";
"VSS_N72":   PN = "N72"  !CDS_PN = "N72";
"VSS_N75":   PN = "N75"  !CDS_PN = "N75";
"VSS_P3":   PN = "P3"  !CDS_PN = "P3";
"VSS_P8":   PN = "P8"  !CDS_PN = "P8";
"VSS_P10":   PN = "P10"  !CDS_PN = "P10";
"VSS_P15":   PN = "P15"  !CDS_PN = "P15";
"VSS_P17":   PN = "P17"  !CDS_PN = "P17";
"VSS_P23":   PN = "P23"  !CDS_PN = "P23";
"VSS_P24":   PN = "P24"  !CDS_PN = "P24";
"VSS_P26":   PN = "P26"  !CDS_PN = "P26";
"VSS_P27":   PN = "P27"  !CDS_PN = "P27";
"VSS_P28":   PN = "P28"  !CDS_PN = "P28";
"VSS_P29":   PN = "P29"  !CDS_PN = "P29";
"VSS_P30":   PN = "P30"  !CDS_PN = "P30";
"VSS_P31":   PN = "P31"  !CDS_PN = "P31";
"VSS_P32":   PN = "P32"  !CDS_PN = "P32";
"VSS_P33":   PN = "P33"  !CDS_PN = "P33";
"VSS_P34":   PN = "P34"  !CDS_PN = "P34";
"VSS_P37":   PN = "P37"  !CDS_PN = "P37";
"VSS_P39":   PN = "P39"  !CDS_PN = "P39";
"VSS_P42":   PN = "P42"  !CDS_PN = "P42";
"VSS_P43":   PN = "P43"  !CDS_PN = "P43";
"VSS_P44":   PN = "P44"  !CDS_PN = "P44";
"VSS_P45":   PN = "P45"  !CDS_PN = "P45";
"VSS_P46":   PN = "P46"  !CDS_PN = "P46";
"VSS_P47":   PN = "P47"  !CDS_PN = "P47";
"VSS_P48":   PN = "P48"  !CDS_PN = "P48";
"VSS_P49":   PN = "P49"  !CDS_PN = "P49";
"VSS_P50":   PN = "P50"  !CDS_PN = "P50";
"VSS_P51":   PN = "P51"  !CDS_PN = "P51";
"VSS_P52":   PN = "P52"  !CDS_PN = "P52";
"VSS_P53":   PN = "P53"  !CDS_PN = "P53";
"VSS_P59":   PN = "P59"  !CDS_PN = "P59";
"VSS_P61":   PN = "P61"  !CDS_PN = "P61";
"VSS_P66":   PN = "P66"  !CDS_PN = "P66";
"VSS_P73":   PN = "P73"  !CDS_PN = "P73";
"VSS_R1":   PN = "R1"  !CDS_PN = "R1";
"VSS_R4":   PN = "R4"  !CDS_PN = "R4";
"VSS_R6":   PN = "R6"  !CDS_PN = "R6";
"VSS_R8":   PN = "R8"  !CDS_PN = "R8";
"VSS_R11":   PN = "R11"  !CDS_PN = "R11";
"VSS_R13":   PN = "R13"  !CDS_PN = "R13";
"VSS_R15":   PN = "R15"  !CDS_PN = "R15";
"VSS_R18":   PN = "R18"  !CDS_PN = "R18";
"VSS_R20":   PN = "R20"  !CDS_PN = "R20";
"VSS_R22":   PN = "R22"  !CDS_PN = "R22";
"VSS_R25":   PN = "R25"  !CDS_PN = "R25";
"VSS_R28":   PN = "R28"  !CDS_PN = "R28";
"VSS_R31":   PN = "R31"  !CDS_PN = "R31";
"VSS_R34":   PN = "R34"  !CDS_PN = "R34";
"VSS_R35":   PN = "R35"  !CDS_PN = "R35";
"VSS_R36":   PN = "R36"  !CDS_PN = "R36";
"VSS_R40":   PN = "R40"  !CDS_PN = "R40";
"VSS_R41":   PN = "R41"  !CDS_PN = "R41";
"VSS_R42":   PN = "R42"  !CDS_PN = "R42";
"VSS_R45":   PN = "R45"  !CDS_PN = "R45";
"VSS_R48":   PN = "R48"  !CDS_PN = "R48";
"VSS_R51":   PN = "R51"  !CDS_PN = "R51";
"VSS_R54":   PN = "R54"  !CDS_PN = "R54";
"VSS_R56":   PN = "R56"  !CDS_PN = "R56";
"VSS_R58":   PN = "R58"  !CDS_PN = "R58";
"VSS_R61":   PN = "R61"  !CDS_PN = "R61";
"VSS_R63":   PN = "R63"  !CDS_PN = "R63";
"VSS_R65":   PN = "R65"  !CDS_PN = "R65";
"VSS_R68":   PN = "R68"  !CDS_PN = "R68";
"VSS_R70":   PN = "R70"  !CDS_PN = "R70";
"VSS_R72":   PN = "R72"  !CDS_PN = "R72";
"VSS_R75":   PN = "R75"  !CDS_PN = "R75";
"VSS_T3":   PN = "T3"  !CDS_PN = "T3";
"VSS_T5":   PN = "T5"  !CDS_PN = "T5";
"VSS_T8":   PN = "T8"  !CDS_PN = "T8";
"VSS_T10":   PN = "T10"  !CDS_PN = "T10";
"VSS_T12":   PN = "T12"  !CDS_PN = "T12";
"VSS_T15":   PN = "T15"  !CDS_PN = "T15";
"VSS_T17":   PN = "T17"  !CDS_PN = "T17";
"VSS_T19":   PN = "T19"  !CDS_PN = "T19";
"VSS_T22":   PN = "T22"  !CDS_PN = "T22";
"VSS_T25":   PN = "T25"  !CDS_PN = "T25";
"VSS_T28":   PN = "T28"  !CDS_PN = "T28";
"VSS_T31":   PN = "T31"  !CDS_PN = "T31";
"VSS_T34":   PN = "T34"  !CDS_PN = "T34";
"VSS_T37":   PN = "T37"  !CDS_PN = "T37";
"VSS_T39":   PN = "T39"  !CDS_PN = "T39";
"VSS_T42":   PN = "T42"  !CDS_PN = "T42";
"VSS_T45":   PN = "T45"  !CDS_PN = "T45";
"VSS_T48":   PN = "T48"  !CDS_PN = "T48";
"VSS_T51":   PN = "T51"  !CDS_PN = "T51";
"VSS_T54":   PN = "T54"  !CDS_PN = "T54";
"VSS_T57":   PN = "T57"  !CDS_PN = "T57";
"VSS_T59":   PN = "T59"  !CDS_PN = "T59";
"VSS_T61":   PN = "T61"  !CDS_PN = "T61";
"VSS_T64":   PN = "T64"  !CDS_PN = "T64";
DRAWING = "@t6g_mb_lib.t6g(sch_1):page59";
BODY = "GENOA_SP5","I1": #LOCATION = "U26" !CDS_LOCATION = "U26" &SEC = "34" #&CDS_SEC = "34";
"VSS_BL26":   PN = "BL26"  !CDS_PN = "BL26";
"VSS_BL28":   PN = "BL28"  !CDS_PN = "BL28";
"VSS_BL49":   PN = "BL49"  !CDS_PN = "BL49";
"VSS_BL51":   PN = "BL51"  !CDS_PN = "BL51";
"VSS_BL53":   PN = "BL53"  !CDS_PN = "BL53";
"VSS_BL56":   PN = "BL56"  !CDS_PN = "BL56";
"VSS_BL58":   PN = "BL58"  !CDS_PN = "BL58";
"VSS_BL61":   PN = "BL61"  !CDS_PN = "BL61";
"VSS_BL63":   PN = "BL63"  !CDS_PN = "BL63";
"VSS_BL65":   PN = "BL65"  !CDS_PN = "BL65";
"VSS_BL68":   PN = "BL68"  !CDS_PN = "BL68";
"VSS_BL70":   PN = "BL70"  !CDS_PN = "BL70";
"VSS_BL72":   PN = "BL72"  !CDS_PN = "BL72";
"VSS_BL75":   PN = "BL75"  !CDS_PN = "BL75";
"VSS_BM3":   PN = "BM3"  !CDS_PN = "BM3";
"VSS_BM8":   PN = "BM8"  !CDS_PN = "BM8";
"VSS_BM10":   PN = "BM10"  !CDS_PN = "BM10";
"VSS_BM15":   PN = "BM15"  !CDS_PN = "BM15";
"VSS_BM17":   PN = "BM17"  !CDS_PN = "BM17";
"VSS_BM23":   PN = "BM23"  !CDS_PN = "BM23";
"VSS_BM25":   PN = "BM25"  !CDS_PN = "BM25";
"VSS_BM27":   PN = "BM27"  !CDS_PN = "BM27";
"VSS_BM29":   PN = "BM29"  !CDS_PN = "BM29";
"VSS_BM31":   PN = "BM31"  !CDS_PN = "BM31";
"VSS_BM33":   PN = "BM33"  !CDS_PN = "BM33";
"VSS_BM35":   PN = "BM35"  !CDS_PN = "BM35";
"VSS_BM37":   PN = "BM37"  !CDS_PN = "BM37";
"VSS_BM40":   PN = "BM40"  !CDS_PN = "BM40";
"VSS_BM42":   PN = "BM42"  !CDS_PN = "BM42";
"VSS_BM44":   PN = "BM44"  !CDS_PN = "BM44";
"VSS_BM46":   PN = "BM46"  !CDS_PN = "BM46";
"VSS_BM48":   PN = "BM48"  !CDS_PN = "BM48";
"VSS_BM50":   PN = "BM50"  !CDS_PN = "BM50";
"VSS_BM52":   PN = "BM52"  !CDS_PN = "BM52";
"VSS_BM54":   PN = "BM54"  !CDS_PN = "BM54";
"VSS_BM59":   PN = "BM59"  !CDS_PN = "BM59";
"VSS_BM61":   PN = "BM61"  !CDS_PN = "BM61";
"VSS_BM66":   PN = "BM66"  !CDS_PN = "BM66";
"VSS_BM68":   PN = "BM68"  !CDS_PN = "BM68";
"VSS_BM73":   PN = "BM73"  !CDS_PN = "BM73";
"VSS_BN1":   PN = "BN1"  !CDS_PN = "BN1";
"VSS_BN4":   PN = "BN4"  !CDS_PN = "BN4";
"VSS_BN6":   PN = "BN6"  !CDS_PN = "BN6";
"VSS_BN8":   PN = "BN8"  !CDS_PN = "BN8";
"VSS_BN11":   PN = "BN11"  !CDS_PN = "BN11";
"VSS_BN13":   PN = "BN13"  !CDS_PN = "BN13";
"VSS_BN15":   PN = "BN15"  !CDS_PN = "BN15";
"VSS_BN18":   PN = "BN18"  !CDS_PN = "BN18";
"VSS_BN20":   PN = "BN20"  !CDS_PN = "BN20";
"VSS_BN22":   PN = "BN22"  !CDS_PN = "BN22";
"VSS_BN24":   PN = "BN24"  !CDS_PN = "BN24";
"VSS_BN26":   PN = "BN26"  !CDS_PN = "BN26";
"VSS_BN28":   PN = "BN28"  !CDS_PN = "BN28";
"VSS_BN30":   PN = "BN30"  !CDS_PN = "BN30";
"VSS_BN32":   PN = "BN32"  !CDS_PN = "BN32";
"VSS_BN34":   PN = "BN34"  !CDS_PN = "BN34";
"VSS_BN36":   PN = "BN36"  !CDS_PN = "BN36";
"VSS_BN41":   PN = "BN41"  !CDS_PN = "BN41";
"VSS_BN43":   PN = "BN43"  !CDS_PN = "BN43";
"VSS_BN45":   PN = "BN45"  !CDS_PN = "BN45";
"VSS_BN47":   PN = "BN47"  !CDS_PN = "BN47";
"VSS_BN49":   PN = "BN49"  !CDS_PN = "BN49";
"VSS_BN51":   PN = "BN51"  !CDS_PN = "BN51";
"VSS_BN53":   PN = "BN53"  !CDS_PN = "BN53";
"VSS_BN56":   PN = "BN56"  !CDS_PN = "BN56";
"VSS_BN58":   PN = "BN58"  !CDS_PN = "BN58";
"VSS_BN61":   PN = "BN61"  !CDS_PN = "BN61";
"VSS_BN63":   PN = "BN63"  !CDS_PN = "BN63";
"VSS_BN65":   PN = "BN65"  !CDS_PN = "BN65";
"VSS_BN68":   PN = "BN68"  !CDS_PN = "BN68";
"VSS_BN70":   PN = "BN70"  !CDS_PN = "BN70";
"VSS_BN72":   PN = "BN72"  !CDS_PN = "BN72";
"VSS_BN75":   PN = "BN75"  !CDS_PN = "BN75";
"VSS_BP3":   PN = "BP3"  !CDS_PN = "BP3";
"VSS_BP5":   PN = "BP5"  !CDS_PN = "BP5";
"VSS_BP8":   PN = "BP8"  !CDS_PN = "BP8";
"VSS_BP10":   PN = "BP10"  !CDS_PN = "BP10";
"VSS_BP12":   PN = "BP12"  !CDS_PN = "BP12";
"VSS_BP15":   PN = "BP15"  !CDS_PN = "BP15";
"VSS_BP17":   PN = "BP17"  !CDS_PN = "BP17";
"VSS_BP19":   PN = "BP19"  !CDS_PN = "BP19";
"VSS_BP23":   PN = "BP23"  !CDS_PN = "BP23";
"VSS_BP25":   PN = "BP25"  !CDS_PN = "BP25";
"VSS_BP27":   PN = "BP27"  !CDS_PN = "BP27";
"VSS_BP29":   PN = "BP29"  !CDS_PN = "BP29";
"VSS_BP31":   PN = "BP31"  !CDS_PN = "BP31";
"VSS_BP33":   PN = "BP33"  !CDS_PN = "BP33";
"VSS_BP35":   PN = "BP35"  !CDS_PN = "BP35";
"VSS_BP37":   PN = "BP37"  !CDS_PN = "BP37";
"VSS_BP40":   PN = "BP40"  !CDS_PN = "BP40";
"VSS_BP42":   PN = "BP42"  !CDS_PN = "BP42";
"VSS_BP44":   PN = "BP44"  !CDS_PN = "BP44";
"VSS_BP46":   PN = "BP46"  !CDS_PN = "BP46";
"VSS_BP48":   PN = "BP48"  !CDS_PN = "BP48";
"VSS_BP50":   PN = "BP50"  !CDS_PN = "BP50";
"VSS_BP52":   PN = "BP52"  !CDS_PN = "BP52";
"VSS_BP54":   PN = "BP54"  !CDS_PN = "BP54";
"VSS_BP57":   PN = "BP57"  !CDS_PN = "BP57";
"VSS_BP59":   PN = "BP59"  !CDS_PN = "BP59";
"VSS_BP61":   PN = "BP61"  !CDS_PN = "BP61";
"VSS_BP64":   PN = "BP64"  !CDS_PN = "BP64";
"VSS_BP66":   PN = "BP66"  !CDS_PN = "BP66";
"VSS_BP68":   PN = "BP68"  !CDS_PN = "BP68";
"VSS_BP71":   PN = "BP71"  !CDS_PN = "BP71";
"VSS_BP73":   PN = "BP73"  !CDS_PN = "BP73";
"VSS_BR1":   PN = "BR1"  !CDS_PN = "BR1";
"VSS_BR3":   PN = "BR3"  !CDS_PN = "BR3";
"VSS_BR6":   PN = "BR6"  !CDS_PN = "BR6";
"VSS_BR7":   PN = "BR7"  !CDS_PN = "BR7";
"VSS_BR8":   PN = "BR8"  !CDS_PN = "BR8";
"VSS_BR10":   PN = "BR10"  !CDS_PN = "BR10";
"VSS_BR13":   PN = "BR13"  !CDS_PN = "BR13";
"VSS_BR14":   PN = "BR14"  !CDS_PN = "BR14";
"VSS_BR15":   PN = "BR15"  !CDS_PN = "BR15";
"VSS_BR17":   PN = "BR17"  !CDS_PN = "BR17";
"VSS_BR20":   PN = "BR20"  !CDS_PN = "BR20";
"VSS_BR21":   PN = "BR21"  !CDS_PN = "BR21";
"VSS_BR22":   PN = "BR22"  !CDS_PN = "BR22";
"VSS_BR24":   PN = "BR24"  !CDS_PN = "BR24";
"VSS_BR26":   PN = "BR26"  !CDS_PN = "BR26";
"VSS_BR28":   PN = "BR28"  !CDS_PN = "BR28";
"VSS_BR30":   PN = "BR30"  !CDS_PN = "BR30";
"VSS_BR32":   PN = "BR32"  !CDS_PN = "BR32";
"VSS_BR34":   PN = "BR34"  !CDS_PN = "BR34";
"VSS_BR36":   PN = "BR36"  !CDS_PN = "BR36";
"VSS_BR41":   PN = "BR41"  !CDS_PN = "BR41";
"VSS_BR43":   PN = "BR43"  !CDS_PN = "BR43";
"VSS_BR45":   PN = "BR45"  !CDS_PN = "BR45";
"VSS_BR47":   PN = "BR47"  !CDS_PN = "BR47";
"VSS_BR49":   PN = "BR49"  !CDS_PN = "BR49";
"VSS_BR51":   PN = "BR51"  !CDS_PN = "BR51";
"VSS_BR55":   PN = "BR55"  !CDS_PN = "BR55";
"VSS_BR56":   PN = "BR56"  !CDS_PN = "BR56";
"VSS_BR59":   PN = "BR59"  !CDS_PN = "BR59";
"VSS_BR61":   PN = "BR61"  !CDS_PN = "BR61";
"VSS_BR62":   PN = "BR62"  !CDS_PN = "BR62";
"VSS_BR63":   PN = "BR63"  !CDS_PN = "BR63";
"VSS_BR66":   PN = "BR66"  !CDS_PN = "BR66";
"VSS_BR68":   PN = "BR68"  !CDS_PN = "BR68";
"VSS_BR69":   PN = "BR69"  !CDS_PN = "BR69";
"VSS_BR70":   PN = "BR70"  !CDS_PN = "BR70";
"VSS_BR73":   PN = "BR73"  !CDS_PN = "BR73";
"VSS_BR75":   PN = "BR75"  !CDS_PN = "BR75";
"VSS_BT3":   PN = "BT3"  !CDS_PN = "BT3";
"VSS_BT4":   PN = "BT4"  !CDS_PN = "BT4";
"VSS_BT5":   PN = "BT5"  !CDS_PN = "BT5";
"VSS_BT7":   PN = "BT7"  !CDS_PN = "BT7";
"VSS_BT8":   PN = "BT8"  !CDS_PN = "BT8";
"VSS_BT10":   PN = "BT10"  !CDS_PN = "BT10";
"VSS_BT11":   PN = "BT11"  !CDS_PN = "BT11";
"VSS_BT12":   PN = "BT12"  !CDS_PN = "BT12";
"VSS_BT14":   PN = "BT14"  !CDS_PN = "BT14";
"VSS_BT15":   PN = "BT15"  !CDS_PN = "BT15";
"VSS_BT17":   PN = "BT17"  !CDS_PN = "BT17";
"VSS_BT18":   PN = "BT18"  !CDS_PN = "BT18";
"VSS_BT19":   PN = "BT19"  !CDS_PN = "BT19";
"VSS_BT21":   PN = "BT21"  !CDS_PN = "BT21";
"VSS_BT22":   PN = "BT22"  !CDS_PN = "BT22";
"VSS_BT25":   PN = "BT25"  !CDS_PN = "BT25";
"VSS_BT28":   PN = "BT28"  !CDS_PN = "BT28";
"VSS_BT31":   PN = "BT31"  !CDS_PN = "BT31";
"VSS_BT34":   PN = "BT34"  !CDS_PN = "BT34";
"VSS_BT37":   PN = "BT37"  !CDS_PN = "BT37";
"VSS_BT39":   PN = "BT39"  !CDS_PN = "BT39";
"VSS_BT42":   PN = "BT42"  !CDS_PN = "BT42";
"VSS_BT45":   PN = "BT45"  !CDS_PN = "BT45";
"VSS_BT48":   PN = "BT48"  !CDS_PN = "BT48";
"VSS_BT51":   PN = "BT51"  !CDS_PN = "BT51";
"VSS_BT54":   PN = "BT54"  !CDS_PN = "BT54";
"VSS_BT55":   PN = "BT55"  !CDS_PN = "BT55";
"VSS_BT57":   PN = "BT57"  !CDS_PN = "BT57";
"VSS_BT58":   PN = "BT58"  !CDS_PN = "BT58";
"VSS_BT59":   PN = "BT59"  !CDS_PN = "BT59";
"VSS_BT61":   PN = "BT61"  !CDS_PN = "BT61";
"VSS_BT62":   PN = "BT62"  !CDS_PN = "BT62";
"VSS_BT64":   PN = "BT64"  !CDS_PN = "BT64";
"VSS_BT65":   PN = "BT65"  !CDS_PN = "BT65";
"VSS_BT66":   PN = "BT66"  !CDS_PN = "BT66";
"VSS_BT68":   PN = "BT68"  !CDS_PN = "BT68";
"VSS_BT69":   PN = "BT69"  !CDS_PN = "BT69";
"VSS_BT71":   PN = "BT71"  !CDS_PN = "BT71";
"VSS_BT72":   PN = "BT72"  !CDS_PN = "BT72";
"VSS_BT73":   PN = "BT73"  !CDS_PN = "BT73";
"VSS_BU1":   PN = "BU1"  !CDS_PN = "BU1";
"VSS_BU4":   PN = "BU4"  !CDS_PN = "BU4";
"VSS_BU6":   PN = "BU6"  !CDS_PN = "BU6";
"VSS_BU8":   PN = "BU8"  !CDS_PN = "BU8";
"VSS_BU11":   PN = "BU11"  !CDS_PN = "BU11";
"VSS_BU13":   PN = "BU13"  !CDS_PN = "BU13";
"VSS_BU15":   PN = "BU15"  !CDS_PN = "BU15";
"VSS_BU18":   PN = "BU18"  !CDS_PN = "BU18";
"VSS_BU20":   PN = "BU20"  !CDS_PN = "BU20";
"VSS_BU22":   PN = "BU22"  !CDS_PN = "BU22";
"VSS_BU25":   PN = "BU25"  !CDS_PN = "BU25";
"VSS_BU28":   PN = "BU28"  !CDS_PN = "BU28";
"VSS_BU31":   PN = "BU31"  !CDS_PN = "BU31";
"VSS_BU34":   PN = "BU34"  !CDS_PN = "BU34";
"VSS_BU35":   PN = "BU35"  !CDS_PN = "BU35";
"VSS_BU36":   PN = "BU36"  !CDS_PN = "BU36";
"VSS_BU40":   PN = "BU40"  !CDS_PN = "BU40";
"VSS_BU41":   PN = "BU41"  !CDS_PN = "BU41";
"VSS_BU42":   PN = "BU42"  !CDS_PN = "BU42";
"VSS_BU45":   PN = "BU45"  !CDS_PN = "BU45";
"VSS_BU48":   PN = "BU48"  !CDS_PN = "BU48";
"VSS_BU51":   PN = "BU51"  !CDS_PN = "BU51";
"VSS_BU54":   PN = "BU54"  !CDS_PN = "BU54";
"VSS_BU56":   PN = "BU56"  !CDS_PN = "BU56";
"VSS_BU58":   PN = "BU58"  !CDS_PN = "BU58";
"VSS_BU61":   PN = "BU61"  !CDS_PN = "BU61";
"VSS_BU63":   PN = "BU63"  !CDS_PN = "BU63";
"VSS_BU65":   PN = "BU65"  !CDS_PN = "BU65";
"VSS_BU68":   PN = "BU68"  !CDS_PN = "BU68";
"VSS_BU70":   PN = "BU70"  !CDS_PN = "BU70";
"VSS_BU72":   PN = "BU72"  !CDS_PN = "BU72";
"VSS_BU75":   PN = "BU75"  !CDS_PN = "BU75";
"VSS_BV3":   PN = "BV3"  !CDS_PN = "BV3";
"VSS_BV8":   PN = "BV8"  !CDS_PN = "BV8";
"VSS_BV10":   PN = "BV10"  !CDS_PN = "BV10";
"VSS_BV15":   PN = "BV15"  !CDS_PN = "BV15";
"VSS_BV17":   PN = "BV17"  !CDS_PN = "BV17";
"VSS_BV23":   PN = "BV23"  !CDS_PN = "BV23";
"VSS_BV24":   PN = "BV24"  !CDS_PN = "BV24";
"VSS_BV25":   PN = "BV25"  !CDS_PN = "BV25";
"VSS_BV26":   PN = "BV26"  !CDS_PN = "BV26";
"VSS_BV27":   PN = "BV27"  !CDS_PN = "BV27";
"VSS_BV28":   PN = "BV28"  !CDS_PN = "BV28";
"VSS_BV29":   PN = "BV29"  !CDS_PN = "BV29";
"VSS_BV30":   PN = "BV30"  !CDS_PN = "BV30";
"VSS_BV31":   PN = "BV31"  !CDS_PN = "BV31";
"VSS_BV32":   PN = "BV32"  !CDS_PN = "BV32";
"VSS_BV33":   PN = "BV33"  !CDS_PN = "BV33";
"VSS_BV34":   PN = "BV34"  !CDS_PN = "BV34";
"VSS_BV37":   PN = "BV37"  !CDS_PN = "BV37";
"VSS_BV39":   PN = "BV39"  !CDS_PN = "BV39";
"VSS_BV43":   PN = "BV43"  !CDS_PN = "BV43";
"VSS_BV44":   PN = "BV44"  !CDS_PN = "BV44";
"VSS_BV45":   PN = "BV45"  !CDS_PN = "BV45";
BODY = "GENOA_SP5","I2": #LOCATION = "U26" !CDS_LOCATION = "U26" &SEC = "37" #&CDS_SEC = "37";
"VSS_BV46":   PN = "BV46"  !CDS_PN = "BV46";
"VSS_BV47":   PN = "BV47"  !CDS_PN = "BV47";
"VSS_BV48":   PN = "BV48"  !CDS_PN = "BV48";
"VSS_BV49":   PN = "BV49"  !CDS_PN = "BV49";
"VSS_BV50":   PN = "BV50"  !CDS_PN = "BV50";
"VSS_BV51":   PN = "BV51"  !CDS_PN = "BV51";
"VSS_BV52":   PN = "BV52"  !CDS_PN = "BV52";
"VSS_BV53":   PN = "BV53"  !CDS_PN = "BV53";
"VSS_BV59":   PN = "BV59"  !CDS_PN = "BV59";
"VSS_BV61":   PN = "BV61"  !CDS_PN = "BV61";
"VSS_BV66":   PN = "BV66"  !CDS_PN = "BV66";
"VSS_BV68":   PN = "BV68"  !CDS_PN = "BV68";
"VSS_BV73":   PN = "BV73"  !CDS_PN = "BV73";
"VSS_BW1":   PN = "BW1"  !CDS_PN = "BW1";
"VSS_BW4":   PN = "BW4"  !CDS_PN = "BW4";
"VSS_BW6":   PN = "BW6"  !CDS_PN = "BW6";
"VSS_BW8":   PN = "BW8"  !CDS_PN = "BW8";
"VSS_BW11":   PN = "BW11"  !CDS_PN = "BW11";
"VSS_BW13":   PN = "BW13"  !CDS_PN = "BW13";
"VSS_BW15":   PN = "BW15"  !CDS_PN = "BW15";
"VSS_BW18":   PN = "BW18"  !CDS_PN = "BW18";
"VSS_BW20":   PN = "BW20"  !CDS_PN = "BW20";
"VSS_BW22":   PN = "BW22"  !CDS_PN = "BW22";
"VSS_BW28":   PN = "BW28"  !CDS_PN = "BW28";
"VSS_BW31":   PN = "BW31"  !CDS_PN = "BW31";
"VSS_BW34":   PN = "BW34"  !CDS_PN = "BW34";
"VSS_BW42":   PN = "BW42"  !CDS_PN = "BW42";
"VSS_BW45":   PN = "BW45"  !CDS_PN = "BW45";
"VSS_BW48":   PN = "BW48"  !CDS_PN = "BW48";
"VSS_BW51":   PN = "BW51"  !CDS_PN = "BW51";
"VSS_BW54":   PN = "BW54"  !CDS_PN = "BW54";
"VSS_BW56":   PN = "BW56"  !CDS_PN = "BW56";
"VSS_BW58":   PN = "BW58"  !CDS_PN = "BW58";
"VSS_BW61":   PN = "BW61"  !CDS_PN = "BW61";
"VSS_BW63":   PN = "BW63"  !CDS_PN = "BW63";
"VSS_BW65":   PN = "BW65"  !CDS_PN = "BW65";
"VSS_BW68":   PN = "BW68"  !CDS_PN = "BW68";
"VSS_BW70":   PN = "BW70"  !CDS_PN = "BW70";
"VSS_BW72":   PN = "BW72"  !CDS_PN = "BW72";
"VSS_BW75":   PN = "BW75"  !CDS_PN = "BW75";
"VSS_BY3":   PN = "BY3"  !CDS_PN = "BY3";
"VSS_BY5":   PN = "BY5"  !CDS_PN = "BY5";
"VSS_BY8":   PN = "BY8"  !CDS_PN = "BY8";
"VSS_BY10":   PN = "BY10"  !CDS_PN = "BY10";
"VSS_BY12":   PN = "BY12"  !CDS_PN = "BY12";
"VSS_BY15":   PN = "BY15"  !CDS_PN = "BY15";
"VSS_BY17":   PN = "BY17"  !CDS_PN = "BY17";
"VSS_BY19":   PN = "BY19"  !CDS_PN = "BY19";
"VSS_BY22":   PN = "BY22"  !CDS_PN = "BY22";
"VSS_BY25":   PN = "BY25"  !CDS_PN = "BY25";
"VSS_BY28":   PN = "BY28"  !CDS_PN = "BY28";
"VSS_BY31":   PN = "BY31"  !CDS_PN = "BY31";
"VSS_BY34":   PN = "BY34"  !CDS_PN = "BY34";
"VSS_BY37":   PN = "BY37"  !CDS_PN = "BY37";
"VSS_BY39":   PN = "BY39"  !CDS_PN = "BY39";
"VSS_BY42":   PN = "BY42"  !CDS_PN = "BY42";
"VSS_BY45":   PN = "BY45"  !CDS_PN = "BY45";
"VSS_BY48":   PN = "BY48"  !CDS_PN = "BY48";
"VSS_BY51":   PN = "BY51"  !CDS_PN = "BY51";
"VSS_BY54":   PN = "BY54"  !CDS_PN = "BY54";
"VSS_BY57":   PN = "BY57"  !CDS_PN = "BY57";
"VSS_BY59":   PN = "BY59"  !CDS_PN = "BY59";
"VSS_BY61":   PN = "BY61"  !CDS_PN = "BY61";
"VSS_BY64":   PN = "BY64"  !CDS_PN = "BY64";
"VSS_BY66":   PN = "BY66"  !CDS_PN = "BY66";
"VSS_BY68":   PN = "BY68"  !CDS_PN = "BY68";
"VSS_BY71":   PN = "BY71"  !CDS_PN = "BY71";
"VSS_BY73":   PN = "BY73"  !CDS_PN = "BY73";
"VSS_CA1":   PN = "CA1"  !CDS_PN = "CA1";
"VSS_CA6":   PN = "CA6"  !CDS_PN = "CA6";
"VSS_CA8":   PN = "CA8"  !CDS_PN = "CA8";
"VSS_CA13":   PN = "CA13"  !CDS_PN = "CA13";
"VSS_CA15":   PN = "CA15"  !CDS_PN = "CA15";
"VSS_CA20":   PN = "CA20"  !CDS_PN = "CA20";
"VSS_CA22":   PN = "CA22"  !CDS_PN = "CA22";
"VSS_CA25":   PN = "CA25"  !CDS_PN = "CA25";
"VSS_CA28":   PN = "CA28"  !CDS_PN = "CA28";
"VSS_CA31":   PN = "CA31"  !CDS_PN = "CA31";
"VSS_CA34":   PN = "CA34"  !CDS_PN = "CA34";
"VSS_CA35":   PN = "CA35"  !CDS_PN = "CA35";
"VSS_CA36":   PN = "CA36"  !CDS_PN = "CA36";
"VSS_CA40":   PN = "CA40"  !CDS_PN = "CA40";
"VSS_CA41":   PN = "CA41"  !CDS_PN = "CA41";
"VSS_CA42":   PN = "CA42"  !CDS_PN = "CA42";
"VSS_CA45":   PN = "CA45"  !CDS_PN = "CA45";
"VSS_CA48":   PN = "CA48"  !CDS_PN = "CA48";
"VSS_CA51":   PN = "CA51"  !CDS_PN = "CA51";
"VSS_CA54":   PN = "CA54"  !CDS_PN = "CA54";
"VSS_CA56":   PN = "CA56"  !CDS_PN = "CA56";
"VSS_CA61":   PN = "CA61"  !CDS_PN = "CA61";
"VSS_CA63":   PN = "CA63"  !CDS_PN = "CA63";
"VSS_CA68":   PN = "CA68"  !CDS_PN = "CA68";
"VSS_CA70":   PN = "CA70"  !CDS_PN = "CA70";
"VSS_CA75":   PN = "CA75"  !CDS_PN = "CA75";
"VSS_CB3":   PN = "CB3"  !CDS_PN = "CB3";
"VSS_CB5":   PN = "CB5"  !CDS_PN = "CB5";
"VSS_CB8":   PN = "CB8"  !CDS_PN = "CB8";
"VSS_CB10":   PN = "CB10"  !CDS_PN = "CB10";
"VSS_CB12":   PN = "CB12"  !CDS_PN = "CB12";
"VSS_CB15":   PN = "CB15"  !CDS_PN = "CB15";
"VSS_CB17":   PN = "CB17"  !CDS_PN = "CB17";
"VSS_CB19":   PN = "CB19"  !CDS_PN = "CB19";
"VSS_CB23":   PN = "CB23"  !CDS_PN = "CB23";
"VSS_CB24":   PN = "CB24"  !CDS_PN = "CB24";
"VSS_CB25":   PN = "CB25"  !CDS_PN = "CB25";
"VSS_CB26":   PN = "CB26"  !CDS_PN = "CB26";
"VSS_CB27":   PN = "CB27"  !CDS_PN = "CB27";
"VSS_CB28":   PN = "CB28"  !CDS_PN = "CB28";
"VSS_CB29":   PN = "CB29"  !CDS_PN = "CB29";
"VSS_CB30":   PN = "CB30"  !CDS_PN = "CB30";
"VSS_CB31":   PN = "CB31"  !CDS_PN = "CB31";
"VSS_CB32":   PN = "CB32"  !CDS_PN = "CB32";
"VSS_CB33":   PN = "CB33"  !CDS_PN = "CB33";
"VSS_CB34":   PN = "CB34"  !CDS_PN = "CB34";
"VSS_CB37":   PN = "CB37"  !CDS_PN = "CB37";
"VSS_CB39":   PN = "CB39"  !CDS_PN = "CB39";
"VSS_CB42":   PN = "CB42"  !CDS_PN = "CB42";
"VSS_CB43":   PN = "CB43"  !CDS_PN = "CB43";
"VSS_CB45":   PN = "CB45"  !CDS_PN = "CB45";
"VSS_CB46":   PN = "CB46"  !CDS_PN = "CB46";
"VSS_CB47":   PN = "CB47"  !CDS_PN = "CB47";
"VSS_CB48":   PN = "CB48"  !CDS_PN = "CB48";
"VSS_CB49":   PN = "CB49"  !CDS_PN = "CB49";
"VSS_CB50":   PN = "CB50"  !CDS_PN = "CB50";
"VSS_CB51":   PN = "CB51"  !CDS_PN = "CB51";
"VSS_CB52":   PN = "CB52"  !CDS_PN = "CB52";
"VSS_CB53":   PN = "CB53"  !CDS_PN = "CB53";
"VSS_CB57":   PN = "CB57"  !CDS_PN = "CB57";
"VSS_CB59":   PN = "CB59"  !CDS_PN = "CB59";
"VSS_CB61":   PN = "CB61"  !CDS_PN = "CB61";
"VSS_CB64":   PN = "CB64"  !CDS_PN = "CB64";
"VSS_CB66":   PN = "CB66"  !CDS_PN = "CB66";
"VSS_CB68":   PN = "CB68"  !CDS_PN = "CB68";
"VSS_CB71":   PN = "CB71"  !CDS_PN = "CB71";
"VSS_CB73":   PN = "CB73"  !CDS_PN = "CB73";
"VSS_CC1":   PN = "CC1"  !CDS_PN = "CC1";
"VSS_CC4":   PN = "CC4"  !CDS_PN = "CC4";
"VSS_CC6":   PN = "CC6"  !CDS_PN = "CC6";
"VSS_CC8":   PN = "CC8"  !CDS_PN = "CC8";
"VSS_CC11":   PN = "CC11"  !CDS_PN = "CC11";
"VSS_CC13":   PN = "CC13"  !CDS_PN = "CC13";
"VSS_CC15":   PN = "CC15"  !CDS_PN = "CC15";
"VSS_CC18":   PN = "CC18"  !CDS_PN = "CC18";
"VSS_CC20":   PN = "CC20"  !CDS_PN = "CC20";
"VSS_CC25":   PN = "CC25"  !CDS_PN = "CC25";
"VSS_CC28":   PN = "CC28"  !CDS_PN = "CC28";
"VSS_CC31":   PN = "CC31"  !CDS_PN = "CC31";
"VSS_CC34":   PN = "CC34"  !CDS_PN = "CC34";
"VSS_CC42":   PN = "CC42"  !CDS_PN = "CC42";
"VSS_CC45":   PN = "CC45"  !CDS_PN = "CC45";
"VSS_CC48":   PN = "CC48"  !CDS_PN = "CC48";
"VSS_CC51":   PN = "CC51"  !CDS_PN = "CC51";
"VSS_CC54":   PN = "CC54"  !CDS_PN = "CC54";
"VSS_CC56":   PN = "CC56"  !CDS_PN = "CC56";
"VSS_CC58":   PN = "CC58"  !CDS_PN = "CC58";
"VSS_CC61":   PN = "CC61"  !CDS_PN = "CC61";
"VSS_CC63":   PN = "CC63"  !CDS_PN = "CC63";
"VSS_CC65":   PN = "CC65"  !CDS_PN = "CC65";
"VSS_CC68":   PN = "CC68"  !CDS_PN = "CC68";
"VSS_CC70":   PN = "CC70"  !CDS_PN = "CC70";
"VSS_CC72":   PN = "CC72"  !CDS_PN = "CC72";
"VSS_CC75":   PN = "CC75"  !CDS_PN = "CC75";
"VSS_CD3":   PN = "CD3"  !CDS_PN = "CD3";
"VSS_CD8":   PN = "CD8"  !CDS_PN = "CD8";
"VSS_CD10":   PN = "CD10"  !CDS_PN = "CD10";
"VSS_CD15":   PN = "CD15"  !CDS_PN = "CD15";
"VSS_CD17":   PN = "CD17"  !CDS_PN = "CD17";
"VSS_CD22":   PN = "CD22"  !CDS_PN = "CD22";
"VSS_CD25":   PN = "CD25"  !CDS_PN = "CD25";
"VSS_CD28":   PN = "CD28"  !CDS_PN = "CD28";
"VSS_CD31":   PN = "CD31"  !CDS_PN = "CD31";
"VSS_CD34":   PN = "CD34"  !CDS_PN = "CD34";
"VSS_CD37":   PN = "CD37"  !CDS_PN = "CD37";
"VSS_CD39":   PN = "CD39"  !CDS_PN = "CD39";
"VSS_CD42":   PN = "CD42"  !CDS_PN = "CD42";
"VSS_CD45":   PN = "CD45"  !CDS_PN = "CD45";
"VSS_CD48":   PN = "CD48"  !CDS_PN = "CD48";
"VSS_CD51":   PN = "CD51"  !CDS_PN = "CD51";
"VSS_CD54":   PN = "CD54"  !CDS_PN = "CD54";
"VSS_CD59":   PN = "CD59"  !CDS_PN = "CD59";
"VSS_CD61":   PN = "CD61"  !CDS_PN = "CD61";
"VSS_CD66":   PN = "CD66"  !CDS_PN = "CD66";
"VSS_CD68":   PN = "CD68"  !CDS_PN = "CD68";
"VSS_CD73":   PN = "CD73"  !CDS_PN = "CD73";
"VSS_CE1":   PN = "CE1"  !CDS_PN = "CE1";
"VSS_CE4":   PN = "CE4"  !CDS_PN = "CE4";
"VSS_CE6":   PN = "CE6"  !CDS_PN = "CE6";
"VSS_CE8":   PN = "CE8"  !CDS_PN = "CE8";
"VSS_CE11":   PN = "CE11"  !CDS_PN = "CE11";
"VSS_CE13":   PN = "CE13"  !CDS_PN = "CE13";
"VSS_CE15":   PN = "CE15"  !CDS_PN = "CE15";
"VSS_CE18":   PN = "CE18"  !CDS_PN = "CE18";
"VSS_CE20":   PN = "CE20"  !CDS_PN = "CE20";
"VSS_CE22":   PN = "CE22"  !CDS_PN = "CE22";
"VSS_CE25":   PN = "CE25"  !CDS_PN = "CE25";
"VSS_CE28":   PN = "CE28"  !CDS_PN = "CE28";
"VSS_CE31":   PN = "CE31"  !CDS_PN = "CE31";
"VSS_CE34":   PN = "CE34"  !CDS_PN = "CE34";
"VSS_CE35":   PN = "CE35"  !CDS_PN = "CE35";
"VSS_CE36":   PN = "CE36"  !CDS_PN = "CE36";
"VSS_CE40":   PN = "CE40"  !CDS_PN = "CE40";
"VSS_CE41":   PN = "CE41"  !CDS_PN = "CE41";
"VSS_CE42":   PN = "CE42"  !CDS_PN = "CE42";
"VSS_CE45":   PN = "CE45"  !CDS_PN = "CE45";
"VSS_CE48":   PN = "CE48"  !CDS_PN = "CE48";
"VSS_CE51":   PN = "CE51"  !CDS_PN = "CE51";
"VSS_CE54":   PN = "CE54"  !CDS_PN = "CE54";
"VSS_CE56":   PN = "CE56"  !CDS_PN = "CE56";
"VSS_CE58":   PN = "CE58"  !CDS_PN = "CE58";
"VSS_CE61":   PN = "CE61"  !CDS_PN = "CE61";
"VSS_CE63":   PN = "CE63"  !CDS_PN = "CE63";
"VSS_CE65":   PN = "CE65"  !CDS_PN = "CE65";
"VSS_CE68":   PN = "CE68"  !CDS_PN = "CE68";
"VSS_CE70":   PN = "CE70"  !CDS_PN = "CE70";
"VSS_CE72":   PN = "CE72"  !CDS_PN = "CE72";
"VSS_CE75":   PN = "CE75"  !CDS_PN = "CE75";
"VSS_CF3":   PN = "CF3"  !CDS_PN = "CF3";
"VSS_CF5":   PN = "CF5"  !CDS_PN = "CF5";
"VSS_CF8":   PN = "CF8"  !CDS_PN = "CF8";
"VSS_CF10":   PN = "CF10"  !CDS_PN = "CF10";
"VSS_CF12":   PN = "CF12"  !CDS_PN = "CF12";
"VSS_CF15":   PN = "CF15"  !CDS_PN = "CF15";
"VSS_CF17":   PN = "CF17"  !CDS_PN = "CF17";
"VSS_CF19":   PN = "CF19"  !CDS_PN = "CF19";
"VSS_CF23":   PN = "CF23"  !CDS_PN = "CF23";
"VSS_CF24":   PN = "CF24"  !CDS_PN = "CF24";
"VSS_CF25":   PN = "CF25"  !CDS_PN = "CF25";
"VSS_CF26":   PN = "CF26"  !CDS_PN = "CF26";
"VSS_CF27":   PN = "CF27"  !CDS_PN = "CF27";
"VSS_CF28":   PN = "CF28"  !CDS_PN = "CF28";
"VSS_CF29":   PN = "CF29"  !CDS_PN = "CF29";
"VSS_CF30":   PN = "CF30"  !CDS_PN = "CF30";
"VSS_CF31":   PN = "CF31"  !CDS_PN = "CF31";
"VSS_CF32":   PN = "CF32"  !CDS_PN = "CF32";
"VSS_CF33":   PN = "CF33"  !CDS_PN = "CF33";
BODY = "GENOA_SP5","I3": #LOCATION = "U26" !CDS_LOCATION = "U26" &SEC = "38" #&CDS_SEC = "38";
"VSS_CF34":   PN = "CF34"  !CDS_PN = "CF34";
"VSS_CF37":   PN = "CF37"  !CDS_PN = "CF37";
"VSS_CF39":   PN = "CF39"  !CDS_PN = "CF39";
"VSS_CF42":   PN = "CF42"  !CDS_PN = "CF42";
"VSS_CF43":   PN = "CF43"  !CDS_PN = "CF43";
"VSS_CF44":   PN = "CF44"  !CDS_PN = "CF44";
"VSS_CF45":   PN = "CF45"  !CDS_PN = "CF45";
"VSS_CF47":   PN = "CF47"  !CDS_PN = "CF47";
"VSS_CF48":   PN = "CF48"  !CDS_PN = "CF48";
"VSS_CF49":   PN = "CF49"  !CDS_PN = "CF49";
"VSS_CF50":   PN = "CF50"  !CDS_PN = "CF50";
"VSS_CF51":   PN = "CF51"  !CDS_PN = "CF51";
"VSS_CF52":   PN = "CF52"  !CDS_PN = "CF52";
"VSS_CF53":   PN = "CF53"  !CDS_PN = "CF53";
"VSS_CF57":   PN = "CF57"  !CDS_PN = "CF57";
"VSS_CF59":   PN = "CF59"  !CDS_PN = "CF59";
"VSS_CF61":   PN = "CF61"  !CDS_PN = "CF61";
"VSS_CF64":   PN = "CF64"  !CDS_PN = "CF64";
"VSS_CF66":   PN = "CF66"  !CDS_PN = "CF66";
"VSS_CF68":   PN = "CF68"  !CDS_PN = "CF68";
"VSS_CF71":   PN = "CF71"  !CDS_PN = "CF71";
"VSS_CF73":   PN = "CF73"  !CDS_PN = "CF73";
"VSS_CG1":   PN = "CG1"  !CDS_PN = "CG1";
"VSS_CG6":   PN = "CG6"  !CDS_PN = "CG6";
"VSS_CG8":   PN = "CG8"  !CDS_PN = "CG8";
"VSS_CG13":   PN = "CG13"  !CDS_PN = "CG13";
"VSS_CG15":   PN = "CG15"  !CDS_PN = "CG15";
"VSS_CG20":   PN = "CG20"  !CDS_PN = "CG20";
"VSS_CG22":   PN = "CG22"  !CDS_PN = "CG22";
"VSS_CG25":   PN = "CG25"  !CDS_PN = "CG25";
"VSS_CG28":   PN = "CG28"  !CDS_PN = "CG28";
"VSS_CG31":   PN = "CG31"  !CDS_PN = "CG31";
"VSS_CG34":   PN = "CG34"  !CDS_PN = "CG34";
"VSS_CG45":   PN = "CG45"  !CDS_PN = "CG45";
"VSS_CG48":   PN = "CG48"  !CDS_PN = "CG48";
"VSS_CG51":   PN = "CG51"  !CDS_PN = "CG51";
"VSS_CG54":   PN = "CG54"  !CDS_PN = "CG54";
"VSS_CG56":   PN = "CG56"  !CDS_PN = "CG56";
"VSS_CG61":   PN = "CG61"  !CDS_PN = "CG61";
"VSS_CG63":   PN = "CG63"  !CDS_PN = "CG63";
"VSS_CG68":   PN = "CG68"  !CDS_PN = "CG68";
"VSS_CG70":   PN = "CG70"  !CDS_PN = "CG70";
"VSS_CG75":   PN = "CG75"  !CDS_PN = "CG75";
"VSS_CH3":   PN = "CH3"  !CDS_PN = "CH3";
"VSS_CH5":   PN = "CH5"  !CDS_PN = "CH5";
"VSS_CH8":   PN = "CH8"  !CDS_PN = "CH8";
"VSS_CH10":   PN = "CH10"  !CDS_PN = "CH10";
"VSS_CH12":   PN = "CH12"  !CDS_PN = "CH12";
"VSS_CH15":   PN = "CH15"  !CDS_PN = "CH15";
"VSS_CH17":   PN = "CH17"  !CDS_PN = "CH17";
"VSS_CH19":   PN = "CH19"  !CDS_PN = "CH19";
"VSS_CH22":   PN = "CH22"  !CDS_PN = "CH22";
"VSS_CH25":   PN = "CH25"  !CDS_PN = "CH25";
"VSS_CH28":   PN = "CH28"  !CDS_PN = "CH28";
"VSS_CH31":   PN = "CH31"  !CDS_PN = "CH31";
"VSS_CH34":   PN = "CH34"  !CDS_PN = "CH34";
"VSS_CH37":   PN = "CH37"  !CDS_PN = "CH37";
"VSS_CH39":   PN = "CH39"  !CDS_PN = "CH39";
"VSS_CH42":   PN = "CH42"  !CDS_PN = "CH42";
"VSS_CH45":   PN = "CH45"  !CDS_PN = "CH45";
"VSS_CH48":   PN = "CH48"  !CDS_PN = "CH48";
"VSS_CH51":   PN = "CH51"  !CDS_PN = "CH51";
"VSS_CH54":   PN = "CH54"  !CDS_PN = "CH54";
"VSS_CH57":   PN = "CH57"  !CDS_PN = "CH57";
"VSS_CH59":   PN = "CH59"  !CDS_PN = "CH59";
"VSS_CH61":   PN = "CH61"  !CDS_PN = "CH61";
"VSS_CH64":   PN = "CH64"  !CDS_PN = "CH64";
"VSS_CH66":   PN = "CH66"  !CDS_PN = "CH66";
"VSS_CH68":   PN = "CH68"  !CDS_PN = "CH68";
"VSS_CH71":   PN = "CH71"  !CDS_PN = "CH71";
"VSS_CH73":   PN = "CH73"  !CDS_PN = "CH73";
"VSS_CJ1":   PN = "CJ1"  !CDS_PN = "CJ1";
"VSS_CJ4":   PN = "CJ4"  !CDS_PN = "CJ4";
"VSS_CJ6":   PN = "CJ6"  !CDS_PN = "CJ6";
"VSS_CJ8":   PN = "CJ8"  !CDS_PN = "CJ8";
"VSS_CJ11":   PN = "CJ11"  !CDS_PN = "CJ11";
"VSS_CJ13":   PN = "CJ13"  !CDS_PN = "CJ13";
"VSS_CJ15":   PN = "CJ15"  !CDS_PN = "CJ15";
"VSS_CJ18":   PN = "CJ18"  !CDS_PN = "CJ18";
"VSS_CJ20":   PN = "CJ20"  !CDS_PN = "CJ20";
"VSS_CJ23":   PN = "CJ23"  !CDS_PN = "CJ23";
"VSS_CJ31":   PN = "CJ31"  !CDS_PN = "CJ31";
"VSS_CJ34":   PN = "CJ34"  !CDS_PN = "CJ34";
"VSS_CJ35":   PN = "CJ35"  !CDS_PN = "CJ35";
"VSS_CJ36":   PN = "CJ36"  !CDS_PN = "CJ36";
"VSS_CJ40":   PN = "CJ40"  !CDS_PN = "CJ40";
"VSS_CJ41":   PN = "CJ41"  !CDS_PN = "CJ41";
"VSS_CJ42":   PN = "CJ42"  !CDS_PN = "CJ42";
"VSS_CJ45":   PN = "CJ45"  !CDS_PN = "CJ45";
"VSS_CJ56":   PN = "CJ56"  !CDS_PN = "CJ56";
"VSS_CJ58":   PN = "CJ58"  !CDS_PN = "CJ58";
"VSS_CJ61":   PN = "CJ61"  !CDS_PN = "CJ61";
"VSS_CJ63":   PN = "CJ63"  !CDS_PN = "CJ63";
"VSS_CJ65":   PN = "CJ65"  !CDS_PN = "CJ65";
"VSS_CJ68":   PN = "CJ68"  !CDS_PN = "CJ68";
"VSS_CJ70":   PN = "CJ70"  !CDS_PN = "CJ70";
"VSS_CJ72":   PN = "CJ72"  !CDS_PN = "CJ72";
"VSS_CJ75":   PN = "CJ75"  !CDS_PN = "CJ75";
"VSS_CK3":   PN = "CK3"  !CDS_PN = "CK3";
"VSS_CK8":   PN = "CK8"  !CDS_PN = "CK8";
"VSS_CK15":   PN = "CK15"  !CDS_PN = "CK15";
"VSS_CK17":   PN = "CK17"  !CDS_PN = "CK17";
"VSS_CK22":   PN = "CK22"  !CDS_PN = "CK22";
"VSS_CK23":   PN = "CK23"  !CDS_PN = "CK23";
"VSS_CK24":   PN = "CK24"  !CDS_PN = "CK24";
"VSS_CK25":   PN = "CK25"  !CDS_PN = "CK25";
"VSS_CK26":   PN = "CK26"  !CDS_PN = "CK26";
"VSS_CK27":   PN = "CK27"  !CDS_PN = "CK27";
"VSS_CK28":   PN = "CK28"  !CDS_PN = "CK28";
"VSS_CK32":   PN = "CK32"  !CDS_PN = "CK32";
"VSS_CK33":   PN = "CK33"  !CDS_PN = "CK33";
"VSS_CK34":   PN = "CK34"  !CDS_PN = "CK34";
"VSS_CK37":   PN = "CK37"  !CDS_PN = "CK37";
"VSS_CK39":   PN = "CK39"  !CDS_PN = "CK39";
"VSS_CK42":   PN = "CK42"  !CDS_PN = "CK42";
"VSS_CK43":   PN = "CK43"  !CDS_PN = "CK43";
"VSS_CK44":   PN = "CK44"  !CDS_PN = "CK44";
"VSS_CK45":   PN = "CK45"  !CDS_PN = "CK45";
"VSS_CK48":   PN = "CK48"  !CDS_PN = "CK48";
"VSS_CK49":   PN = "CK49"  !CDS_PN = "CK49";
"VSS_CK50":   PN = "CK50"  !CDS_PN = "CK50";
"VSS_CK51":   PN = "CK51"  !CDS_PN = "CK51";
"VSS_CK52":   PN = "CK52"  !CDS_PN = "CK52";
"VSS_CK53":   PN = "CK53"  !CDS_PN = "CK53";
"VSS_CK54":   PN = "CK54"  !CDS_PN = "CK54";
"VSS_CK59":   PN = "CK59"  !CDS_PN = "CK59";
"VSS_CK61":   PN = "CK61"  !CDS_PN = "CK61";
"VSS_CK66":   PN = "CK66"  !CDS_PN = "CK66";
"VSS_CK68":   PN = "CK68"  !CDS_PN = "CK68";
"VSS_CK73":   PN = "CK73"  !CDS_PN = "CK73";
"VSS_CL1":   PN = "CL1"  !CDS_PN = "CL1";
"VSS_CL4":   PN = "CL4"  !CDS_PN = "CL4";
"VSS_CL6":   PN = "CL6"  !CDS_PN = "CL6";
"VSS_CL8":   PN = "CL8"  !CDS_PN = "CL8";
"VSS_CL11":   PN = "CL11"  !CDS_PN = "CL11";
"VSS_CL13":   PN = "CL13"  !CDS_PN = "CL13";
"VSS_CL15":   PN = "CL15"  !CDS_PN = "CL15";
"VSS_CL18":   PN = "CL18"  !CDS_PN = "CL18";
"VSS_CL20":   PN = "CL20"  !CDS_PN = "CL20";
"VSS_CL22":   PN = "CL22"  !CDS_PN = "CL22";
"VSS_CL25":   PN = "CL25"  !CDS_PN = "CL25";
"VSS_CL28":   PN = "CL28"  !CDS_PN = "CL28";
"VSS_CL31":   PN = "CL31"  !CDS_PN = "CL31";
"VSS_CL34":   PN = "CL34"  !CDS_PN = "CL34";
"VSS_CL35":   PN = "CL35"  !CDS_PN = "CL35";
"VSS_CL36":   PN = "CL36"  !CDS_PN = "CL36";
"VSS_CL40":   PN = "CL40"  !CDS_PN = "CL40";
"VSS_CL41":   PN = "CL41"  !CDS_PN = "CL41";
"VSS_CL42":   PN = "CL42"  !CDS_PN = "CL42";
"VSS_CL45":   PN = "CL45"  !CDS_PN = "CL45";
"VSS_CL48":   PN = "CL48"  !CDS_PN = "CL48";
"VSS_CL51":   PN = "CL51"  !CDS_PN = "CL51";
"VSS_CL54":   PN = "CL54"  !CDS_PN = "CL54";
"VSS_CL56":   PN = "CL56"  !CDS_PN = "CL56";
"VSS_CL58":   PN = "CL58"  !CDS_PN = "CL58";
"VSS_CL61":   PN = "CL61"  !CDS_PN = "CL61";
"VSS_CL63":   PN = "CL63"  !CDS_PN = "CL63";
"VSS_CL65":   PN = "CL65"  !CDS_PN = "CL65";
"VSS_CL68":   PN = "CL68"  !CDS_PN = "CL68";
"VSS_CL70":   PN = "CL70"  !CDS_PN = "CL70";
"VSS_CL72":   PN = "CL72"  !CDS_PN = "CL72";
"VSS_CL75":   PN = "CL75"  !CDS_PN = "CL75";
"VSS_CM3":   PN = "CM3"  !CDS_PN = "CM3";
"VSS_CM5":   PN = "CM5"  !CDS_PN = "CM5";
"VSS_CM8":   PN = "CM8"  !CDS_PN = "CM8";
"VSS_CM10":   PN = "CM10"  !CDS_PN = "CM10";
"VSS_CM12":   PN = "CM12"  !CDS_PN = "CM12";
"VSS_CM15":   PN = "CM15"  !CDS_PN = "CM15";
"VSS_CM17":   PN = "CM17"  !CDS_PN = "CM17";
"VSS_CM19":   PN = "CM19"  !CDS_PN = "CM19";
"VSS_CM23":   PN = "CM23"  !CDS_PN = "CM23";
"VSS_CM24":   PN = "CM24"  !CDS_PN = "CM24";
"VSS_CM25":   PN = "CM25"  !CDS_PN = "CM25";
"VSS_CM26":   PN = "CM26"  !CDS_PN = "CM26";
"VSS_CM27":   PN = "CM27"  !CDS_PN = "CM27";
"VSS_CM28":   PN = "CM28"  !CDS_PN = "CM28";
"VSS_CM29":   PN = "CM29"  !CDS_PN = "CM29";
"VSS_CM30":   PN = "CM30"  !CDS_PN = "CM30";
"VSS_CM31":   PN = "CM31"  !CDS_PN = "CM31";
"VSS_CM32":   PN = "CM32"  !CDS_PN = "CM32";
"VSS_CM33":   PN = "CM33"  !CDS_PN = "CM33";
"VSS_CM34":   PN = "CM34"  !CDS_PN = "CM34";
"VSS_CM37":   PN = "CM37"  !CDS_PN = "CM37";
"VSS_CM39":   PN = "CM39"  !CDS_PN = "CM39";
"VSS_CM42":   PN = "CM42"  !CDS_PN = "CM42";
"VSS_CM43":   PN = "CM43"  !CDS_PN = "CM43";
"VSS_CM44":   PN = "CM44"  !CDS_PN = "CM44";
"VSS_CM45":   PN = "CM45"  !CDS_PN = "CM45";
"VSS_CM46":   PN = "CM46"  !CDS_PN = "CM46";
"VSS_CM47":   PN = "CM47"  !CDS_PN = "CM47";
"VSS_CM48":   PN = "CM48"  !CDS_PN = "CM48";
"VSS_CM49":   PN = "CM49"  !CDS_PN = "CM49";
"VSS_CM51":   PN = "CM51"  !CDS_PN = "CM51";
"VSS_CM52":   PN = "CM52"  !CDS_PN = "CM52";
"VSS_CM53":   PN = "CM53"  !CDS_PN = "CM53";
"VSS_CM57":   PN = "CM57"  !CDS_PN = "CM57";
"VSS_CM59":   PN = "CM59"  !CDS_PN = "CM59";
"VSS_CM61":   PN = "CM61"  !CDS_PN = "CM61";
"VSS_CM64":   PN = "CM64"  !CDS_PN = "CM64";
"VSS_CM66":   PN = "CM66"  !CDS_PN = "CM66";
"VSS_CM68":   PN = "CM68"  !CDS_PN = "CM68";
"VSS_CM71":   PN = "CM71"  !CDS_PN = "CM71";
"VSS_CM73":   PN = "CM73"  !CDS_PN = "CM73";
"VSS_CN1":   PN = "CN1"  !CDS_PN = "CN1";
"VSS_CN6":   PN = "CN6"  !CDS_PN = "CN6";
"VSS_CN8":   PN = "CN8"  !CDS_PN = "CN8";
"VSS_CN13":   PN = "CN13"  !CDS_PN = "CN13";
"VSS_CN15":   PN = "CN15"  !CDS_PN = "CN15";
"VSS_CN20":   PN = "CN20"  !CDS_PN = "CN20";
"VSS_CN22":   PN = "CN22"  !CDS_PN = "CN22";
"VSS_CN25":   PN = "CN25"  !CDS_PN = "CN25";
"VSS_CN28":   PN = "CN28"  !CDS_PN = "CN28";
"VSS_CN31":   PN = "CN31"  !CDS_PN = "CN31";
"VSS_CN34":   PN = "CN34"  !CDS_PN = "CN34";
"VSS_CN42":   PN = "CN42"  !CDS_PN = "CN42";
"VSS_CN45":   PN = "CN45"  !CDS_PN = "CN45";
"VSS_CN48":   PN = "CN48"  !CDS_PN = "CN48";
"VSS_CN51":   PN = "CN51"  !CDS_PN = "CN51";
"VSS_CN56":   PN = "CN56"  !CDS_PN = "CN56";
"VSS_CN61":   PN = "CN61"  !CDS_PN = "CN61";
"VSS_CN63":   PN = "CN63"  !CDS_PN = "CN63";
"VSS_CN68":   PN = "CN68"  !CDS_PN = "CN68";
"VSS_CN70":   PN = "CN70"  !CDS_PN = "CN70";
"VSS_CN75":   PN = "CN75"  !CDS_PN = "CN75";
"VSS_CP3":   PN = "CP3"  !CDS_PN = "CP3";
"VSS_CP5":   PN = "CP5"  !CDS_PN = "CP5";
"VSS_CP8":   PN = "CP8"  !CDS_PN = "CP8";
"VSS_CP10":   PN = "CP10"  !CDS_PN = "CP10";
"VSS_CP12":   PN = "CP12"  !CDS_PN = "CP12";
"VSS_CP15":   PN = "CP15"  !CDS_PN = "CP15";
"VSS_CP17":   PN = "CP17"  !CDS_PN = "CP17";
"VSS_CP19":   PN = "CP19"  !CDS_PN = "CP19";
BODY = "GENOA_SP5","I4": #LOCATION = "U26" !CDS_LOCATION = "U26" &SEC = "39" #&CDS_SEC = "39";
"VSS_CP22":   PN = "CP22"  !CDS_PN = "CP22";
"VSS_CP25":   PN = "CP25"  !CDS_PN = "CP25";
"VSS_CP28":   PN = "CP28"  !CDS_PN = "CP28";
"VSS_CP31":   PN = "CP31"  !CDS_PN = "CP31";
"VSS_CP34":   PN = "CP34"  !CDS_PN = "CP34";
"VSS_CP37":   PN = "CP37"  !CDS_PN = "CP37";
"VSS_CP39":   PN = "CP39"  !CDS_PN = "CP39";
"VSS_CP42":   PN = "CP42"  !CDS_PN = "CP42";
"VSS_CP45":   PN = "CP45"  !CDS_PN = "CP45";
"VSS_CP48":   PN = "CP48"  !CDS_PN = "CP48";
"VSS_CP51":   PN = "CP51"  !CDS_PN = "CP51";
"VSS_CP54":   PN = "CP54"  !CDS_PN = "CP54";
"VSS_CP57":   PN = "CP57"  !CDS_PN = "CP57";
"VSS_CP59":   PN = "CP59"  !CDS_PN = "CP59";
"VSS_CP61":   PN = "CP61"  !CDS_PN = "CP61";
"VSS_CP64":   PN = "CP64"  !CDS_PN = "CP64";
"VSS_CP66":   PN = "CP66"  !CDS_PN = "CP66";
"VSS_CP68":   PN = "CP68"  !CDS_PN = "CP68";
"VSS_CP71":   PN = "CP71"  !CDS_PN = "CP71";
"VSS_CP73":   PN = "CP73"  !CDS_PN = "CP73";
"VSS_CR1":   PN = "CR1"  !CDS_PN = "CR1";
"VSS_CR4":   PN = "CR4"  !CDS_PN = "CR4";
"VSS_CR6":   PN = "CR6"  !CDS_PN = "CR6";
"VSS_CR8":   PN = "CR8"  !CDS_PN = "CR8";
"VSS_CR11":   PN = "CR11"  !CDS_PN = "CR11";
"VSS_CR13":   PN = "CR13"  !CDS_PN = "CR13";
"VSS_CR15":   PN = "CR15"  !CDS_PN = "CR15";
"VSS_CR18":   PN = "CR18"  !CDS_PN = "CR18";
"VSS_CR20":   PN = "CR20"  !CDS_PN = "CR20";
"VSS_CR22":   PN = "CR22"  !CDS_PN = "CR22";
"VSS_CR25":   PN = "CR25"  !CDS_PN = "CR25";
"VSS_CR28":   PN = "CR28"  !CDS_PN = "CR28";
"VSS_CR31":   PN = "CR31"  !CDS_PN = "CR31";
"VSS_CR34":   PN = "CR34"  !CDS_PN = "CR34";
"VSS_CR35":   PN = "CR35"  !CDS_PN = "CR35";
"VSS_CR36":   PN = "CR36"  !CDS_PN = "CR36";
"VSS_CR40":   PN = "CR40"  !CDS_PN = "CR40";
"VSS_CR41":   PN = "CR41"  !CDS_PN = "CR41";
"VSS_CR42":   PN = "CR42"  !CDS_PN = "CR42";
"VSS_CR45":   PN = "CR45"  !CDS_PN = "CR45";
"VSS_CR48":   PN = "CR48"  !CDS_PN = "CR48";
"VSS_CR51":   PN = "CR51"  !CDS_PN = "CR51";
"VSS_CR54":   PN = "CR54"  !CDS_PN = "CR54";
"VSS_CR56":   PN = "CR56"  !CDS_PN = "CR56";
"VSS_CR58":   PN = "CR58"  !CDS_PN = "CR58";
"VSS_CR61":   PN = "CR61"  !CDS_PN = "CR61";
"VSS_CR63":   PN = "CR63"  !CDS_PN = "CR63";
"VSS_CR65":   PN = "CR65"  !CDS_PN = "CR65";
"VSS_CR68":   PN = "CR68"  !CDS_PN = "CR68";
"VSS_CR70":   PN = "CR70"  !CDS_PN = "CR70";
"VSS_CR72":   PN = "CR72"  !CDS_PN = "CR72";
"VSS_CR75":   PN = "CR75"  !CDS_PN = "CR75";
"VSS_CT3":   PN = "CT3"  !CDS_PN = "CT3";
"VSS_CT8":   PN = "CT8"  !CDS_PN = "CT8";
"VSS_CT10":   PN = "CT10"  !CDS_PN = "CT10";
"VSS_CT15":   PN = "CT15"  !CDS_PN = "CT15";
"VSS_CT17":   PN = "CT17"  !CDS_PN = "CT17";
"VSS_CT23":   PN = "CT23"  !CDS_PN = "CT23";
"VSS_CT24":   PN = "CT24"  !CDS_PN = "CT24";
"VSS_CT25":   PN = "CT25"  !CDS_PN = "CT25";
"VSS_CT26":   PN = "CT26"  !CDS_PN = "CT26";
"VSS_CT27":   PN = "CT27"  !CDS_PN = "CT27";
"VSS_CT28":   PN = "CT28"  !CDS_PN = "CT28";
"VSS_CT29":   PN = "CT29"  !CDS_PN = "CT29";
"VSS_CT30":   PN = "CT30"  !CDS_PN = "CT30";
"VSS_CT31":   PN = "CT31"  !CDS_PN = "CT31";
"VSS_CT32":   PN = "CT32"  !CDS_PN = "CT32";
"VSS_CT33":   PN = "CT33"  !CDS_PN = "CT33";
"VSS_CT34":   PN = "CT34"  !CDS_PN = "CT34";
"VSS_CT37":   PN = "CT37"  !CDS_PN = "CT37";
"VSS_CT39":   PN = "CT39"  !CDS_PN = "CT39";
"VSS_CT42":   PN = "CT42"  !CDS_PN = "CT42";
"VSS_CT43":   PN = "CT43"  !CDS_PN = "CT43";
"VSS_CT44":   PN = "CT44"  !CDS_PN = "CT44";
"VSS_CT45":   PN = "CT45"  !CDS_PN = "CT45";
"VSS_CT46":   PN = "CT46"  !CDS_PN = "CT46";
"VSS_CT47":   PN = "CT47"  !CDS_PN = "CT47";
"VSS_CT48":   PN = "CT48"  !CDS_PN = "CT48";
"VSS_CT49":   PN = "CT49"  !CDS_PN = "CT49";
"VSS_CT50":   PN = "CT50"  !CDS_PN = "CT50";
"VSS_CT51":   PN = "CT51"  !CDS_PN = "CT51";
"VSS_CT53":   PN = "CT53"  !CDS_PN = "CT53";
"VSS_CT59":   PN = "CT59"  !CDS_PN = "CT59";
"VSS_CT61":   PN = "CT61"  !CDS_PN = "CT61";
"VSS_CT66":   PN = "CT66"  !CDS_PN = "CT66";
"VSS_CT68":   PN = "CT68"  !CDS_PN = "CT68";
"VSS_CT73":   PN = "CT73"  !CDS_PN = "CT73";
"VSS_CU1":   PN = "CU1"  !CDS_PN = "CU1";
"VSS_CU4":   PN = "CU4"  !CDS_PN = "CU4";
"VSS_CU6":   PN = "CU6"  !CDS_PN = "CU6";
"VSS_CU8":   PN = "CU8"  !CDS_PN = "CU8";
"VSS_CU11":   PN = "CU11"  !CDS_PN = "CU11";
"VSS_CU13":   PN = "CU13"  !CDS_PN = "CU13";
"VSS_CU15":   PN = "CU15"  !CDS_PN = "CU15";
"VSS_CU18":   PN = "CU18"  !CDS_PN = "CU18";
"VSS_CU20":   PN = "CU20"  !CDS_PN = "CU20";
"VSS_CU22":   PN = "CU22"  !CDS_PN = "CU22";
"VSS_CU25":   PN = "CU25"  !CDS_PN = "CU25";
"VSS_CU28":   PN = "CU28"  !CDS_PN = "CU28";
"VSS_CU31":   PN = "CU31"  !CDS_PN = "CU31";
"VSS_CU34":   PN = "CU34"  !CDS_PN = "CU34";
"VSS_CU42":   PN = "CU42"  !CDS_PN = "CU42";
"VSS_CU45":   PN = "CU45"  !CDS_PN = "CU45";
"VSS_CU48":   PN = "CU48"  !CDS_PN = "CU48";
"VSS_CU51":   PN = "CU51"  !CDS_PN = "CU51";
"VSS_CU54":   PN = "CU54"  !CDS_PN = "CU54";
"VSS_CU56":   PN = "CU56"  !CDS_PN = "CU56";
"VSS_CU61":   PN = "CU61"  !CDS_PN = "CU61";
"VSS_CU63":   PN = "CU63"  !CDS_PN = "CU63";
"VSS_CU65":   PN = "CU65"  !CDS_PN = "CU65";
"VSS_CU68":   PN = "CU68"  !CDS_PN = "CU68";
"VSS_CU70":   PN = "CU70"  !CDS_PN = "CU70";
"VSS_CU72":   PN = "CU72"  !CDS_PN = "CU72";
"VSS_CU75":   PN = "CU75"  !CDS_PN = "CU75";
"VSS_CV3":   PN = "CV3"  !CDS_PN = "CV3";
"VSS_CV5":   PN = "CV5"  !CDS_PN = "CV5";
"VSS_CV8":   PN = "CV8"  !CDS_PN = "CV8";
"VSS_CV10":   PN = "CV10"  !CDS_PN = "CV10";
"VSS_CV12":   PN = "CV12"  !CDS_PN = "CV12";
"VSS_CV15":   PN = "CV15"  !CDS_PN = "CV15";
"VSS_CV17":   PN = "CV17"  !CDS_PN = "CV17";
"VSS_CV19":   PN = "CV19"  !CDS_PN = "CV19";
"VSS_CV22":   PN = "CV22"  !CDS_PN = "CV22";
"VSS_CV25":   PN = "CV25"  !CDS_PN = "CV25";
"VSS_CV28":   PN = "CV28"  !CDS_PN = "CV28";
"VSS_CV31":   PN = "CV31"  !CDS_PN = "CV31";
"VSS_CV34":   PN = "CV34"  !CDS_PN = "CV34";
"VSS_CV37":   PN = "CV37"  !CDS_PN = "CV37";
"VSS_CV39":   PN = "CV39"  !CDS_PN = "CV39";
"VSS_CV42":   PN = "CV42"  !CDS_PN = "CV42";
"VSS_CV45":   PN = "CV45"  !CDS_PN = "CV45";
"VSS_CV48":   PN = "CV48"  !CDS_PN = "CV48";
"VSS_CV51":   PN = "CV51"  !CDS_PN = "CV51";
"VSS_CV54":   PN = "CV54"  !CDS_PN = "CV54";
"VSS_CV57":   PN = "CV57"  !CDS_PN = "CV57";
"VSS_CV59":   PN = "CV59"  !CDS_PN = "CV59";
"VSS_CV61":   PN = "CV61"  !CDS_PN = "CV61";
"VSS_CV64":   PN = "CV64"  !CDS_PN = "CV64";
"VSS_CV66":   PN = "CV66"  !CDS_PN = "CV66";
"VSS_CV68":   PN = "CV68"  !CDS_PN = "CV68";
"VSS_CV71":   PN = "CV71"  !CDS_PN = "CV71";
"VSS_CV73":   PN = "CV73"  !CDS_PN = "CV73";
"VSS_CW1":   PN = "CW1"  !CDS_PN = "CW1";
"VSS_CW6":   PN = "CW6"  !CDS_PN = "CW6";
"VSS_CW8":   PN = "CW8"  !CDS_PN = "CW8";
"VSS_CW13":   PN = "CW13"  !CDS_PN = "CW13";
"VSS_CW15":   PN = "CW15"  !CDS_PN = "CW15";
"VSS_CW20":   PN = "CW20"  !CDS_PN = "CW20";
"VSS_CW22":   PN = "CW22"  !CDS_PN = "CW22";
"VSS_CW25":   PN = "CW25"  !CDS_PN = "CW25";
"VSS_CW28":   PN = "CW28"  !CDS_PN = "CW28";
"VSS_CW31":   PN = "CW31"  !CDS_PN = "CW31";
"VSS_CW34":   PN = "CW34"  !CDS_PN = "CW34";
"VSS_CW35":   PN = "CW35"  !CDS_PN = "CW35";
"VSS_CW36":   PN = "CW36"  !CDS_PN = "CW36";
"VSS_CW40":   PN = "CW40"  !CDS_PN = "CW40";
"VSS_CW41":   PN = "CW41"  !CDS_PN = "CW41";
"VSS_CW42":   PN = "CW42"  !CDS_PN = "CW42";
"VSS_CW45":   PN = "CW45"  !CDS_PN = "CW45";
"VSS_CW48":   PN = "CW48"  !CDS_PN = "CW48";
"VSS_CW51":   PN = "CW51"  !CDS_PN = "CW51";
"VSS_CW54":   PN = "CW54"  !CDS_PN = "CW54";
"VSS_CW56":   PN = "CW56"  !CDS_PN = "CW56";
"VSS_CW61":   PN = "CW61"  !CDS_PN = "CW61";
"VSS_CW63":   PN = "CW63"  !CDS_PN = "CW63";
"VSS_CW68":   PN = "CW68"  !CDS_PN = "CW68";
"VSS_CW70":   PN = "CW70"  !CDS_PN = "CW70";
"VSS_CW75":   PN = "CW75"  !CDS_PN = "CW75";
"VSS_CY3":   PN = "CY3"  !CDS_PN = "CY3";
"VSS_CY5":   PN = "CY5"  !CDS_PN = "CY5";
"VSS_CY8":   PN = "CY8"  !CDS_PN = "CY8";
"VSS_CY10":   PN = "CY10"  !CDS_PN = "CY10";
"VSS_CY12":   PN = "CY12"  !CDS_PN = "CY12";
"VSS_CY15":   PN = "CY15"  !CDS_PN = "CY15";
"VSS_CY17":   PN = "CY17"  !CDS_PN = "CY17";
"VSS_CY19":   PN = "CY19"  !CDS_PN = "CY19";
"VSS_CY23":   PN = "CY23"  !CDS_PN = "CY23";
"VSS_CY24":   PN = "CY24"  !CDS_PN = "CY24";
"VSS_CY25":   PN = "CY25"  !CDS_PN = "CY25";
"VSS_CY26":   PN = "CY26"  !CDS_PN = "CY26";
"VSS_CY27":   PN = "CY27"  !CDS_PN = "CY27";
"VSS_CY28":   PN = "CY28"  !CDS_PN = "CY28";
"VSS_CY29":   PN = "CY29"  !CDS_PN = "CY29";
"VSS_CY30":   PN = "CY30"  !CDS_PN = "CY30";
"VSS_CY31":   PN = "CY31"  !CDS_PN = "CY31";
"VSS_CY32":   PN = "CY32"  !CDS_PN = "CY32";
"VSS_CY33":   PN = "CY33"  !CDS_PN = "CY33";
"VSS_CY34":   PN = "CY34"  !CDS_PN = "CY34";
"VSS_CY37":   PN = "CY37"  !CDS_PN = "CY37";
"VSS_CY39":   PN = "CY39"  !CDS_PN = "CY39";
"VSS_CY42":   PN = "CY42"  !CDS_PN = "CY42";
"VSS_CY43":   PN = "CY43"  !CDS_PN = "CY43";
"VSS_CY44":   PN = "CY44"  !CDS_PN = "CY44";
"VSS_CY45":   PN = "CY45"  !CDS_PN = "CY45";
"VSS_CY46":   PN = "CY46"  !CDS_PN = "CY46";
"VSS_CY47":   PN = "CY47"  !CDS_PN = "CY47";
"VSS_CY48":   PN = "CY48"  !CDS_PN = "CY48";
"VSS_CY49":   PN = "CY49"  !CDS_PN = "CY49";
"VSS_CY50":   PN = "CY50"  !CDS_PN = "CY50";
"VSS_CY51":   PN = "CY51"  !CDS_PN = "CY51";
"VSS_CY52":   PN = "CY52"  !CDS_PN = "CY52";
"VSS_CY53":   PN = "CY53"  !CDS_PN = "CY53";
"VSS_CY59":   PN = "CY59"  !CDS_PN = "CY59";
"VSS_CY61":   PN = "CY61"  !CDS_PN = "CY61";
"VSS_CY64":   PN = "CY64"  !CDS_PN = "CY64";
"VSS_CY66":   PN = "CY66"  !CDS_PN = "CY66";
"VSS_CY68":   PN = "CY68"  !CDS_PN = "CY68";
"VSS_CY71":   PN = "CY71"  !CDS_PN = "CY71";
"VSS_CY73":   PN = "CY73"  !CDS_PN = "CY73";
"VSS_DA1":   PN = "DA1"  !CDS_PN = "DA1";
"VSS_DA4":   PN = "DA4"  !CDS_PN = "DA4";
"VSS_DA6":   PN = "DA6"  !CDS_PN = "DA6";
"VSS_DA8":   PN = "DA8"  !CDS_PN = "DA8";
"VSS_DA11":   PN = "DA11"  !CDS_PN = "DA11";
"VSS_DA13":   PN = "DA13"  !CDS_PN = "DA13";
"VSS_DA15":   PN = "DA15"  !CDS_PN = "DA15";
"VSS_DA18":   PN = "DA18"  !CDS_PN = "DA18";
"VSS_DA20":   PN = "DA20"  !CDS_PN = "DA20";
"VSS_DA22":   PN = "DA22"  !CDS_PN = "DA22";
"VSS_DA25":   PN = "DA25"  !CDS_PN = "DA25";
"VSS_DA28":   PN = "DA28"  !CDS_PN = "DA28";
"VSS_DA31":   PN = "DA31"  !CDS_PN = "DA31";
"VSS_DA34":   PN = "DA34"  !CDS_PN = "DA34";
"VSS_DA42":   PN = "DA42"  !CDS_PN = "DA42";
"VSS_DA45":   PN = "DA45"  !CDS_PN = "DA45";
"VSS_DA48":   PN = "DA48"  !CDS_PN = "DA48";
"VSS_DA51":   PN = "DA51"  !CDS_PN = "DA51";
"VSS_DA54":   PN = "DA54"  !CDS_PN = "DA54";
"VSS_DA58":   PN = "DA58"  !CDS_PN = "DA58";
"VSS_DA61":   PN = "DA61"  !CDS_PN = "DA61";
"VSS_DA63":   PN = "DA63"  !CDS_PN = "DA63";
"VSS_DA65":   PN = "DA65"  !CDS_PN = "DA65";
"VSS_DA68":   PN = "DA68"  !CDS_PN = "DA68";
"VSS_DA70":   PN = "DA70"  !CDS_PN = "DA70";
DRAWING = "@t6g_mb_lib.t6g(sch_1):page60";
BODY = "GENOA_SP5","I3": #LOCATION = "U26" !CDS_LOCATION = "U26" &SEC = "40" #&CDS_SEC = "40";
"VSS_AA42":   PN = "AA42"  !CDS_PN = "AA42";
"VSS_AA72":   PN = "AA72"  !CDS_PN = "AA72";
"VSS_AD31":   PN = "AD31"  !CDS_PN = "AD31";
"VSS_AE4":   PN = "AE4"  !CDS_PN = "AE4";
"VSS_AH33":   PN = "AH33"  !CDS_PN = "AH33";
"VSS_AJ13":   PN = "AJ13"  !CDS_PN = "AJ13";
"VSS_AM37":   PN = "AM37"  !CDS_PN = "AM37";
"VSS_AN20":   PN = "AN20"  !CDS_PN = "AN20";
"VSS_BV42":   PN = "BV42"  !CDS_PN = "BV42";
"VSS_BW25":   PN = "BW25"  !CDS_PN = "BW25";
"VSS_CB44":   PN = "CB44"  !CDS_PN = "CB44";
"VSS_CC22":   PN = "CC22"  !CDS_PN = "CC22";
"VSS_CF46":   PN = "CF46"  !CDS_PN = "CF46";
"VSS_CG42":   PN = "CG42"  !CDS_PN = "CG42";
"VSS_CK10":   PN = "CK10"  !CDS_PN = "CK10";
"VSS_CK31":   PN = "CK31"  !CDS_PN = "CK31";
"VSS_CM50":   PN = "CM50"  !CDS_PN = "CM50";
"VSS_CN54":   PN = "CN54"  !CDS_PN = "CN54";
"VSS_CT52":   PN = "CT52"  !CDS_PN = "CT52";
"VSS_CU58":   PN = "CU58"  !CDS_PN = "CU58";
"VSS_CY57":   PN = "CY57"  !CDS_PN = "CY57";
"VSS_DA56":   PN = "DA56"  !CDS_PN = "DA56";
"VSS_DA72":   PN = "DA72"  !CDS_PN = "DA72";
"VSS_DA75":   PN = "DA75"  !CDS_PN = "DA75";
"VSS_DB3":   PN = "DB3"  !CDS_PN = "DB3";
"VSS_DB8":   PN = "DB8"  !CDS_PN = "DB8";
"VSS_DB10":   PN = "DB10"  !CDS_PN = "DB10";
"VSS_DB15":   PN = "DB15"  !CDS_PN = "DB15";
"VSS_DB17":   PN = "DB17"  !CDS_PN = "DB17";
"VSS_DB22":   PN = "DB22"  !CDS_PN = "DB22";
"VSS_DB25":   PN = "DB25"  !CDS_PN = "DB25";
"VSS_DB28":   PN = "DB28"  !CDS_PN = "DB28";
"VSS_DB31":   PN = "DB31"  !CDS_PN = "DB31";
"VSS_DB34":   PN = "DB34"  !CDS_PN = "DB34";
"VSS_DB37":   PN = "DB37"  !CDS_PN = "DB37";
"VSS_DB39":   PN = "DB39"  !CDS_PN = "DB39";
"VSS_DB42":   PN = "DB42"  !CDS_PN = "DB42";
"VSS_DB45":   PN = "DB45"  !CDS_PN = "DB45";
"VSS_DB48":   PN = "DB48"  !CDS_PN = "DB48";
"VSS_DB51":   PN = "DB51"  !CDS_PN = "DB51";
"VSS_DB54":   PN = "DB54"  !CDS_PN = "DB54";
"VSS_DB59":   PN = "DB59"  !CDS_PN = "DB59";
"VSS_DB61":   PN = "DB61"  !CDS_PN = "DB61";
"VSS_DB66":   PN = "DB66"  !CDS_PN = "DB66";
"VSS_DB68":   PN = "DB68"  !CDS_PN = "DB68";
"VSS_DB73":   PN = "DB73"  !CDS_PN = "DB73";
"VSS_DC1":   PN = "DC1"  !CDS_PN = "DC1";
"VSS_DC4":   PN = "DC4"  !CDS_PN = "DC4";
"VSS_DC6":   PN = "DC6"  !CDS_PN = "DC6";
"VSS_DC8":   PN = "DC8"  !CDS_PN = "DC8";
"VSS_DC11":   PN = "DC11"  !CDS_PN = "DC11";
"VSS_DC13":   PN = "DC13"  !CDS_PN = "DC13";
"VSS_DC15":   PN = "DC15"  !CDS_PN = "DC15";
"VSS_DC18":   PN = "DC18"  !CDS_PN = "DC18";
"VSS_DC20":   PN = "DC20"  !CDS_PN = "DC20";
"VSS_DC22":   PN = "DC22"  !CDS_PN = "DC22";
"VSS_DC25":   PN = "DC25"  !CDS_PN = "DC25";
"VSS_DC28":   PN = "DC28"  !CDS_PN = "DC28";
"VSS_DC31":   PN = "DC31"  !CDS_PN = "DC31";
"VSS_DC34":   PN = "DC34"  !CDS_PN = "DC34";
"VSS_DC42":   PN = "DC42"  !CDS_PN = "DC42";
"VSS_DC45":   PN = "DC45"  !CDS_PN = "DC45";
"VSS_DC48":   PN = "DC48"  !CDS_PN = "DC48";
"VSS_DC51":   PN = "DC51"  !CDS_PN = "DC51";
"VSS_DC54":   PN = "DC54"  !CDS_PN = "DC54";
"VSS_DC56":   PN = "DC56"  !CDS_PN = "DC56";
"VSS_DC58":   PN = "DC58"  !CDS_PN = "DC58";
"VSS_DC61":   PN = "DC61"  !CDS_PN = "DC61";
"VSS_DC63":   PN = "DC63"  !CDS_PN = "DC63";
"VSS_DC65":   PN = "DC65"  !CDS_PN = "DC65";
"VSS_DC68":   PN = "DC68"  !CDS_PN = "DC68";
"VSS_DC70":   PN = "DC70"  !CDS_PN = "DC70";
"VSS_DC72":   PN = "DC72"  !CDS_PN = "DC72";
"VSS_DC75":   PN = "DC75"  !CDS_PN = "DC75";
"VSS_DD3":   PN = "DD3"  !CDS_PN = "DD3";
"VSS_DD5":   PN = "DD5"  !CDS_PN = "DD5";
"VSS_DD8":   PN = "DD8"  !CDS_PN = "DD8";
"VSS_DD10":   PN = "DD10"  !CDS_PN = "DD10";
"VSS_DD12":   PN = "DD12"  !CDS_PN = "DD12";
"VSS_DD15":   PN = "DD15"  !CDS_PN = "DD15";
"VSS_DD17":   PN = "DD17"  !CDS_PN = "DD17";
"VSS_DD19":   PN = "DD19"  !CDS_PN = "DD19";
"VSS_DD23":   PN = "DD23"  !CDS_PN = "DD23";
"VSS_DD24":   PN = "DD24"  !CDS_PN = "DD24";
"VSS_DD26":   PN = "DD26"  !CDS_PN = "DD26";
"VSS_DD27":   PN = "DD27"  !CDS_PN = "DD27";
"VSS_DD29":   PN = "DD29"  !CDS_PN = "DD29";
"VSS_DD30":   PN = "DD30"  !CDS_PN = "DD30";
"VSS_DD32":   PN = "DD32"  !CDS_PN = "DD32";
"VSS_DD33":   PN = "DD33"  !CDS_PN = "DD33";
"VSS_DD35":   PN = "DD35"  !CDS_PN = "DD35";
"VSS_DD36":   PN = "DD36"  !CDS_PN = "DD36";
"VSS_DD37":   PN = "DD37"  !CDS_PN = "DD37";
"VSS_DD39":   PN = "DD39"  !CDS_PN = "DD39";
"VSS_DD40":   PN = "DD40"  !CDS_PN = "DD40";
"VSS_DD41":   PN = "DD41"  !CDS_PN = "DD41";
"VSS_DD43":   PN = "DD43"  !CDS_PN = "DD43";
"VSS_DD44":   PN = "DD44"  !CDS_PN = "DD44";
"VSS_DD46":   PN = "DD46"  !CDS_PN = "DD46";
"VSS_DD47":   PN = "DD47"  !CDS_PN = "DD47";
"VSS_DD49":   PN = "DD49"  !CDS_PN = "DD49";
"VSS_DD50":   PN = "DD50"  !CDS_PN = "DD50";
"VSS_DD52":   PN = "DD52"  !CDS_PN = "DD52";
"VSS_DD53":   PN = "DD53"  !CDS_PN = "DD53";
"VSS_DD57":   PN = "DD57"  !CDS_PN = "DD57";
"VSS_DD59":   PN = "DD59"  !CDS_PN = "DD59";
"VSS_DD61":   PN = "DD61"  !CDS_PN = "DD61";
"VSS_DD64":   PN = "DD64"  !CDS_PN = "DD64";
"VSS_DD66":   PN = "DD66"  !CDS_PN = "DD66";
"VSS_DD68":   PN = "DD68"  !CDS_PN = "DD68";
"VSS_DD71":   PN = "DD71"  !CDS_PN = "DD71";
"VSS_DD73":   PN = "DD73"  !CDS_PN = "DD73";
"VSS_DE1":   PN = "DE1"  !CDS_PN = "DE1";
"VSS_DE6":   PN = "DE6"  !CDS_PN = "DE6";
"VSS_DE8":   PN = "DE8"  !CDS_PN = "DE8";
"VSS_DE13":   PN = "DE13"  !CDS_PN = "DE13";
"VSS_DE15":   PN = "DE15"  !CDS_PN = "DE15";
"VSS_DE20":   PN = "DE20"  !CDS_PN = "DE20";
"VSS_DE23":   PN = "DE23"  !CDS_PN = "DE23";
"VSS_DE26":   PN = "DE26"  !CDS_PN = "DE26";
"VSS_DE29":   PN = "DE29"  !CDS_PN = "DE29";
"VSS_DE33":   PN = "DE33"  !CDS_PN = "DE33";
"VSS_DE56":   PN = "DE56"  !CDS_PN = "DE56";
"VSS_DE61":   PN = "DE61"  !CDS_PN = "DE61";
"VSS_DE63":   PN = "DE63"  !CDS_PN = "DE63";
"VSS_DE68":   PN = "DE68"  !CDS_PN = "DE68";
"VSS_DE70":   PN = "DE70"  !CDS_PN = "DE70";
"VSS_DE75":   PN = "DE75"  !CDS_PN = "DE75";
"VSS_DF3":   PN = "DF3"  !CDS_PN = "DF3";
"VSS_DF4":   PN = "DF4"  !CDS_PN = "DF4";
"VSS_DF5":   PN = "DF5"  !CDS_PN = "DF5";
"VSS_DF6":   PN = "DF6"  !CDS_PN = "DF6";
"VSS_DF8":   PN = "DF8"  !CDS_PN = "DF8";
"VSS_DF10":   PN = "DF10"  !CDS_PN = "DF10";
"VSS_DF11":   PN = "DF11"  !CDS_PN = "DF11";
"VSS_DF12":   PN = "DF12"  !CDS_PN = "DF12";
"VSS_DF13":   PN = "DF13"  !CDS_PN = "DF13";
"VSS_DF15":   PN = "DF15"  !CDS_PN = "DF15";
"VSS_DF17":   PN = "DF17"  !CDS_PN = "DF17";
"VSS_DF18":   PN = "DF18"  !CDS_PN = "DF18";
"VSS_DF19":   PN = "DF19"  !CDS_PN = "DF19";
"VSS_DF20":   PN = "DF20"  !CDS_PN = "DF20";
"VSS_DF22":   PN = "DF22"  !CDS_PN = "DF22";
"VSS_DF23":   PN = "DF23"  !CDS_PN = "DF23";
"VSS_DF26":   PN = "DF26"  !CDS_PN = "DF26";
"VSS_DF29":   PN = "DF29"  !CDS_PN = "DF29";
"VSS_DF32":   PN = "DF32"  !CDS_PN = "DF32";
"VSS_DF35":   PN = "DF35"  !CDS_PN = "DF35";
"VSS_DF37":   PN = "DF37"  !CDS_PN = "DF37";
"VSS_DF39":   PN = "DF39"  !CDS_PN = "DF39";
"VSS_DF42":   PN = "DF42"  !CDS_PN = "DF42";
"VSS_DF43":   PN = "DF43"  !CDS_PN = "DF43";
"VSS_DF44":   PN = "DF44"  !CDS_PN = "DF44";
"VSS_DF45":   PN = "DF45"  !CDS_PN = "DF45";
"VSS_DF46":   PN = "DF46"  !CDS_PN = "DF46";
"VSS_DF47":   PN = "DF47"  !CDS_PN = "DF47";
"VSS_DF48":   PN = "DF48"  !CDS_PN = "DF48";
"VSS_DF49":   PN = "DF49"  !CDS_PN = "DF49";
"VSS_DF50":   PN = "DF50"  !CDS_PN = "DF50";
"VSS_DF51":   PN = "DF51"  !CDS_PN = "DF51";
"VSS_DF52":   PN = "DF52"  !CDS_PN = "DF52";
"VSS_DF53":   PN = "DF53"  !CDS_PN = "DF53";
"VSS_DF54":   PN = "DF54"  !CDS_PN = "DF54";
"VSS_DF56":   PN = "DF56"  !CDS_PN = "DF56";
"VSS_DF57":   PN = "DF57"  !CDS_PN = "DF57";
"VSS_DF58":   PN = "DF58"  !CDS_PN = "DF58";
"VSS_DF59":   PN = "DF59"  !CDS_PN = "DF59";
"VSS_DF61":   PN = "DF61"  !CDS_PN = "DF61";
"VSS_DF63":   PN = "DF63"  !CDS_PN = "DF63";
"VSS_DF64":   PN = "DF64"  !CDS_PN = "DF64";
"VSS_DF65":   PN = "DF65"  !CDS_PN = "DF65";
"VSS_DF66":   PN = "DF66"  !CDS_PN = "DF66";
"VSS_DF68":   PN = "DF68"  !CDS_PN = "DF68";
"VSS_DF70":   PN = "DF70"  !CDS_PN = "DF70";
"VSS_DF71":   PN = "DF71"  !CDS_PN = "DF71";
"VSS_DF72":   PN = "DF72"  !CDS_PN = "DF72";
"VSS_DF73":   PN = "DF73"  !CDS_PN = "DF73";
"VSS_DG1":   PN = "DG1"  !CDS_PN = "DG1";
"VSS_DG2":   PN = "DG2"  !CDS_PN = "DG2";
"VSS_DG6":   PN = "DG6"  !CDS_PN = "DG6";
"VSS_DG7":   PN = "DG7"  !CDS_PN = "DG7";
"VSS_DG8":   PN = "DG8"  !CDS_PN = "DG8";
"VSS_DG9":   PN = "DG9"  !CDS_PN = "DG9";
"VSS_DG13":   PN = "DG13"  !CDS_PN = "DG13";
"VSS_DG14":   PN = "DG14"  !CDS_PN = "DG14";
"VSS_DG15":   PN = "DG15"  !CDS_PN = "DG15";
"VSS_DG16":   PN = "DG16"  !CDS_PN = "DG16";
"VSS_DG18":   PN = "DG18"  !CDS_PN = "DG18";
"VSS_DG20":   PN = "DG20"  !CDS_PN = "DG20";
"VSS_DG21":   PN = "DG21"  !CDS_PN = "DG21";
"VSS_DG24":   PN = "DG24"  !CDS_PN = "DG24";
"VSS_DG27":   PN = "DG27"  !CDS_PN = "DG27";
"VSS_DG30":   PN = "DG30"  !CDS_PN = "DG30";
"VSS_DG33":   PN = "DG33"  !CDS_PN = "DG33";
"VSS_DG41":   PN = "DG41"  !CDS_PN = "DG41";
"VSS_DG43":   PN = "DG43"  !CDS_PN = "DG43";
"VSS_DG46":   PN = "DG46"  !CDS_PN = "DG46";
"VSS_DG49":   PN = "DG49"  !CDS_PN = "DG49";
"VSS_DG52":   PN = "DG52"  !CDS_PN = "DG52";
"VSS_DG55":   PN = "DG55"  !CDS_PN = "DG55";
"VSS_DG56":   PN = "DG56"  !CDS_PN = "DG56";
"VSS_DG59":   PN = "DG59"  !CDS_PN = "DG59";
"VSS_DG60":   PN = "DG60"  !CDS_PN = "DG60";
"VSS_DG61":   PN = "DG61"  !CDS_PN = "DG61";
"VSS_DG62":   PN = "DG62"  !CDS_PN = "DG62";
"VSS_DG63":   PN = "DG63"  !CDS_PN = "DG63";
"VSS_DG65":   PN = "DG65"  !CDS_PN = "DG65";
"VSS_DG66":   PN = "DG66"  !CDS_PN = "DG66";
"VSS_DG67":   PN = "DG67"  !CDS_PN = "DG67";
"VSS_DG68":   PN = "DG68"  !CDS_PN = "DG68";
"VSS_DG69":   PN = "DG69"  !CDS_PN = "DG69";
"VSS_DG70":   PN = "DG70"  !CDS_PN = "DG70";
"VSS_DG74":   PN = "DG74"  !CDS_PN = "DG74";
"VSS_DG75":   PN = "DG75"  !CDS_PN = "DG75";
"VSS_DH5":   PN = "DH5"  !CDS_PN = "DH5";
"VSS_DH11":   PN = "DH11"  !CDS_PN = "DH11";
"VSS_DH18":   PN = "DH18"  !CDS_PN = "DH18";
"VSS_DH37":   PN = "DH37"  !CDS_PN = "DH37";
"VSS_DH39":   PN = "DH39"  !CDS_PN = "DH39";
"VSS_DH43":   PN = "DH43"  !CDS_PN = "DH43";
"VSS_DH46":   PN = "DH46"  !CDS_PN = "DH46";
"VSS_DH49":   PN = "DH49"  !CDS_PN = "DH49";
"VSS_DH52":   PN = "DH52"  !CDS_PN = "DH52";
"VSS_DH55":   PN = "DH55"  !CDS_PN = "DH55";
"VSS_DH59":   PN = "DH59"  !CDS_PN = "DH59";
"VSS_DH61":   PN = "DH61"  !CDS_PN = "DH61";
"VSS_DH63":   PN = "DH63"  !CDS_PN = "DH63";
"VSS_DH64":   PN = "DH64"  !CDS_PN = "DH64";
"VSS_DH66":   PN = "DH66"  !CDS_PN = "DH66";
"VSS_DH68":   PN = "DH68"  !CDS_PN = "DH68";
"VSS_DH70":   PN = "DH70"  !CDS_PN = "DH70";
"VSS_DJ7":   PN = "DJ7"  !CDS_PN = "DJ7";
"VSS_DJ15":   PN = "DJ15"  !CDS_PN = "DJ15";
"VSS_DJ19":   PN = "DJ19"  !CDS_PN = "DJ19";
"VSS_DJ43":   PN = "DJ43"  !CDS_PN = "DJ43";
"VSS_DJ49":   PN = "DJ49"  !CDS_PN = "DJ49";
"VSS_DJ59":   PN = "DJ59"  !CDS_PN = "DJ59";
"VSS_DJ61":   PN = "DJ61"  !CDS_PN = "DJ61";
"VSS_DJ63":   PN = "DJ63"  !CDS_PN = "DJ63";
"VSS_DJ66":   PN = "DJ66"  !CDS_PN = "DJ66";
"VSS_DJ68":   PN = "DJ68"  !CDS_PN = "DJ68";
"VSS_DJ73":   PN = "DJ73"  !CDS_PN = "DJ73";
"VSS_K23":   PN = "K23"  !CDS_PN = "K23";
"VSS_K59":   PN = "K59"  !CDS_PN = "K59";
"VSS_P25":   PN = "P25"  !CDS_PN = "P25";
"VSS_P68":   PN = "P68"  !CDS_PN = "P68";
"VSS_V27":   PN = "V27"  !CDS_PN = "V27";
"VSS_V68":   PN = "V68"  !CDS_PN = "V68";
DRAWING = "@t6g_mb_lib.t6g(sch_1):page67";
BODY = "Q_CAP","I83": #LOCATION = "C3888" !CDS_LOCATION = "C3888" &SEC = "1" #&CDS_SEC = "1";
"A":   PN = "1"  !CDS_PN = "1";
"B":   PN = "2"  !CDS_PN = "2";
BODY = "Q_CAP","I85": #LOCATION = "C2130" !CDS_LOCATION = "C2130" &SEC = "1" #&CDS_SEC = "1";
"A":   PN = "1"  !CDS_PN = "1";
"B":   PN = "2"  !CDS_PN = "2";
BODY = "Q_CAP","I86": #LOCATION = "C3889" !CDS_LOCATION = "C3889" &SEC = "1" #&CDS_SEC = "1";
"A":   PN = "1"  !CDS_PN = "1";
"B":   PN = "2"  !CDS_PN = "2";
BODY = "Q_CAP","I87": #LOCATION = "C2135" !CDS_LOCATION = "C2135" &SEC = "1" #&CDS_SEC = "1";
"A":   PN = "1"  !CDS_PN = "1";
"B":   PN = "2"  !CDS_PN = "2";
BODY = "Q_CAP","I89": #LOCATION = "C2129" !CDS_LOCATION = "C2129" &SEC = "1" #&CDS_SEC = "1";
"A":   PN = "1"  !CDS_PN = "1";
"B":   PN = "2"  !CDS_PN = "2";
BODY = "Q_CAP","I90": #LOCATION = "C2134" !CDS_LOCATION = "C2134" &SEC = "1" #&CDS_SEC = "1";
"A":   PN = "1"  !CDS_PN = "1";
"B":   PN = "2"  !CDS_PN = "2";
BODY = "Q_CAP","I92": #LOCATION = "C2140" !CDS_LOCATION = "C2140" &SEC = "1" #&CDS_SEC = "1";
"A":   PN = "1"  !CDS_PN = "1";
"B":   PN = "2"  !CDS_PN = "2";
BODY = "Q_CAP","I93": #LOCATION = "C2144" !CDS_LOCATION = "C2144" &SEC = "1" #&CDS_SEC = "1";
"A":   PN = "1"  !CDS_PN = "1";
"B":   PN = "2"  !CDS_PN = "2";
BODY = "Q_CAP","I94": #LOCATION = "C2148" !CDS_LOCATION = "C2148" &SEC = "1" #&CDS_SEC = "1";
"A":   PN = "1"  !CDS_PN = "1";
"B":   PN = "2"  !CDS_PN = "2";
BODY = "Q_CAP","I95": #LOCATION = "C2139" !CDS_LOCATION = "C2139" &SEC = "1" #&CDS_SEC = "1";
"A":   PN = "1"  !CDS_PN = "1";
"B":   PN = "2"  !CDS_PN = "2";
BODY = "Q_CAP","I96": #LOCATION = "C2143" !CDS_LOCATION = "C2143" &SEC = "1" #&CDS_SEC = "1";
"A":   PN = "1"  !CDS_PN = "1";
"B":   PN = "2"  !CDS_PN = "2";
BODY = "Q_CAP","I97": #LOCATION = "C2152" !CDS_LOCATION = "C2152" &SEC = "1" #&CDS_SEC = "1";
"A":   PN = "1"  !CDS_PN = "1";
"B":   PN = "2"  !CDS_PN = "2";
BODY = "Q_CAP","I98": #LOCATION = "C2155" !CDS_LOCATION = "C2155" &SEC = "1" #&CDS_SEC = "1";
"A":   PN = "1"  !CDS_PN = "1";
"B":   PN = "2"  !CDS_PN = "2";
BODY = "Q_CAP","I99": #LOCATION = "C2151" !CDS_LOCATION = "C2151" &SEC = "1" #&CDS_SEC = "1";
"A":   PN = "1"  !CDS_PN = "1";
"B":   PN = "2"  !CDS_PN = "2";
BODY = "Q_CAP","I100": #LOCATION = "C2154" !CDS_LOCATION = "C2154" &SEC = "1" #&CDS_SEC = "1";
"A":   PN = "1"  !CDS_PN = "1";
"B":   PN = "2"  !CDS_PN = "2";
BODY = "Q_CAP","I101": #LOCATION = "C3894" !CDS_LOCATION = "C3894" &SEC = "1" #&CDS_SEC = "1";
"A":   PN = "1"  !CDS_PN = "1";
"B":   PN = "2"  !CDS_PN = "2";
BODY = "Q_CAP","I102": #LOCATION = "C3895" !CDS_LOCATION = "C3895" &SEC = "1" #&CDS_SEC = "1";
"A":   PN = "1"  !CDS_PN = "1";
"B":   PN = "2"  !CDS_PN = "2";
BODY = "Q_CAP","I103": #LOCATION = "C2157" !CDS_LOCATION = "C2157" &SEC = "1" #&CDS_SEC = "1";
"A":   PN = "1"  !CDS_PN = "1";
"B":   PN = "2"  !CDS_PN = "2";
BODY = "Q_CAP","I104": #LOCATION = "C2159" !CDS_LOCATION = "C2159" &SEC = "1" #&CDS_SEC = "1";
"A":   PN = "1"  !CDS_PN = "1";
"B":   PN = "2"  !CDS_PN = "2";
BODY = "Q_CAP","I106": #LOCATION = "C3896" !CDS_LOCATION = "C3896" &SEC = "1" #&CDS_SEC = "1";
"A":   PN = "1"  !CDS_PN = "1";
"B":   PN = "2"  !CDS_PN = "2";
BODY = "Q_CAP","I108": #LOCATION = "C2161" !CDS_LOCATION = "C2161" &SEC = "1" #&CDS_SEC = "1";
"A":   PN = "1"  !CDS_PN = "1";
"B":   PN = "2"  !CDS_PN = "2";
BODY = "Q_CAP","I109": #LOCATION = "C2147" !CDS_LOCATION = "C2147" &SEC = "1" #&CDS_SEC = "1";
"A":   PN = "1"  !CDS_PN = "1";
"B":   PN = "2"  !CDS_PN = "2";
BODY = "Q_CAP","I110": #LOCATION = "C2133" !CDS_LOCATION = "C2133" &SEC = "1" #&CDS_SEC = "1";
"A":   PN = "1"  !CDS_PN = "1";
"B":   PN = "2"  !CDS_PN = "2";
BODY = "Q_CAP","I112": #LOCATION = "C2138" !CDS_LOCATION = "C2138" &SEC = "1" #&CDS_SEC = "1";
"A":   PN = "1"  !CDS_PN = "1";
"B":   PN = "2"  !CDS_PN = "2";
BODY = "Q_CAP","I113": #LOCATION = "C2132" !CDS_LOCATION = "C2132" &SEC = "1" #&CDS_SEC = "1";
"A":   PN = "1"  !CDS_PN = "1";
"B":   PN = "2"  !CDS_PN = "2";
BODY = "Q_CAP","I115": #LOCATION = "C2137" !CDS_LOCATION = "C2137" &SEC = "1" #&CDS_SEC = "1";
"A":   PN = "1"  !CDS_PN = "1";
"B":   PN = "2"  !CDS_PN = "2";
BODY = "Q_CAP","I116": #LOCATION = "C3890" !CDS_LOCATION = "C3890" &SEC = "1" #&CDS_SEC = "1";
"A":   PN = "1"  !CDS_PN = "1";
"B":   PN = "2"  !CDS_PN = "2";
BODY = "Q_CAP","I117": #LOCATION = "C3891" !CDS_LOCATION = "C3891" &SEC = "1" #&CDS_SEC = "1";
"A":   PN = "1"  !CDS_PN = "1";
"B":   PN = "2"  !CDS_PN = "2";
BODY = "Q_CAP","I118": #LOCATION = "C3892" !CDS_LOCATION = "C3892" &SEC = "1" #&CDS_SEC = "1";
"A":   PN = "1"  !CDS_PN = "1";
"B":   PN = "2"  !CDS_PN = "2";
BODY = "Q_CAP","I120": #LOCATION = "C3893" !CDS_LOCATION = "C3893" &SEC = "1" #&CDS_SEC = "1";
"A":   PN = "1"  !CDS_PN = "1";
"B":   PN = "2"  !CDS_PN = "2";
BODY = "Q_CAP","I121": #LOCATION = "C2142" !CDS_LOCATION = "C2142" &SEC = "1" #&CDS_SEC = "1";
"A":   PN = "1"  !CDS_PN = "1";
"B":   PN = "2"  !CDS_PN = "2";
BODY = "Q_CAP","I122": #LOCATION = "C2146" !CDS_LOCATION = "C2146" &SEC = "1" #&CDS_SEC = "1";
"A":   PN = "1"  !CDS_PN = "1";
"B":   PN = "2"  !CDS_PN = "2";
BODY = "Q_CAP","I123": #LOCATION = "C2150" !CDS_LOCATION = "C2150" &SEC = "1" #&CDS_SEC = "1";
"A":   PN = "1"  !CDS_PN = "1";
"B":   PN = "2"  !CDS_PN = "2";
BODY = "Q_CAP","I124": #LOCATION = "C2153" !CDS_LOCATION = "C2153" &SEC = "1" #&CDS_SEC = "1";
"A":   PN = "1"  !CDS_PN = "1";
"B":   PN = "2"  !CDS_PN = "2";
BODY = "Q_CAP","I125": #LOCATION = "C2156" !CDS_LOCATION = "C2156" &SEC = "1" #&CDS_SEC = "1";
"A":   PN = "1"  !CDS_PN = "1";
"B":   PN = "2"  !CDS_PN = "2";
BODY = "Q_CAP","I127": #LOCATION = "C2158" !CDS_LOCATION = "C2158" &SEC = "1" #&CDS_SEC = "1";
"A":   PN = "1"  !CDS_PN = "1";
"B":   PN = "2"  !CDS_PN = "2";
BODY = "Q_CAP","I128": #LOCATION = "C2160" !CDS_LOCATION = "C2160" &SEC = "1" #&CDS_SEC = "1";
"A":   PN = "1"  !CDS_PN = "1";
"B":   PN = "2"  !CDS_PN = "2";
BODY = "Q_CAP","I129": #LOCATION = "C2162" !CDS_LOCATION = "C2162" &SEC = "1" #&CDS_SEC = "1";
"A":   PN = "1"  !CDS_PN = "1";
"B":   PN = "2"  !CDS_PN = "2";
BODY = "Q_CAP","I131": #LOCATION = "C2163" !CDS_LOCATION = "C2163" &SEC = "1" #&CDS_SEC = "1";
"A":   PN = "1"  !CDS_PN = "1";
"B":   PN = "2"  !CDS_PN = "2";
BODY = "Q_CAP","I133": #LOCATION = "C2164" !CDS_LOCATION = "C2164" &SEC = "1" #&CDS_SEC = "1";
"A":   PN = "1"  !CDS_PN = "1";
"B":   PN = "2"  !CDS_PN = "2";
BODY = "Q_CAP","I134": #LOCATION = "C3897" !CDS_LOCATION = "C3897" &SEC = "1" #&CDS_SEC = "1";
"A":   PN = "1"  !CDS_PN = "1";
"B":   PN = "2"  !CDS_PN = "2";
BODY = "Q_CAP","I135": #LOCATION = "C2131" !CDS_LOCATION = "C2131" &SEC = "1" #&CDS_SEC = "1";
"A":   PN = "1"  !CDS_PN = "1";
"B":   PN = "2"  !CDS_PN = "2";
BODY = "Q_CAP","I136": #LOCATION = "C2136" !CDS_LOCATION = "C2136" &SEC = "1" #&CDS_SEC = "1";
"A":   PN = "1"  !CDS_PN = "1";
"B":   PN = "2"  !CDS_PN = "2";
BODY = "Q_CAP","I137": #LOCATION = "C2141" !CDS_LOCATION = "C2141" &SEC = "1" #&CDS_SEC = "1";
"A":   PN = "1"  !CDS_PN = "1";
"B":   PN = "2"  !CDS_PN = "2";
BODY = "Q_CAP","I138": #LOCATION = "C2145" !CDS_LOCATION = "C2145" &SEC = "1" #&CDS_SEC = "1";
"A":   PN = "1"  !CDS_PN = "1";
"B":   PN = "2"  !CDS_PN = "2";
BODY = "Q_CAP","I139": #LOCATION = "C2149" !CDS_LOCATION = "C2149" &SEC = "1" #&CDS_SEC = "1";
"A":   PN = "1"  !CDS_PN = "1";
"B":   PN = "2"  !CDS_PN = "2";
BODY = "Q_CAP","I141": #LOCATION = "C3898" !CDS_LOCATION = "C3898" &SEC = "1" #&CDS_SEC = "1";
"A":   PN = "1"  !CDS_PN = "1";
"B":   PN = "2"  !CDS_PN = "2";
BODY = "Q_CAP","I143": #LOCATION = "C3899" !CDS_LOCATION = "C3899" &SEC = "1" #&CDS_SEC = "1";
"A":   PN = "1"  !CDS_PN = "1";
"B":   PN = "2"  !CDS_PN = "2";
DRAWING = "@t6g_mb_lib.t6g(sch_1):page68";
BODY = "Q_CAP","I1": #LOCATION = "C2167" !CDS_LOCATION = "C2167" &SEC = "1" #&CDS_SEC = "1";
"A":   PN = "1"  !CDS_PN = "1";
"B":   PN = "2"  !CDS_PN = "2";
BODY = "Q_CAP","I2": #LOCATION = "C2171" !CDS_LOCATION = "C2171" &SEC = "1" #&CDS_SEC = "1";
"A":   PN = "1"  !CDS_PN = "1";
"B":   PN = "2"  !CDS_PN = "2";
BODY = "Q_CAP","I4": #LOCATION = "C2166" !CDS_LOCATION = "C2166" &SEC = "1" #&CDS_SEC = "1";
"A":   PN = "1"  !CDS_PN = "1";
"B":   PN = "2"  !CDS_PN = "2";
BODY = "Q_CAP","I5": #LOCATION = "C2170" !CDS_LOCATION = "C2170" &SEC = "1" #&CDS_SEC = "1";
"A":   PN = "1"  !CDS_PN = "1";
"B":   PN = "2"  !CDS_PN = "2";
BODY = "Q_CAP","I7": #LOCATION = "C2165" !CDS_LOCATION = "C2165" &SEC = "1" #&CDS_SEC = "1";
"A":   PN = "1"  !CDS_PN = "1";
"B":   PN = "2"  !CDS_PN = "2";
BODY = "Q_CAP","I9": #LOCATION = "C2169" !CDS_LOCATION = "C2169" &SEC = "1" #&CDS_SEC = "1";
"A":   PN = "1"  !CDS_PN = "1";
"B":   PN = "2"  !CDS_PN = "2";
BODY = "Q_CAP","I10": #LOCATION = "C246" !CDS_LOCATION = "C246" &SEC = "1" #&CDS_SEC = "1";
"A":   PN = "1"  !CDS_PN = "1";
"B":   PN = "2"  !CDS_PN = "2";
BODY = "Q_CAP","I12": #LOCATION = "C252" !CDS_LOCATION = "C252" &SEC = "1" #&CDS_SEC = "1";
"A":   PN = "1"  !CDS_PN = "1";
"B":   PN = "2"  !CDS_PN = "2";
BODY = "Q_CAP","I14": #LOCATION = "C245" !CDS_LOCATION = "C245" &SEC = "1" #&CDS_SEC = "1";
"A":   PN = "1"  !CDS_PN = "1";
"B":   PN = "2"  !CDS_PN = "2";
BODY = "Q_CAP","I15": #LOCATION = "C251" !CDS_LOCATION = "C251" &SEC = "1" #&CDS_SEC = "1";
"A":   PN = "1"  !CDS_PN = "1";
"B":   PN = "2"  !CDS_PN = "2";
BODY = "Q_CAP","I16": #LOCATION = "C2175" !CDS_LOCATION = "C2175" &SEC = "1" #&CDS_SEC = "1";
"A":   PN = "1"  !CDS_PN = "1";
"B":   PN = "2"  !CDS_PN = "2";
BODY = "Q_CAP","I17": #LOCATION = "C10179" !CDS_LOCATION = "C10179" &SEC = "1" #&CDS_SEC = "1";
"A":   PN = "1"  !CDS_PN = "1";
"B":   PN = "2"  !CDS_PN = "2";
BODY = "Q_CAP","I19": #LOCATION = "C2183" !CDS_LOCATION = "C2183" &SEC = "1" #&CDS_SEC = "1";
"A":   PN = "1"  !CDS_PN = "1";
"B":   PN = "2"  !CDS_PN = "2";
BODY = "Q_CAP","I20": #LOCATION = "C2174" !CDS_LOCATION = "C2174" &SEC = "1" #&CDS_SEC = "1";
"A":   PN = "1"  !CDS_PN = "1";
"B":   PN = "2"  !CDS_PN = "2";
BODY = "Q_CAP","I21": #LOCATION = "C2178" !CDS_LOCATION = "C2178" &SEC = "1" #&CDS_SEC = "1";
"A":   PN = "1"  !CDS_PN = "1";
"B":   PN = "2"  !CDS_PN = "2";
BODY = "Q_CAP","I22": #LOCATION = "C2173" !CDS_LOCATION = "C2173" &SEC = "1" #&CDS_SEC = "1";
"A":   PN = "1"  !CDS_PN = "1";
"B":   PN = "2"  !CDS_PN = "2";
BODY = "Q_CAP","I23": #LOCATION = "C2177" !CDS_LOCATION = "C2177" &SEC = "1" #&CDS_SEC = "1";
"A":   PN = "1"  !CDS_PN = "1";
"B":   PN = "2"  !CDS_PN = "2";
BODY = "Q_CAP","I24": #LOCATION = "C2182" !CDS_LOCATION = "C2182" &SEC = "1" #&CDS_SEC = "1";
"A":   PN = "1"  !CDS_PN = "1";
"B":   PN = "2"  !CDS_PN = "2";
BODY = "Q_CAP","I25": #LOCATION = "C2181" !CDS_LOCATION = "C2181" &SEC = "1" #&CDS_SEC = "1";
"A":   PN = "1"  !CDS_PN = "1";
"B":   PN = "2"  !CDS_PN = "2";
BODY = "Q_CAP","I26": #LOCATION = "C2186" !CDS_LOCATION = "C2186" &SEC = "1" #&CDS_SEC = "1";
"A":   PN = "1"  !CDS_PN = "1";
"B":   PN = "2"  !CDS_PN = "2";
BODY = "Q_CAP","I27": #LOCATION = "C2190" !CDS_LOCATION = "C2190" &SEC = "1" #&CDS_SEC = "1";
"A":   PN = "1"  !CDS_PN = "1";
"B":   PN = "2"  !CDS_PN = "2";
BODY = "Q_CAP","I28": #LOCATION = "C2185" !CDS_LOCATION = "C2185" &SEC = "1" #&CDS_SEC = "1";
"A":   PN = "1"  !CDS_PN = "1";
"B":   PN = "2"  !CDS_PN = "2";
BODY = "Q_CAP","I29": #LOCATION = "C2189" !CDS_LOCATION = "C2189" &SEC = "1" #&CDS_SEC = "1";
"A":   PN = "1"  !CDS_PN = "1";
"B":   PN = "2"  !CDS_PN = "2";
BODY = "Q_CAP","I30": #LOCATION = "C2205" !CDS_LOCATION = "C2205" &SEC = "1" #&CDS_SEC = "1";
"A":   PN = "1"  !CDS_PN = "1";
"B":   PN = "2"  !CDS_PN = "2";
BODY = "Q_CAP","I31": #LOCATION = "C2193" !CDS_LOCATION = "C2193" &SEC = "1" #&CDS_SEC = "1";
"A":   PN = "1"  !CDS_PN = "1";
"B":   PN = "2"  !CDS_PN = "2";
BODY = "Q_CAP","I32": #LOCATION = "C2196" !CDS_LOCATION = "C2196" &SEC = "1" #&CDS_SEC = "1";
"A":   PN = "1"  !CDS_PN = "1";
"B":   PN = "2"  !CDS_PN = "2";
BODY = "Q_CAP","I33": #LOCATION = "C2192" !CDS_LOCATION = "C2192" &SEC = "1" #&CDS_SEC = "1";
"A":   PN = "1"  !CDS_PN = "1";
"B":   PN = "2"  !CDS_PN = "2";
BODY = "Q_CAP","I34": #LOCATION = "C2195" !CDS_LOCATION = "C2195" &SEC = "1" #&CDS_SEC = "1";
"A":   PN = "1"  !CDS_PN = "1";
"B":   PN = "2"  !CDS_PN = "2";
BODY = "Q_CAP","I36": #LOCATION = "C2199" !CDS_LOCATION = "C2199" &SEC = "1" #&CDS_SEC = "1";
"A":   PN = "1"  !CDS_PN = "1";
"B":   PN = "2"  !CDS_PN = "2";
BODY = "Q_CAP","I38": #LOCATION = "C2204" !CDS_LOCATION = "C2204" &SEC = "1" #&CDS_SEC = "1";
"A":   PN = "1"  !CDS_PN = "1";
"B":   PN = "2"  !CDS_PN = "2";
BODY = "Q_CAP","I40": #LOCATION = "C2198" !CDS_LOCATION = "C2198" &SEC = "1" #&CDS_SEC = "1";
"A":   PN = "1"  !CDS_PN = "1";
"B":   PN = "2"  !CDS_PN = "2";
BODY = "Q_CAP","I43": #LOCATION = "C2203" !CDS_LOCATION = "C2203" &SEC = "1" #&CDS_SEC = "1";
"A":   PN = "1"  !CDS_PN = "1";
"B":   PN = "2"  !CDS_PN = "2";
BODY = "Q_CAP","I45": #LOCATION = "C1922" !CDS_LOCATION = "C1922" &SEC = "1" #&CDS_SEC = "1";
"A":   PN = "1"  !CDS_PN = "1";
"B":   PN = "2"  !CDS_PN = "2";
BODY = "Q_CAP","I46": #LOCATION = "C263" !CDS_LOCATION = "C263" &SEC = "1" #&CDS_SEC = "1";
"A":   PN = "1"  !CDS_PN = "1";
"B":   PN = "2"  !CDS_PN = "2";
BODY = "Q_CAP","I47": #LOCATION = "C4178" !CDS_LOCATION = "C4178" &SEC = "1" #&CDS_SEC = "1";
"A":   PN = "1"  !CDS_PN = "1";
"B":   PN = "2"  !CDS_PN = "2";
BODY = "Q_CAP","I48": #LOCATION = "C4179" !CDS_LOCATION = "C4179" &SEC = "1" #&CDS_SEC = "1";
"A":   PN = "1"  !CDS_PN = "1";
"B":   PN = "2"  !CDS_PN = "2";
BODY = "Q_CAP","I49": #LOCATION = "C268" !CDS_LOCATION = "C268" &SEC = "1" #&CDS_SEC = "1";
"A":   PN = "1"  !CDS_PN = "1";
"B":   PN = "2"  !CDS_PN = "2";
BODY = "Q_CAP","I50": #LOCATION = "C267" !CDS_LOCATION = "C267" &SEC = "1" #&CDS_SEC = "1";
"A":   PN = "1"  !CDS_PN = "1";
"B":   PN = "2"  !CDS_PN = "2";
BODY = "Q_CAP","I51": #LOCATION = "C271" !CDS_LOCATION = "C271" &SEC = "1" #&CDS_SEC = "1";
"A":   PN = "1"  !CDS_PN = "1";
"B":   PN = "2"  !CDS_PN = "2";
BODY = "Q_CAP","I52": #LOCATION = "C273" !CDS_LOCATION = "C273" &SEC = "1" #&CDS_SEC = "1";
"A":   PN = "1"  !CDS_PN = "1";
"B":   PN = "2"  !CDS_PN = "2";
BODY = "Q_CAP","I53": #LOCATION = "C270" !CDS_LOCATION = "C270" &SEC = "1" #&CDS_SEC = "1";
"A":   PN = "1"  !CDS_PN = "1";
"B":   PN = "2"  !CDS_PN = "2";
BODY = "Q_CAP","I54": #LOCATION = "C275" !CDS_LOCATION = "C275" &SEC = "1" #&CDS_SEC = "1";
"A":   PN = "1"  !CDS_PN = "1";
"B":   PN = "2"  !CDS_PN = "2";
BODY = "Q_CAP","I55": #LOCATION = "C277" !CDS_LOCATION = "C277" &SEC = "1" #&CDS_SEC = "1";
"A":   PN = "1"  !CDS_PN = "1";
"B":   PN = "2"  !CDS_PN = "2";
BODY = "Q_CAP","I56": #LOCATION = "C274" !CDS_LOCATION = "C274" &SEC = "1" #&CDS_SEC = "1";
"A":   PN = "1"  !CDS_PN = "1";
"B":   PN = "2"  !CDS_PN = "2";
BODY = "Q_CAP","I57": #LOCATION = "C276" !CDS_LOCATION = "C276" &SEC = "1" #&CDS_SEC = "1";
"A":   PN = "1"  !CDS_PN = "1";
"B":   PN = "2"  !CDS_PN = "2";
BODY = "Q_CAP","I58": #LOCATION = "C279" !CDS_LOCATION = "C279" &SEC = "1" #&CDS_SEC = "1";
"A":   PN = "1"  !CDS_PN = "1";
"B":   PN = "2"  !CDS_PN = "2";
BODY = "Q_CAP","I60": #LOCATION = "C2202" !CDS_LOCATION = "C2202" &SEC = "1" #&CDS_SEC = "1";
"A":   PN = "1"  !CDS_PN = "1";
"B":   PN = "2"  !CDS_PN = "2";
BODY = "Q_CAP","I62": #LOCATION = "C278" !CDS_LOCATION = "C278" &SEC = "1" #&CDS_SEC = "1";
"A":   PN = "1"  !CDS_PN = "1";
"B":   PN = "2"  !CDS_PN = "2";
BODY = "Q_CAP","I63": #LOCATION = "C2201" !CDS_LOCATION = "C2201" &SEC = "1" #&CDS_SEC = "1";
"A":   PN = "1"  !CDS_PN = "1";
"B":   PN = "2"  !CDS_PN = "2";
BODY = "Q_CAP","I65": #LOCATION = "C2211" !CDS_LOCATION = "C2211" &SEC = "1" #&CDS_SEC = "1";
"A":   PN = "1"  !CDS_PN = "1";
"B":   PN = "2"  !CDS_PN = "2";
BODY = "Q_CAP","I66": #LOCATION = "C2217" !CDS_LOCATION = "C2217" &SEC = "1" #&CDS_SEC = "1";
"A":   PN = "1"  !CDS_PN = "1";
"B":   PN = "2"  !CDS_PN = "2";
BODY = "Q_CAP","I67": #LOCATION = "C2223" !CDS_LOCATION = "C2223" &SEC = "1" #&CDS_SEC = "1";
"A":   PN = "1"  !CDS_PN = "1";
"B":   PN = "2"  !CDS_PN = "2";
BODY = "Q_CAP","I69": #LOCATION = "C2229" !CDS_LOCATION = "C2229" &SEC = "1" #&CDS_SEC = "1";
"A":   PN = "1"  !CDS_PN = "1";
"B":   PN = "2"  !CDS_PN = "2";
BODY = "Q_CAP","I70": #LOCATION = "C2210" !CDS_LOCATION = "C2210" &SEC = "1" #&CDS_SEC = "1";
"A":   PN = "1"  !CDS_PN = "1";
"B":   PN = "2"  !CDS_PN = "2";
BODY = "Q_CAP","I71": #LOCATION = "C2216" !CDS_LOCATION = "C2216" &SEC = "1" #&CDS_SEC = "1";
"A":   PN = "1"  !CDS_PN = "1";
"B":   PN = "2"  !CDS_PN = "2";
BODY = "Q_CAP","I72": #LOCATION = "C2209" !CDS_LOCATION = "C2209" &SEC = "1" #&CDS_SEC = "1";
"A":   PN = "1"  !CDS_PN = "1";
"B":   PN = "2"  !CDS_PN = "2";
BODY = "Q_CAP","I73": #LOCATION = "C2215" !CDS_LOCATION = "C2215" &SEC = "1" #&CDS_SEC = "1";
"A":   PN = "1"  !CDS_PN = "1";
"B":   PN = "2"  !CDS_PN = "2";
BODY = "Q_CAP","I74": #LOCATION = "C2222" !CDS_LOCATION = "C2222" &SEC = "1" #&CDS_SEC = "1";
"A":   PN = "1"  !CDS_PN = "1";
"B":   PN = "2"  !CDS_PN = "2";
BODY = "Q_CAP","I75": #LOCATION = "C2228" !CDS_LOCATION = "C2228" &SEC = "1" #&CDS_SEC = "1";
"A":   PN = "1"  !CDS_PN = "1";
"B":   PN = "2"  !CDS_PN = "2";
BODY = "Q_CAP","I76": #LOCATION = "C2234" !CDS_LOCATION = "C2234" &SEC = "1" #&CDS_SEC = "1";
"A":   PN = "1"  !CDS_PN = "1";
"B":   PN = "2"  !CDS_PN = "2";
BODY = "Q_CAP","I77": #LOCATION = "C2221" !CDS_LOCATION = "C2221" &SEC = "1" #&CDS_SEC = "1";
"A":   PN = "1"  !CDS_PN = "1";
"B":   PN = "2"  !CDS_PN = "2";
BODY = "Q_CAP","I78": #LOCATION = "C2227" !CDS_LOCATION = "C2227" &SEC = "1" #&CDS_SEC = "1";
"A":   PN = "1"  !CDS_PN = "1";
"B":   PN = "2"  !CDS_PN = "2";
BODY = "Q_CAP","I79": #LOCATION = "C2233" !CDS_LOCATION = "C2233" &SEC = "1" #&CDS_SEC = "1";
"A":   PN = "1"  !CDS_PN = "1";
"B":   PN = "2"  !CDS_PN = "2";
BODY = "Q_CAP","I80": #LOCATION = "C2240" !CDS_LOCATION = "C2240" &SEC = "1" #&CDS_SEC = "1";
"A":   PN = "1"  !CDS_PN = "1";
"B":   PN = "2"  !CDS_PN = "2";
BODY = "Q_CAP","I81": #LOCATION = "C2246" !CDS_LOCATION = "C2246" &SEC = "1" #&CDS_SEC = "1";
"A":   PN = "1"  !CDS_PN = "1";
"B":   PN = "2"  !CDS_PN = "2";
BODY = "Q_CAP","I82": #LOCATION = "C2239" !CDS_LOCATION = "C2239" &SEC = "1" #&CDS_SEC = "1";
"A":   PN = "1"  !CDS_PN = "1";
"B":   PN = "2"  !CDS_PN = "2";
BODY = "Q_CAP","I83": #LOCATION = "C2245" !CDS_LOCATION = "C2245" &SEC = "1" #&CDS_SEC = "1";
"A":   PN = "1"  !CDS_PN = "1";
"B":   PN = "2"  !CDS_PN = "2";
BODY = "Q_CAP","I84": #LOCATION = "C2251" !CDS_LOCATION = "C2251" &SEC = "1" #&CDS_SEC = "1";
"A":   PN = "1"  !CDS_PN = "1";
"B":   PN = "2"  !CDS_PN = "2";
BODY = "Q_CAP","I86": #LOCATION = "C2256" !CDS_LOCATION = "C2256" &SEC = "1" #&CDS_SEC = "1";
"A":   PN = "1"  !CDS_PN = "1";
"B":   PN = "2"  !CDS_PN = "2";
BODY = "Q_CAP","I87": #LOCATION = "C2250" !CDS_LOCATION = "C2250" &SEC = "1" #&CDS_SEC = "1";
"A":   PN = "1"  !CDS_PN = "1";
"B":   PN = "2"  !CDS_PN = "2";
BODY = "Q_CAP","I89": #LOCATION = "C2255" !CDS_LOCATION = "C2255" &SEC = "1" #&CDS_SEC = "1";
"A":   PN = "1"  !CDS_PN = "1";
"B":   PN = "2"  !CDS_PN = "2";
BODY = "Q_CAP","I91": #LOCATION = "C2208" !CDS_LOCATION = "C2208" &SEC = "1" #&CDS_SEC = "1";
"A":   PN = "1"  !CDS_PN = "1";
"B":   PN = "2"  !CDS_PN = "2";
BODY = "Q_CAP","I92": #LOCATION = "C2214" !CDS_LOCATION = "C2214" &SEC = "1" #&CDS_SEC = "1";
"A":   PN = "1"  !CDS_PN = "1";
"B":   PN = "2"  !CDS_PN = "2";
BODY = "Q_CAP","I93": #LOCATION = "C2207" !CDS_LOCATION = "C2207" &SEC = "1" #&CDS_SEC = "1";
"A":   PN = "1"  !CDS_PN = "1";
"B":   PN = "2"  !CDS_PN = "2";
BODY = "Q_CAP","I94": #LOCATION = "C2213" !CDS_LOCATION = "C2213" &SEC = "1" #&CDS_SEC = "1";
"A":   PN = "1"  !CDS_PN = "1";
"B":   PN = "2"  !CDS_PN = "2";
BODY = "Q_CAP","I95": #LOCATION = "C2220" !CDS_LOCATION = "C2220" &SEC = "1" #&CDS_SEC = "1";
"A":   PN = "1"  !CDS_PN = "1";
"B":   PN = "2"  !CDS_PN = "2";
BODY = "Q_CAP","I96": #LOCATION = "C2226" !CDS_LOCATION = "C2226" &SEC = "1" #&CDS_SEC = "1";
"A":   PN = "1"  !CDS_PN = "1";
"B":   PN = "2"  !CDS_PN = "2";
BODY = "Q_CAP","I97": #LOCATION = "C2232" !CDS_LOCATION = "C2232" &SEC = "1" #&CDS_SEC = "1";
"A":   PN = "1"  !CDS_PN = "1";
"B":   PN = "2"  !CDS_PN = "2";
BODY = "Q_CAP","I98": #LOCATION = "C2219" !CDS_LOCATION = "C2219" &SEC = "1" #&CDS_SEC = "1";
"A":   PN = "1"  !CDS_PN = "1";
"B":   PN = "2"  !CDS_PN = "2";
BODY = "Q_CAP","I99": #LOCATION = "C2225" !CDS_LOCATION = "C2225" &SEC = "1" #&CDS_SEC = "1";
"A":   PN = "1"  !CDS_PN = "1";
"B":   PN = "2"  !CDS_PN = "2";
BODY = "Q_CAP","I100": #LOCATION = "C2231" !CDS_LOCATION = "C2231" &SEC = "1" #&CDS_SEC = "1";
"A":   PN = "1"  !CDS_PN = "1";
"B":   PN = "2"  !CDS_PN = "2";
BODY = "Q_CAP","I101": #LOCATION = "C2238" !CDS_LOCATION = "C2238" &SEC = "1" #&CDS_SEC = "1";
"A":   PN = "1"  !CDS_PN = "1";
"B":   PN = "2"  !CDS_PN = "2";
BODY = "Q_CAP","I102": #LOCATION = "C2244" !CDS_LOCATION = "C2244" &SEC = "1" #&CDS_SEC = "1";
"A":   PN = "1"  !CDS_PN = "1";
"B":   PN = "2"  !CDS_PN = "2";
BODY = "Q_CAP","I103": #LOCATION = "C2237" !CDS_LOCATION = "C2237" &SEC = "1" #&CDS_SEC = "1";
"A":   PN = "1"  !CDS_PN = "1";
"B":   PN = "2"  !CDS_PN = "2";
BODY = "Q_CAP","I104": #LOCATION = "C2243" !CDS_LOCATION = "C2243" &SEC = "1" #&CDS_SEC = "1";
"A":   PN = "1"  !CDS_PN = "1";
"B":   PN = "2"  !CDS_PN = "2";
BODY = "Q_CAP","I105": #LOCATION = "C2249" !CDS_LOCATION = "C2249" &SEC = "1" #&CDS_SEC = "1";
"A":   PN = "1"  !CDS_PN = "1";
"B":   PN = "2"  !CDS_PN = "2";
BODY = "Q_CAP","I106": #LOCATION = "C2254" !CDS_LOCATION = "C2254" &SEC = "1" #&CDS_SEC = "1";
"A":   PN = "1"  !CDS_PN = "1";
"B":   PN = "2"  !CDS_PN = "2";
BODY = "Q_CAP","I108": #LOCATION = "C2248" !CDS_LOCATION = "C2248" &SEC = "1" #&CDS_SEC = "1";
"A":   PN = "1"  !CDS_PN = "1";
"B":   PN = "2"  !CDS_PN = "2";
BODY = "Q_CAP","I109": #LOCATION = "C2253" !CDS_LOCATION = "C2253" &SEC = "1" #&CDS_SEC = "1";
"A":   PN = "1"  !CDS_PN = "1";
"B":   PN = "2"  !CDS_PN = "2";
BODY = "Q_CAP","I110": #LOCATION = "C272" !CDS_LOCATION = "C272" &SEC = "1" #&CDS_SEC = "1";
"A":   PN = "1"  !CDS_PN = "1";
"B":   PN = "2"  !CDS_PN = "2";
DRAWING = "@t6g_mb_lib.t6g(sch_1):page69";
BODY = "Q_CAP","I1": #LOCATION = "C3925" !CDS_LOCATION = "C3925" &SEC = "1" #&CDS_SEC = "1";
"A":   PN = "1"  !CDS_PN = "1";
"B":   PN = "2"  !CDS_PN = "2";
BODY = "Q_CAP","I3": #LOCATION = "C3926" !CDS_LOCATION = "C3926" &SEC = "1" #&CDS_SEC = "1";
"A":   PN = "1"  !CDS_PN = "1";
"B":   PN = "2"  !CDS_PN = "2";
BODY = "Q_CAP","I4": #LOCATION = "C2533" !CDS_LOCATION = "C2533" &SEC = "1" #&CDS_SEC = "1";
"A":   PN = "1"  !CDS_PN = "1";
"B":   PN = "2"  !CDS_PN = "2";
BODY = "Q_CAP","I6": #LOCATION = "C2540" !CDS_LOCATION = "C2540" &SEC = "1" #&CDS_SEC = "1";
"A":   PN = "1"  !CDS_PN = "1";
"B":   PN = "2"  !CDS_PN = "2";
BODY = "Q_CAP","I7": #LOCATION = "C2532" !CDS_LOCATION = "C2532" &SEC = "1" #&CDS_SEC = "1";
"A":   PN = "1"  !CDS_PN = "1";
"B":   PN = "2"  !CDS_PN = "2";
BODY = "Q_CAP","I9": #LOCATION = "C2531" !CDS_LOCATION = "C2531" &SEC = "1" #&CDS_SEC = "1";
"A":   PN = "1"  !CDS_PN = "1";
"B":   PN = "2"  !CDS_PN = "2";
BODY = "Q_CAP","I10": #LOCATION = "C2539" !CDS_LOCATION = "C2539" &SEC = "1" #&CDS_SEC = "1";
"A":   PN = "1"  !CDS_PN = "1";
"B":   PN = "2"  !CDS_PN = "2";
BODY = "Q_CAP","I11": #LOCATION = "C2538" !CDS_LOCATION = "C2538" &SEC = "1" #&CDS_SEC = "1";
"A":   PN = "1"  !CDS_PN = "1";
"B":   PN = "2"  !CDS_PN = "2";
BODY = "Q_CAP","I13": #LOCATION = "C2530" !CDS_LOCATION = "C2530" &SEC = "1" #&CDS_SEC = "1";
"A":   PN = "1"  !CDS_PN = "1";
"B":   PN = "2"  !CDS_PN = "2";
BODY = "Q_CAP","I15": #LOCATION = "C2537" !CDS_LOCATION = "C2537" &SEC = "1" #&CDS_SEC = "1";
"A":   PN = "1"  !CDS_PN = "1";
"B":   PN = "2"  !CDS_PN = "2";
BODY = "Q_CAP","I16": #LOCATION = "C2529" !CDS_LOCATION = "C2529" &SEC = "1" #&CDS_SEC = "1";
"A":   PN = "1"  !CDS_PN = "1";
"B":   PN = "2"  !CDS_PN = "2";
BODY = "Q_CAP","I18": #LOCATION = "C2528" !CDS_LOCATION = "C2528" &SEC = "1" #&CDS_SEC = "1";
"A":   PN = "1"  !CDS_PN = "1";
"B":   PN = "2"  !CDS_PN = "2";
BODY = "Q_CAP","I19": #LOCATION = "C2536" !CDS_LOCATION = "C2536" &SEC = "1" #&CDS_SEC = "1";
"A":   PN = "1"  !CDS_PN = "1";
"B":   PN = "2"  !CDS_PN = "2";
BODY = "Q_CAP","I20": #LOCATION = "C2535" !CDS_LOCATION = "C2535" &SEC = "1" #&CDS_SEC = "1";
"A":   PN = "1"  !CDS_PN = "1";
"B":   PN = "2"  !CDS_PN = "2";
BODY = "Q_CAP","I22": #LOCATION = "C2527" !CDS_LOCATION = "C2527" &SEC = "1" #&CDS_SEC = "1";
"A":   PN = "1"  !CDS_PN = "1";
"B":   PN = "2"  !CDS_PN = "2";
BODY = "Q_CAP","I24": #LOCATION = "C2534" !CDS_LOCATION = "C2534" &SEC = "1" #&CDS_SEC = "1";
"A":   PN = "1"  !CDS_PN = "1";
"B":   PN = "2"  !CDS_PN = "2";
BODY = "Q_CAP","I25": #LOCATION = "C3927" !CDS_LOCATION = "C3927" &SEC = "1" #&CDS_SEC = "1";
"A":   PN = "1"  !CDS_PN = "1";
"B":   PN = "2"  !CDS_PN = "2";
BODY = "Q_CAP","I26": #LOCATION = "C3928" !CDS_LOCATION = "C3928" &SEC = "1" #&CDS_SEC = "1";
"A":   PN = "1"  !CDS_PN = "1";
"B":   PN = "2"  !CDS_PN = "2";
BODY = "Q_CAP","I27": #LOCATION = "C3929" !CDS_LOCATION = "C3929" &SEC = "1" #&CDS_SEC = "1";
"A":   PN = "1"  !CDS_PN = "1";
"B":   PN = "2"  !CDS_PN = "2";
BODY = "Q_CAP","I28": #LOCATION = "C2547" !CDS_LOCATION = "C2547" &SEC = "1" #&CDS_SEC = "1";
"A":   PN = "1"  !CDS_PN = "1";
"B":   PN = "2"  !CDS_PN = "2";
BODY = "Q_CAP","I29": #LOCATION = "C2554" !CDS_LOCATION = "C2554" &SEC = "1" #&CDS_SEC = "1";
"A":   PN = "1"  !CDS_PN = "1";
"B":   PN = "2"  !CDS_PN = "2";
BODY = "Q_CAP","I30": #LOCATION = "C2561" !CDS_LOCATION = "C2561" &SEC = "1" #&CDS_SEC = "1";
"A":   PN = "1"  !CDS_PN = "1";
"B":   PN = "2"  !CDS_PN = "2";
BODY = "Q_CAP","I31": #LOCATION = "C3930" !CDS_LOCATION = "C3930" &SEC = "1" #&CDS_SEC = "1";
"A":   PN = "1"  !CDS_PN = "1";
"B":   PN = "2"  !CDS_PN = "2";
BODY = "Q_CAP","I33": #LOCATION = "C3931" !CDS_LOCATION = "C3931" &SEC = "1" #&CDS_SEC = "1";
"A":   PN = "1"  !CDS_PN = "1";
"B":   PN = "2"  !CDS_PN = "2";
BODY = "Q_CAP","I34": #LOCATION = "C2568" !CDS_LOCATION = "C2568" &SEC = "1" #&CDS_SEC = "1";
"A":   PN = "1"  !CDS_PN = "1";
"B":   PN = "2"  !CDS_PN = "2";
BODY = "Q_CAP","I35": #LOCATION = "C2575" !CDS_LOCATION = "C2575" &SEC = "1" #&CDS_SEC = "1";
"A":   PN = "1"  !CDS_PN = "1";
"B":   PN = "2"  !CDS_PN = "2";
BODY = "Q_CAP","I36": #LOCATION = "C2546" !CDS_LOCATION = "C2546" &SEC = "1" #&CDS_SEC = "1";
"A":   PN = "1"  !CDS_PN = "1";
"B":   PN = "2"  !CDS_PN = "2";
BODY = "Q_CAP","I37": #LOCATION = "C2545" !CDS_LOCATION = "C2545" &SEC = "1" #&CDS_SEC = "1";
"A":   PN = "1"  !CDS_PN = "1";
"B":   PN = "2"  !CDS_PN = "2";
BODY = "Q_CAP","I38": #LOCATION = "C2553" !CDS_LOCATION = "C2553" &SEC = "1" #&CDS_SEC = "1";
"A":   PN = "1"  !CDS_PN = "1";
"B":   PN = "2"  !CDS_PN = "2";
BODY = "Q_CAP","I39": #LOCATION = "C2560" !CDS_LOCATION = "C2560" &SEC = "1" #&CDS_SEC = "1";
"A":   PN = "1"  !CDS_PN = "1";
"B":   PN = "2"  !CDS_PN = "2";
BODY = "Q_CAP","I40": #LOCATION = "C2552" !CDS_LOCATION = "C2552" &SEC = "1" #&CDS_SEC = "1";
"A":   PN = "1"  !CDS_PN = "1";
"B":   PN = "2"  !CDS_PN = "2";
BODY = "Q_CAP","I41": #LOCATION = "C2559" !CDS_LOCATION = "C2559" &SEC = "1" #&CDS_SEC = "1";
"A":   PN = "1"  !CDS_PN = "1";
"B":   PN = "2"  !CDS_PN = "2";
BODY = "Q_CAP","I42": #LOCATION = "C2544" !CDS_LOCATION = "C2544" &SEC = "1" #&CDS_SEC = "1";
"A":   PN = "1"  !CDS_PN = "1";
"B":   PN = "2"  !CDS_PN = "2";
BODY = "Q_CAP","I43": #LOCATION = "C2551" !CDS_LOCATION = "C2551" &SEC = "1" #&CDS_SEC = "1";
"A":   PN = "1"  !CDS_PN = "1";
"B":   PN = "2"  !CDS_PN = "2";
BODY = "Q_CAP","I44": #LOCATION = "C2558" !CDS_LOCATION = "C2558" &SEC = "1" #&CDS_SEC = "1";
"A":   PN = "1"  !CDS_PN = "1";
"B":   PN = "2"  !CDS_PN = "2";
BODY = "Q_CAP","I45": #LOCATION = "C2567" !CDS_LOCATION = "C2567" &SEC = "1" #&CDS_SEC = "1";
"A":   PN = "1"  !CDS_PN = "1";
"B":   PN = "2"  !CDS_PN = "2";
BODY = "Q_CAP","I46": #LOCATION = "C2566" !CDS_LOCATION = "C2566" &SEC = "1" #&CDS_SEC = "1";
"A":   PN = "1"  !CDS_PN = "1";
"B":   PN = "2"  !CDS_PN = "2";
BODY = "Q_CAP","I47": #LOCATION = "C2574" !CDS_LOCATION = "C2574" &SEC = "1" #&CDS_SEC = "1";
"A":   PN = "1"  !CDS_PN = "1";
"B":   PN = "2"  !CDS_PN = "2";
BODY = "Q_CAP","I48": #LOCATION = "C2573" !CDS_LOCATION = "C2573" &SEC = "1" #&CDS_SEC = "1";
"A":   PN = "1"  !CDS_PN = "1";
"B":   PN = "2"  !CDS_PN = "2";
BODY = "Q_CAP","I49": #LOCATION = "C2565" !CDS_LOCATION = "C2565" &SEC = "1" #&CDS_SEC = "1";
"A":   PN = "1"  !CDS_PN = "1";
"B":   PN = "2"  !CDS_PN = "2";
BODY = "Q_CAP","I50": #LOCATION = "C2572" !CDS_LOCATION = "C2572" &SEC = "1" #&CDS_SEC = "1";
"A":   PN = "1"  !CDS_PN = "1";
"B":   PN = "2"  !CDS_PN = "2";
BODY = "Q_CAP","I51": #LOCATION = "C2582" !CDS_LOCATION = "C2582" &SEC = "1" #&CDS_SEC = "1";
"A":   PN = "1"  !CDS_PN = "1";
"B":   PN = "2"  !CDS_PN = "2";
BODY = "Q_CAP","I52": #LOCATION = "C2589" !CDS_LOCATION = "C2589" &SEC = "1" #&CDS_SEC = "1";
"A":   PN = "1"  !CDS_PN = "1";
"B":   PN = "2"  !CDS_PN = "2";
BODY = "Q_CAP","I53": #LOCATION = "C3932" !CDS_LOCATION = "C3932" &SEC = "1" #&CDS_SEC = "1";
"A":   PN = "1"  !CDS_PN = "1";
"B":   PN = "2"  !CDS_PN = "2";
BODY = "Q_CAP","I56": #LOCATION = "C2596" !CDS_LOCATION = "C2596" &SEC = "1" #&CDS_SEC = "1";
"A":   PN = "1"  !CDS_PN = "1";
"B":   PN = "2"  !CDS_PN = "2";
BODY = "Q_CAP","I58": #LOCATION = "C2603" !CDS_LOCATION = "C2603" &SEC = "1" #&CDS_SEC = "1";
"A":   PN = "1"  !CDS_PN = "1";
"B":   PN = "2"  !CDS_PN = "2";
BODY = "Q_CAP","I60": #LOCATION = "C2602" !CDS_LOCATION = "C2602" &SEC = "1" #&CDS_SEC = "1";
"A":   PN = "1"  !CDS_PN = "1";
"B":   PN = "2"  !CDS_PN = "2";
BODY = "Q_CAP","I61": #LOCATION = "C2581" !CDS_LOCATION = "C2581" &SEC = "1" #&CDS_SEC = "1";
"A":   PN = "1"  !CDS_PN = "1";
"B":   PN = "2"  !CDS_PN = "2";
BODY = "Q_CAP","I62": #LOCATION = "C2580" !CDS_LOCATION = "C2580" &SEC = "1" #&CDS_SEC = "1";
"A":   PN = "1"  !CDS_PN = "1";
"B":   PN = "2"  !CDS_PN = "2";
BODY = "Q_CAP","I63": #LOCATION = "C2588" !CDS_LOCATION = "C2588" &SEC = "1" #&CDS_SEC = "1";
"A":   PN = "1"  !CDS_PN = "1";
"B":   PN = "2"  !CDS_PN = "2";
BODY = "Q_CAP","I64": #LOCATION = "C2587" !CDS_LOCATION = "C2587" &SEC = "1" #&CDS_SEC = "1";
"A":   PN = "1"  !CDS_PN = "1";
"B":   PN = "2"  !CDS_PN = "2";
BODY = "Q_CAP","I65": #LOCATION = "C2579" !CDS_LOCATION = "C2579" &SEC = "1" #&CDS_SEC = "1";
"A":   PN = "1"  !CDS_PN = "1";
"B":   PN = "2"  !CDS_PN = "2";
BODY = "Q_CAP","I66": #LOCATION = "C2586" !CDS_LOCATION = "C2586" &SEC = "1" #&CDS_SEC = "1";
"A":   PN = "1"  !CDS_PN = "1";
"B":   PN = "2"  !CDS_PN = "2";
BODY = "Q_CAP","I67": #LOCATION = "C2595" !CDS_LOCATION = "C2595" &SEC = "1" #&CDS_SEC = "1";
"A":   PN = "1"  !CDS_PN = "1";
"B":   PN = "2"  !CDS_PN = "2";
BODY = "Q_CAP","I69": #LOCATION = "C2594" !CDS_LOCATION = "C2594" &SEC = "1" #&CDS_SEC = "1";
"A":   PN = "1"  !CDS_PN = "1";
"B":   PN = "2"  !CDS_PN = "2";
BODY = "Q_CAP","I71": #LOCATION = "C2601" !CDS_LOCATION = "C2601" &SEC = "1" #&CDS_SEC = "1";
"A":   PN = "1"  !CDS_PN = "1";
"B":   PN = "2"  !CDS_PN = "2";
BODY = "Q_CAP","I74": #LOCATION = "C2593" !CDS_LOCATION = "C2593" &SEC = "1" #&CDS_SEC = "1";
"A":   PN = "1"  !CDS_PN = "1";
"B":   PN = "2"  !CDS_PN = "2";
BODY = "Q_CAP","I76": #LOCATION = "C2600" !CDS_LOCATION = "C2600" &SEC = "1" #&CDS_SEC = "1";
"A":   PN = "1"  !CDS_PN = "1";
"B":   PN = "2"  !CDS_PN = "2";
BODY = "Q_CAP","I78": #LOCATION = "C2543" !CDS_LOCATION = "C2543" &SEC = "1" #&CDS_SEC = "1";
"A":   PN = "1"  !CDS_PN = "1";
"B":   PN = "2"  !CDS_PN = "2";
BODY = "Q_CAP","I79": #LOCATION = "C2542" !CDS_LOCATION = "C2542" &SEC = "1" #&CDS_SEC = "1";
"A":   PN = "1"  !CDS_PN = "1";
"B":   PN = "2"  !CDS_PN = "2";
BODY = "Q_CAP","I80": #LOCATION = "C2550" !CDS_LOCATION = "C2550" &SEC = "1" #&CDS_SEC = "1";
"A":   PN = "1"  !CDS_PN = "1";
"B":   PN = "2"  !CDS_PN = "2";
BODY = "Q_CAP","I81": #LOCATION = "C2549" !CDS_LOCATION = "C2549" &SEC = "1" #&CDS_SEC = "1";
"A":   PN = "1"  !CDS_PN = "1";
"B":   PN = "2"  !CDS_PN = "2";
BODY = "Q_CAP","I82": #LOCATION = "C2557" !CDS_LOCATION = "C2557" &SEC = "1" #&CDS_SEC = "1";
"A":   PN = "1"  !CDS_PN = "1";
"B":   PN = "2"  !CDS_PN = "2";
BODY = "Q_CAP","I83": #LOCATION = "C2556" !CDS_LOCATION = "C2556" &SEC = "1" #&CDS_SEC = "1";
"A":   PN = "1"  !CDS_PN = "1";
"B":   PN = "2"  !CDS_PN = "2";
BODY = "Q_CAP","I84": #LOCATION = "C2541" !CDS_LOCATION = "C2541" &SEC = "1" #&CDS_SEC = "1";
"A":   PN = "1"  !CDS_PN = "1";
"B":   PN = "2"  !CDS_PN = "2";
BODY = "Q_CAP","I85": #LOCATION = "C2548" !CDS_LOCATION = "C2548" &SEC = "1" #&CDS_SEC = "1";
"A":   PN = "1"  !CDS_PN = "1";
"B":   PN = "2"  !CDS_PN = "2";
BODY = "Q_CAP","I86": #LOCATION = "C2555" !CDS_LOCATION = "C2555" &SEC = "1" #&CDS_SEC = "1";
"A":   PN = "1"  !CDS_PN = "1";
"B":   PN = "2"  !CDS_PN = "2";
BODY = "Q_CAP","I87": #LOCATION = "C2564" !CDS_LOCATION = "C2564" &SEC = "1" #&CDS_SEC = "1";
"A":   PN = "1"  !CDS_PN = "1";
"B":   PN = "2"  !CDS_PN = "2";
BODY = "Q_CAP","I88": #LOCATION = "C2563" !CDS_LOCATION = "C2563" &SEC = "1" #&CDS_SEC = "1";
"A":   PN = "1"  !CDS_PN = "1";
"B":   PN = "2"  !CDS_PN = "2";
BODY = "Q_CAP","I89": #LOCATION = "C2571" !CDS_LOCATION = "C2571" &SEC = "1" #&CDS_SEC = "1";
"A":   PN = "1"  !CDS_PN = "1";
"B":   PN = "2"  !CDS_PN = "2";
BODY = "Q_CAP","I90": #LOCATION = "C2570" !CDS_LOCATION = "C2570" &SEC = "1" #&CDS_SEC = "1";
"A":   PN = "1"  !CDS_PN = "1";
"B":   PN = "2"  !CDS_PN = "2";
BODY = "Q_CAP","I91": #LOCATION = "C2562" !CDS_LOCATION = "C2562" &SEC = "1" #&CDS_SEC = "1";
"A":   PN = "1"  !CDS_PN = "1";
"B":   PN = "2"  !CDS_PN = "2";
BODY = "Q_CAP","I92": #LOCATION = "C2569" !CDS_LOCATION = "C2569" &SEC = "1" #&CDS_SEC = "1";
"A":   PN = "1"  !CDS_PN = "1";
"B":   PN = "2"  !CDS_PN = "2";
BODY = "Q_CAP","I93": #LOCATION = "C2578" !CDS_LOCATION = "C2578" &SEC = "1" #&CDS_SEC = "1";
"A":   PN = "1"  !CDS_PN = "1";
"B":   PN = "2"  !CDS_PN = "2";
BODY = "Q_CAP","I94": #LOCATION = "C2577" !CDS_LOCATION = "C2577" &SEC = "1" #&CDS_SEC = "1";
"A":   PN = "1"  !CDS_PN = "1";
"B":   PN = "2"  !CDS_PN = "2";
BODY = "Q_CAP","I95": #LOCATION = "C2585" !CDS_LOCATION = "C2585" &SEC = "1" #&CDS_SEC = "1";
"A":   PN = "1"  !CDS_PN = "1";
"B":   PN = "2"  !CDS_PN = "2";
BODY = "Q_CAP","I96": #LOCATION = "C2584" !CDS_LOCATION = "C2584" &SEC = "1" #&CDS_SEC = "1";
"A":   PN = "1"  !CDS_PN = "1";
"B":   PN = "2"  !CDS_PN = "2";
BODY = "Q_CAP","I97": #LOCATION = "C2576" !CDS_LOCATION = "C2576" &SEC = "1" #&CDS_SEC = "1";
"A":   PN = "1"  !CDS_PN = "1";
"B":   PN = "2"  !CDS_PN = "2";
BODY = "Q_CAP","I98": #LOCATION = "C2583" !CDS_LOCATION = "C2583" &SEC = "1" #&CDS_SEC = "1";
"A":   PN = "1"  !CDS_PN = "1";
"B":   PN = "2"  !CDS_PN = "2";
BODY = "Q_CAP","I99": #LOCATION = "C2592" !CDS_LOCATION = "C2592" &SEC = "1" #&CDS_SEC = "1";
"A":   PN = "1"  !CDS_PN = "1";
"B":   PN = "2"  !CDS_PN = "2";
BODY = "Q_CAP","I101": #LOCATION = "C2591" !CDS_LOCATION = "C2591" &SEC = "1" #&CDS_SEC = "1";
"A":   PN = "1"  !CDS_PN = "1";
"B":   PN = "2"  !CDS_PN = "2";
BODY = "Q_CAP","I102": #LOCATION = "C2599" !CDS_LOCATION = "C2599" &SEC = "1" #&CDS_SEC = "1";
"A":   PN = "1"  !CDS_PN = "1";
"B":   PN = "2"  !CDS_PN = "2";
BODY = "Q_CAP","I104": #LOCATION = "C2598" !CDS_LOCATION = "C2598" &SEC = "1" #&CDS_SEC = "1";
"A":   PN = "1"  !CDS_PN = "1";
"B":   PN = "2"  !CDS_PN = "2";
BODY = "Q_CAP","I106": #LOCATION = "C2590" !CDS_LOCATION = "C2590" &SEC = "1" #&CDS_SEC = "1";
"A":   PN = "1"  !CDS_PN = "1";
"B":   PN = "2"  !CDS_PN = "2";
BODY = "Q_CAP","I108": #LOCATION = "C2597" !CDS_LOCATION = "C2597" &SEC = "1" #&CDS_SEC = "1";
"A":   PN = "1"  !CDS_PN = "1";
"B":   PN = "2"  !CDS_PN = "2";
BODY = "Q_CAP","I111": #LOCATION = "C3933" !CDS_LOCATION = "C3933" &SEC = "1" #&CDS_SEC = "1";
"A":   PN = "1"  !CDS_PN = "1";
"B":   PN = "2"  !CDS_PN = "2";
BODY = "Q_CAP","I112": #LOCATION = "C2610" !CDS_LOCATION = "C2610" &SEC = "1" #&CDS_SEC = "1";
"A":   PN = "1"  !CDS_PN = "1";
"B":   PN = "2"  !CDS_PN = "2";
BODY = "Q_CAP","I113": #LOCATION = "C2609" !CDS_LOCATION = "C2609" &SEC = "1" #&CDS_SEC = "1";
"A":   PN = "1"  !CDS_PN = "1";
"B":   PN = "2"  !CDS_PN = "2";
BODY = "Q_CAP","I114": #LOCATION = "C2617" !CDS_LOCATION = "C2617" &SEC = "1" #&CDS_SEC = "1";
"A":   PN = "1"  !CDS_PN = "1";
"B":   PN = "2"  !CDS_PN = "2";
BODY = "Q_CAP","I115": #LOCATION = "C2616" !CDS_LOCATION = "C2616" &SEC = "1" #&CDS_SEC = "1";
"A":   PN = "1"  !CDS_PN = "1";
"B":   PN = "2"  !CDS_PN = "2";
BODY = "Q_CAP","I116": #LOCATION = "C2624" !CDS_LOCATION = "C2624" &SEC = "1" #&CDS_SEC = "1";
"A":   PN = "1"  !CDS_PN = "1";
"B":   PN = "2"  !CDS_PN = "2";
BODY = "Q_CAP","I117": #LOCATION = "C2623" !CDS_LOCATION = "C2623" &SEC = "1" #&CDS_SEC = "1";
"A":   PN = "1"  !CDS_PN = "1";
"B":   PN = "2"  !CDS_PN = "2";
BODY = "Q_CAP","I118": #LOCATION = "C2630" !CDS_LOCATION = "C2630" &SEC = "1" #&CDS_SEC = "1";
"A":   PN = "1"  !CDS_PN = "1";
"B":   PN = "2"  !CDS_PN = "2";
BODY = "Q_CAP","I119": #LOCATION = "C2629" !CDS_LOCATION = "C2629" &SEC = "1" #&CDS_SEC = "1";
"A":   PN = "1"  !CDS_PN = "1";
"B":   PN = "2"  !CDS_PN = "2";
BODY = "Q_CAP","I120": #LOCATION = "C2636" !CDS_LOCATION = "C2636" &SEC = "1" #&CDS_SEC = "1";
"A":   PN = "1"  !CDS_PN = "1";
"B":   PN = "2"  !CDS_PN = "2";
BODY = "Q_CAP","I121": #LOCATION = "C2635" !CDS_LOCATION = "C2635" &SEC = "1" #&CDS_SEC = "1";
"A":   PN = "1"  !CDS_PN = "1";
"B":   PN = "2"  !CDS_PN = "2";
BODY = "Q_CAP","I122": #LOCATION = "C2608" !CDS_LOCATION = "C2608" &SEC = "1" #&CDS_SEC = "1";
"A":   PN = "1"  !CDS_PN = "1";
"B":   PN = "2"  !CDS_PN = "2";
BODY = "Q_CAP","I123": #LOCATION = "C2615" !CDS_LOCATION = "C2615" &SEC = "1" #&CDS_SEC = "1";
"A":   PN = "1"  !CDS_PN = "1";
"B":   PN = "2"  !CDS_PN = "2";
BODY = "Q_CAP","I124": #LOCATION = "C2607" !CDS_LOCATION = "C2607" &SEC = "1" #&CDS_SEC = "1";
"A":   PN = "1"  !CDS_PN = "1";
"B":   PN = "2"  !CDS_PN = "2";
BODY = "Q_CAP","I125": #LOCATION = "C2614" !CDS_LOCATION = "C2614" &SEC = "1" #&CDS_SEC = "1";
"A":   PN = "1"  !CDS_PN = "1";
"B":   PN = "2"  !CDS_PN = "2";
BODY = "Q_CAP","I126": #LOCATION = "C2622" !CDS_LOCATION = "C2622" &SEC = "1" #&CDS_SEC = "1";
"A":   PN = "1"  !CDS_PN = "1";
"B":   PN = "2"  !CDS_PN = "2";
BODY = "Q_CAP","I127": #LOCATION = "C2621" !CDS_LOCATION = "C2621" &SEC = "1" #&CDS_SEC = "1";
"A":   PN = "1"  !CDS_PN = "1";
"B":   PN = "2"  !CDS_PN = "2";
BODY = "Q_CAP","I129": #LOCATION = "C2628" !CDS_LOCATION = "C2628" &SEC = "1" #&CDS_SEC = "1";
"A":   PN = "1"  !CDS_PN = "1";
"B":   PN = "2"  !CDS_PN = "2";
BODY = "Q_CAP","I130": #LOCATION = "C2634" !CDS_LOCATION = "C2634" &SEC = "1" #&CDS_SEC = "1";
"A":   PN = "1"  !CDS_PN = "1";
"B":   PN = "2"  !CDS_PN = "2";
BODY = "Q_CAP","I131": #LOCATION = "C2627" !CDS_LOCATION = "C2627" &SEC = "1" #&CDS_SEC = "1";
"A":   PN = "1"  !CDS_PN = "1";
"B":   PN = "2"  !CDS_PN = "2";
BODY = "Q_CAP","I132": #LOCATION = "C2633" !CDS_LOCATION = "C2633" &SEC = "1" #&CDS_SEC = "1";
"A":   PN = "1"  !CDS_PN = "1";
"B":   PN = "2"  !CDS_PN = "2";
BODY = "Q_CAP","I133": #LOCATION = "C2642" !CDS_LOCATION = "C2642" &SEC = "1" #&CDS_SEC = "1";
"A":   PN = "1"  !CDS_PN = "1";
"B":   PN = "2"  !CDS_PN = "2";
BODY = "Q_CAP","I134": #LOCATION = "C2641" !CDS_LOCATION = "C2641" &SEC = "1" #&CDS_SEC = "1";
"A":   PN = "1"  !CDS_PN = "1";
"B":   PN = "2"  !CDS_PN = "2";
BODY = "Q_CAP","I135": #LOCATION = "C2648" !CDS_LOCATION = "C2648" &SEC = "1" #&CDS_SEC = "1";
"A":   PN = "1"  !CDS_PN = "1";
"B":   PN = "2"  !CDS_PN = "2";
BODY = "Q_CAP","I136": #LOCATION = "C2647" !CDS_LOCATION = "C2647" &SEC = "1" #&CDS_SEC = "1";
"A":   PN = "1"  !CDS_PN = "1";
"B":   PN = "2"  !CDS_PN = "2";
BODY = "Q_CAP","I138": #LOCATION = "C3934" !CDS_LOCATION = "C3934" &SEC = "1" #&CDS_SEC = "1";
"A":   PN = "1"  !CDS_PN = "1";
"B":   PN = "2"  !CDS_PN = "2";
BODY = "Q_CAP","I139": #LOCATION = "C2653" !CDS_LOCATION = "C2653" &SEC = "1" #&CDS_SEC = "1";
"A":   PN = "1"  !CDS_PN = "1";
"B":   PN = "2"  !CDS_PN = "2";
BODY = "Q_CAP","I140": #LOCATION = "C3935" !CDS_LOCATION = "C3935" &SEC = "1" #&CDS_SEC = "1";
"A":   PN = "1"  !CDS_PN = "1";
"B":   PN = "2"  !CDS_PN = "2";
BODY = "Q_CAP","I142": #LOCATION = "C2658" !CDS_LOCATION = "C2658" &SEC = "1" #&CDS_SEC = "1";
"A":   PN = "1"  !CDS_PN = "1";
"B":   PN = "2"  !CDS_PN = "2";
BODY = "Q_CAP","I143": #LOCATION = "C2640" !CDS_LOCATION = "C2640" &SEC = "1" #&CDS_SEC = "1";
"A":   PN = "1"  !CDS_PN = "1";
"B":   PN = "2"  !CDS_PN = "2";
BODY = "Q_CAP","I144": #LOCATION = "C2646" !CDS_LOCATION = "C2646" &SEC = "1" #&CDS_SEC = "1";
"A":   PN = "1"  !CDS_PN = "1";
"B":   PN = "2"  !CDS_PN = "2";
BODY = "Q_CAP","I145": #LOCATION = "C2639" !CDS_LOCATION = "C2639" &SEC = "1" #&CDS_SEC = "1";
"A":   PN = "1"  !CDS_PN = "1";
"B":   PN = "2"  !CDS_PN = "2";
BODY = "Q_CAP","I146": #LOCATION = "C2645" !CDS_LOCATION = "C2645" &SEC = "1" #&CDS_SEC = "1";
"A":   PN = "1"  !CDS_PN = "1";
"B":   PN = "2"  !CDS_PN = "2";
BODY = "Q_CAP","I147": #LOCATION = "C2652" !CDS_LOCATION = "C2652" &SEC = "1" #&CDS_SEC = "1";
"A":   PN = "1"  !CDS_PN = "1";
"B":   PN = "2"  !CDS_PN = "2";
BODY = "Q_CAP","I149": #LOCATION = "C2657" !CDS_LOCATION = "C2657" &SEC = "1" #&CDS_SEC = "1";
"A":   PN = "1"  !CDS_PN = "1";
"B":   PN = "2"  !CDS_PN = "2";
BODY = "Q_CAP","I151": #LOCATION = "C2651" !CDS_LOCATION = "C2651" &SEC = "1" #&CDS_SEC = "1";
"A":   PN = "1"  !CDS_PN = "1";
"B":   PN = "2"  !CDS_PN = "2";
BODY = "Q_CAP","I152": #LOCATION = "C2656" !CDS_LOCATION = "C2656" &SEC = "1" #&CDS_SEC = "1";
"A":   PN = "1"  !CDS_PN = "1";
"B":   PN = "2"  !CDS_PN = "2";
BODY = "Q_CAP","I153": #LOCATION = "C2606" !CDS_LOCATION = "C2606" &SEC = "1" #&CDS_SEC = "1";
"A":   PN = "1"  !CDS_PN = "1";
"B":   PN = "2"  !CDS_PN = "2";
BODY = "Q_CAP","I154": #LOCATION = "C2605" !CDS_LOCATION = "C2605" &SEC = "1" #&CDS_SEC = "1";
"A":   PN = "1"  !CDS_PN = "1";
"B":   PN = "2"  !CDS_PN = "2";
BODY = "Q_CAP","I155": #LOCATION = "C2613" !CDS_LOCATION = "C2613" &SEC = "1" #&CDS_SEC = "1";
"A":   PN = "1"  !CDS_PN = "1";
"B":   PN = "2"  !CDS_PN = "2";
BODY = "Q_CAP","I156": #LOCATION = "C2612" !CDS_LOCATION = "C2612" &SEC = "1" #&CDS_SEC = "1";
"A":   PN = "1"  !CDS_PN = "1";
"B":   PN = "2"  !CDS_PN = "2";
BODY = "Q_CAP","I157": #LOCATION = "C2619" !CDS_LOCATION = "C2619" &SEC = "1" #&CDS_SEC = "1";
"A":   PN = "1"  !CDS_PN = "1";
"B":   PN = "2"  !CDS_PN = "2";
BODY = "Q_CAP","I158": #LOCATION = "C2604" !CDS_LOCATION = "C2604" &SEC = "1" #&CDS_SEC = "1";
"A":   PN = "1"  !CDS_PN = "1";
"B":   PN = "2"  !CDS_PN = "2";
BODY = "Q_CAP","I159": #LOCATION = "C2611" !CDS_LOCATION = "C2611" &SEC = "1" #&CDS_SEC = "1";
"A":   PN = "1"  !CDS_PN = "1";
"B":   PN = "2"  !CDS_PN = "2";
BODY = "Q_CAP","I160": #LOCATION = "C2618" !CDS_LOCATION = "C2618" &SEC = "1" #&CDS_SEC = "1";
"A":   PN = "1"  !CDS_PN = "1";
"B":   PN = "2"  !CDS_PN = "2";
BODY = "Q_CAP","I161": #LOCATION = "C2620" !CDS_LOCATION = "C2620" &SEC = "1" #&CDS_SEC = "1";
"A":   PN = "1"  !CDS_PN = "1";
"B":   PN = "2"  !CDS_PN = "2";
BODY = "Q_CAP","I162": #LOCATION = "C2626" !CDS_LOCATION = "C2626" &SEC = "1" #&CDS_SEC = "1";
"A":   PN = "1"  !CDS_PN = "1";
"B":   PN = "2"  !CDS_PN = "2";
BODY = "Q_CAP","I163": #LOCATION = "C2632" !CDS_LOCATION = "C2632" &SEC = "1" #&CDS_SEC = "1";
"A":   PN = "1"  !CDS_PN = "1";
"B":   PN = "2"  !CDS_PN = "2";
BODY = "Q_CAP","I164": #LOCATION = "C2625" !CDS_LOCATION = "C2625" &SEC = "1" #&CDS_SEC = "1";
"A":   PN = "1"  !CDS_PN = "1";
"B":   PN = "2"  !CDS_PN = "2";
BODY = "Q_CAP","I165": #LOCATION = "C2631" !CDS_LOCATION = "C2631" &SEC = "1" #&CDS_SEC = "1";
"A":   PN = "1"  !CDS_PN = "1";
"B":   PN = "2"  !CDS_PN = "2";
BODY = "Q_CAP","I166": #LOCATION = "C2638" !CDS_LOCATION = "C2638" &SEC = "1" #&CDS_SEC = "1";
"A":   PN = "1"  !CDS_PN = "1";
"B":   PN = "2"  !CDS_PN = "2";
BODY = "Q_CAP","I167": #LOCATION = "C2644" !CDS_LOCATION = "C2644" &SEC = "1" #&CDS_SEC = "1";
"A":   PN = "1"  !CDS_PN = "1";
"B":   PN = "2"  !CDS_PN = "2";
BODY = "Q_CAP","I168": #LOCATION = "C2637" !CDS_LOCATION = "C2637" &SEC = "1" #&CDS_SEC = "1";
"A":   PN = "1"  !CDS_PN = "1";
"B":   PN = "2"  !CDS_PN = "2";
BODY = "Q_CAP","I169": #LOCATION = "C2643" !CDS_LOCATION = "C2643" &SEC = "1" #&CDS_SEC = "1";
"A":   PN = "1"  !CDS_PN = "1";
"B":   PN = "2"  !CDS_PN = "2";
BODY = "Q_CAP","I170": #LOCATION = "C2650" !CDS_LOCATION = "C2650" &SEC = "1" #&CDS_SEC = "1";
"A":   PN = "1"  !CDS_PN = "1";
"B":   PN = "2"  !CDS_PN = "2";
BODY = "Q_CAP","I172": #LOCATION = "C2655" !CDS_LOCATION = "C2655" &SEC = "1" #&CDS_SEC = "1";
"A":   PN = "1"  !CDS_PN = "1";
"B":   PN = "2"  !CDS_PN = "2";
BODY = "Q_CAP","I173": #LOCATION = "C2649" !CDS_LOCATION = "C2649" &SEC = "1" #&CDS_SEC = "1";
"A":   PN = "1"  !CDS_PN = "1";
"B":   PN = "2"  !CDS_PN = "2";
BODY = "Q_CAP","I175": #LOCATION = "C2654" !CDS_LOCATION = "C2654" &SEC = "1" #&CDS_SEC = "1";
"A":   PN = "1"  !CDS_PN = "1";
"B":   PN = "2"  !CDS_PN = "2";
DRAWING = "@t6g_mb_lib.t6g(sch_1):page70";
BODY = "Q_CAP","I1": #LOCATION = "C2514" !CDS_LOCATION = "C2514" &SEC = "1" #&CDS_SEC = "1";
"A":   PN = "1"  !CDS_PN = "1";
"B":   PN = "2"  !CDS_PN = "2";
BODY = "Q_CAP","I3": #LOCATION = "C2513" !CDS_LOCATION = "C2513" &SEC = "1" #&CDS_SEC = "1";
"A":   PN = "1"  !CDS_PN = "1";
"B":   PN = "2"  !CDS_PN = "2";
BODY = "Q_CAP","I8": #LOCATION = "C2517" !CDS_LOCATION = "C2517" &SEC = "1" #&CDS_SEC = "1";
"A":   PN = "1"  !CDS_PN = "1";
"B":   PN = "2"  !CDS_PN = "2";
BODY = "Q_CAP","I9": #LOCATION = "C2516" !CDS_LOCATION = "C2516" &SEC = "1" #&CDS_SEC = "1";
"A":   PN = "1"  !CDS_PN = "1";
"B":   PN = "2"  !CDS_PN = "2";
BODY = "Q_CAP","I10": #LOCATION = "C2518" !CDS_LOCATION = "C2518" &SEC = "1" #&CDS_SEC = "1";
"A":   PN = "1"  !CDS_PN = "1";
"B":   PN = "2"  !CDS_PN = "2";
BODY = "Q_CAP","I11": #LOCATION = "C2520" !CDS_LOCATION = "C2520" &SEC = "1" #&CDS_SEC = "1";
"A":   PN = "1"  !CDS_PN = "1";
"B":   PN = "2"  !CDS_PN = "2";
BODY = "Q_CAP","I12": #LOCATION = "C2521" !CDS_LOCATION = "C2521" &SEC = "1" #&CDS_SEC = "1";
"A":   PN = "1"  !CDS_PN = "1";
"B":   PN = "2"  !CDS_PN = "2";
BODY = "Q_CAP","I13": #LOCATION = "C2522" !CDS_LOCATION = "C2522" &SEC = "1" #&CDS_SEC = "1";
"A":   PN = "1"  !CDS_PN = "1";
"B":   PN = "2"  !CDS_PN = "2";
BODY = "Q_CAP","I14": #LOCATION = "C2523" !CDS_LOCATION = "C2523" &SEC = "1" #&CDS_SEC = "1";
"A":   PN = "1"  !CDS_PN = "1";
"B":   PN = "2"  !CDS_PN = "2";
BODY = "Q_CAP","I15": #LOCATION = "C2524" !CDS_LOCATION = "C2524" &SEC = "1" #&CDS_SEC = "1";
"A":   PN = "1"  !CDS_PN = "1";
"B":   PN = "2"  !CDS_PN = "2";
BODY = "Q_CAP","I16": #LOCATION = "C2525" !CDS_LOCATION = "C2525" &SEC = "1" #&CDS_SEC = "1";
"A":   PN = "1"  !CDS_PN = "1";
"B":   PN = "2"  !CDS_PN = "2";
BODY = "Q_CAP","I18": #LOCATION = "C2526" !CDS_LOCATION = "C2526" &SEC = "1" #&CDS_SEC = "1";
"A":   PN = "1"  !CDS_PN = "1";
"B":   PN = "2"  !CDS_PN = "2";
BODY = "Q_CAP","I25": #LOCATION = "C2515" !CDS_LOCATION = "C2515" &SEC = "1" #&CDS_SEC = "1";
"A":   PN = "1"  !CDS_PN = "1";
"B":   PN = "2"  !CDS_PN = "2";
BODY = "Q_CAP","I26": #LOCATION = "C2512" !CDS_LOCATION = "C2512" &SEC = "1" #&CDS_SEC = "1";
"A":   PN = "1"  !CDS_PN = "1";
"B":   PN = "2"  !CDS_PN = "2";
DRAWING = "@t6g_mb_lib.t6g(sch_1):page71";
BODY = "Q_CAP","I1": #LOCATION = "C2262" !CDS_LOCATION = "C2262" &SEC = "1" #&CDS_SEC = "1";
"A":   PN = "1"  !CDS_PN = "1";
"B":   PN = "2"  !CDS_PN = "2";
BODY = "Q_CAP","I3": #LOCATION = "C2261" !CDS_LOCATION = "C2261" &SEC = "1" #&CDS_SEC = "1";
"A":   PN = "1"  !CDS_PN = "1";
"B":   PN = "2"  !CDS_PN = "2";
BODY = "Q_CAP","I5": #LOCATION = "C3900" !CDS_LOCATION = "C3900" &SEC = "1" #&CDS_SEC = "1";
"A":   PN = "1"  !CDS_PN = "1";
"B":   PN = "2"  !CDS_PN = "2";
BODY = "Q_CAP","I7": #LOCATION = "C2259" !CDS_LOCATION = "C2259" &SEC = "1" #&CDS_SEC = "1";
"A":   PN = "1"  !CDS_PN = "1";
"B":   PN = "2"  !CDS_PN = "2";
BODY = "Q_CAP","I9": #LOCATION = "C2258" !CDS_LOCATION = "C2258" &SEC = "1" #&CDS_SEC = "1";
"A":   PN = "1"  !CDS_PN = "1";
"B":   PN = "2"  !CDS_PN = "2";
BODY = "Q_CAP","I11": #LOCATION = "C2267" !CDS_LOCATION = "C2267" &SEC = "1" #&CDS_SEC = "1";
"A":   PN = "1"  !CDS_PN = "1";
"B":   PN = "2"  !CDS_PN = "2";
BODY = "Q_CAP","I12": #LOCATION = "C3902" !CDS_LOCATION = "C3902" &SEC = "1" #&CDS_SEC = "1";
"A":   PN = "1"  !CDS_PN = "1";
"B":   PN = "2"  !CDS_PN = "2";
BODY = "Q_CAP","I13": #LOCATION = "C2266" !CDS_LOCATION = "C2266" &SEC = "1" #&CDS_SEC = "1";
"A":   PN = "1"  !CDS_PN = "1";
"B":   PN = "2"  !CDS_PN = "2";
BODY = "Q_CAP","I14": #LOCATION = "C2271" !CDS_LOCATION = "C2271" &SEC = "1" #&CDS_SEC = "1";
"A":   PN = "1"  !CDS_PN = "1";
"B":   PN = "2"  !CDS_PN = "2";
BODY = "Q_CAP","I15": #LOCATION = "C3903" !CDS_LOCATION = "C3903" &SEC = "1" #&CDS_SEC = "1";
"A":   PN = "1"  !CDS_PN = "1";
"B":   PN = "2"  !CDS_PN = "2";
BODY = "Q_CAP","I16": #LOCATION = "C3904" !CDS_LOCATION = "C3904" &SEC = "1" #&CDS_SEC = "1";
"A":   PN = "1"  !CDS_PN = "1";
"B":   PN = "2"  !CDS_PN = "2";
BODY = "Q_CAP","I18": #LOCATION = "C3905" !CDS_LOCATION = "C3905" &SEC = "1" #&CDS_SEC = "1";
"A":   PN = "1"  !CDS_PN = "1";
"B":   PN = "2"  !CDS_PN = "2";
BODY = "Q_CAP","I19": #LOCATION = "C2275" !CDS_LOCATION = "C2275" &SEC = "1" #&CDS_SEC = "1";
"A":   PN = "1"  !CDS_PN = "1";
"B":   PN = "2"  !CDS_PN = "2";
BODY = "Q_CAP","I20": #LOCATION = "C2279" !CDS_LOCATION = "C2279" &SEC = "1" #&CDS_SEC = "1";
"A":   PN = "1"  !CDS_PN = "1";
"B":   PN = "2"  !CDS_PN = "2";
BODY = "Q_CAP","I21": #LOCATION = "C2282" !CDS_LOCATION = "C2282" &SEC = "1" #&CDS_SEC = "1";
"A":   PN = "1"  !CDS_PN = "1";
"B":   PN = "2"  !CDS_PN = "2";
BODY = "Q_CAP","I23": #LOCATION = "C3901" !CDS_LOCATION = "C3901" &SEC = "1" #&CDS_SEC = "1";
"A":   PN = "1"  !CDS_PN = "1";
"B":   PN = "2"  !CDS_PN = "2";
BODY = "Q_CAP","I24": #LOCATION = "C2285" !CDS_LOCATION = "C2285" &SEC = "1" #&CDS_SEC = "1";
"A":   PN = "1"  !CDS_PN = "1";
"B":   PN = "2"  !CDS_PN = "2";
BODY = "Q_CAP","I25": #LOCATION = "C2287" !CDS_LOCATION = "C2287" &SEC = "1" #&CDS_SEC = "1";
"A":   PN = "1"  !CDS_PN = "1";
"B":   PN = "2"  !CDS_PN = "2";
BODY = "Q_CAP","I26": #LOCATION = "C2289" !CDS_LOCATION = "C2289" &SEC = "1" #&CDS_SEC = "1";
"A":   PN = "1"  !CDS_PN = "1";
"B":   PN = "2"  !CDS_PN = "2";
BODY = "Q_CAP","I28": #LOCATION = "C2291" !CDS_LOCATION = "C2291" &SEC = "1" #&CDS_SEC = "1";
"A":   PN = "1"  !CDS_PN = "1";
"B":   PN = "2"  !CDS_PN = "2";
BODY = "Q_CAP","I30": #LOCATION = "C2264" !CDS_LOCATION = "C2264" &SEC = "1" #&CDS_SEC = "1";
"A":   PN = "1"  !CDS_PN = "1";
"B":   PN = "2"  !CDS_PN = "2";
BODY = "Q_CAP","I31": #LOCATION = "C2263" !CDS_LOCATION = "C2263" &SEC = "1" #&CDS_SEC = "1";
"A":   PN = "1"  !CDS_PN = "1";
"B":   PN = "2"  !CDS_PN = "2";
BODY = "Q_CAP","I32": #LOCATION = "C2269" !CDS_LOCATION = "C2269" &SEC = "1" #&CDS_SEC = "1";
"A":   PN = "1"  !CDS_PN = "1";
"B":   PN = "2"  !CDS_PN = "2";
BODY = "Q_CAP","I33": #LOCATION = "C2268" !CDS_LOCATION = "C2268" &SEC = "1" #&CDS_SEC = "1";
"A":   PN = "1"  !CDS_PN = "1";
"B":   PN = "2"  !CDS_PN = "2";
BODY = "Q_CAP","I34": #LOCATION = "C2272" !CDS_LOCATION = "C2272" &SEC = "1" #&CDS_SEC = "1";
"A":   PN = "1"  !CDS_PN = "1";
"B":   PN = "2"  !CDS_PN = "2";
BODY = "Q_CAP","I35": #LOCATION = "C2273" !CDS_LOCATION = "C2273" &SEC = "1" #&CDS_SEC = "1";
"A":   PN = "1"  !CDS_PN = "1";
"B":   PN = "2"  !CDS_PN = "2";
BODY = "Q_CAP","I36": #LOCATION = "C2277" !CDS_LOCATION = "C2277" &SEC = "1" #&CDS_SEC = "1";
"A":   PN = "1"  !CDS_PN = "1";
"B":   PN = "2"  !CDS_PN = "2";
BODY = "Q_CAP","I37": #LOCATION = "C2281" !CDS_LOCATION = "C2281" &SEC = "1" #&CDS_SEC = "1";
"A":   PN = "1"  !CDS_PN = "1";
"B":   PN = "2"  !CDS_PN = "2";
BODY = "Q_CAP","I38": #LOCATION = "C2280" !CDS_LOCATION = "C2280" &SEC = "1" #&CDS_SEC = "1";
"A":   PN = "1"  !CDS_PN = "1";
"B":   PN = "2"  !CDS_PN = "2";
BODY = "Q_CAP","I39": #LOCATION = "C2284" !CDS_LOCATION = "C2284" &SEC = "1" #&CDS_SEC = "1";
"A":   PN = "1"  !CDS_PN = "1";
"B":   PN = "2"  !CDS_PN = "2";
BODY = "Q_CAP","I40": #LOCATION = "C2283" !CDS_LOCATION = "C2283" &SEC = "1" #&CDS_SEC = "1";
"A":   PN = "1"  !CDS_PN = "1";
"B":   PN = "2"  !CDS_PN = "2";
BODY = "Q_CAP","I41": #LOCATION = "C3906" !CDS_LOCATION = "C3906" &SEC = "1" #&CDS_SEC = "1";
"A":   PN = "1"  !CDS_PN = "1";
"B":   PN = "2"  !CDS_PN = "2";
BODY = "Q_CAP","I42": #LOCATION = "C2286" !CDS_LOCATION = "C2286" &SEC = "1" #&CDS_SEC = "1";
"A":   PN = "1"  !CDS_PN = "1";
"B":   PN = "2"  !CDS_PN = "2";
BODY = "Q_CAP","I43": #LOCATION = "C3907" !CDS_LOCATION = "C3907" &SEC = "1" #&CDS_SEC = "1";
"A":   PN = "1"  !CDS_PN = "1";
"B":   PN = "2"  !CDS_PN = "2";
BODY = "Q_CAP","I44": #LOCATION = "C2288" !CDS_LOCATION = "C2288" &SEC = "1" #&CDS_SEC = "1";
"A":   PN = "1"  !CDS_PN = "1";
"B":   PN = "2"  !CDS_PN = "2";
BODY = "Q_CAP","I45": #LOCATION = "C3908" !CDS_LOCATION = "C3908" &SEC = "1" #&CDS_SEC = "1";
"A":   PN = "1"  !CDS_PN = "1";
"B":   PN = "2"  !CDS_PN = "2";
BODY = "Q_CAP","I47": #LOCATION = "C2290" !CDS_LOCATION = "C2290" &SEC = "1" #&CDS_SEC = "1";
"A":   PN = "1"  !CDS_PN = "1";
"B":   PN = "2"  !CDS_PN = "2";
BODY = "Q_CAP","I49": #LOCATION = "C2292" !CDS_LOCATION = "C2292" &SEC = "1" #&CDS_SEC = "1";
"A":   PN = "1"  !CDS_PN = "1";
"B":   PN = "2"  !CDS_PN = "2";
BODY = "Q_CAP","I50": #LOCATION = "C2293" !CDS_LOCATION = "C2293" &SEC = "1" #&CDS_SEC = "1";
"A":   PN = "1"  !CDS_PN = "1";
"B":   PN = "2"  !CDS_PN = "2";
BODY = "Q_CAP","I52": #LOCATION = "C3909" !CDS_LOCATION = "C3909" &SEC = "1" #&CDS_SEC = "1";
"A":   PN = "1"  !CDS_PN = "1";
"B":   PN = "2"  !CDS_PN = "2";
BODY = "Q_CAP","I53": #LOCATION = "C2260" !CDS_LOCATION = "C2260" &SEC = "1" #&CDS_SEC = "1";
"A":   PN = "1"  !CDS_PN = "1";
"B":   PN = "2"  !CDS_PN = "2";
BODY = "Q_CAP","I54": #LOCATION = "C2265" !CDS_LOCATION = "C2265" &SEC = "1" #&CDS_SEC = "1";
"A":   PN = "1"  !CDS_PN = "1";
"B":   PN = "2"  !CDS_PN = "2";
BODY = "Q_CAP","I56": #LOCATION = "C2270" !CDS_LOCATION = "C2270" &SEC = "1" #&CDS_SEC = "1";
"A":   PN = "1"  !CDS_PN = "1";
"B":   PN = "2"  !CDS_PN = "2";
BODY = "Q_CAP","I57": #LOCATION = "C2274" !CDS_LOCATION = "C2274" &SEC = "1" #&CDS_SEC = "1";
"A":   PN = "1"  !CDS_PN = "1";
"B":   PN = "2"  !CDS_PN = "2";
BODY = "Q_CAP","I58": #LOCATION = "C2278" !CDS_LOCATION = "C2278" &SEC = "1" #&CDS_SEC = "1";
"A":   PN = "1"  !CDS_PN = "1";
"B":   PN = "2"  !CDS_PN = "2";
BODY = "Q_CAP","I59": #LOCATION = "C3910" !CDS_LOCATION = "C3910" &SEC = "1" #&CDS_SEC = "1";
"A":   PN = "1"  !CDS_PN = "1";
"B":   PN = "2"  !CDS_PN = "2";
BODY = "Q_CAP","I61": #LOCATION = "C3911" !CDS_LOCATION = "C3911" &SEC = "1" #&CDS_SEC = "1";
"A":   PN = "1"  !CDS_PN = "1";
"B":   PN = "2"  !CDS_PN = "2";
BODY = "Q_CAP","I62": #LOCATION = "C2276" !CDS_LOCATION = "C2276" &SEC = "1" #&CDS_SEC = "1";
"A":   PN = "1"  !CDS_PN = "1";
"B":   PN = "2"  !CDS_PN = "2";
DRAWING = "@t6g_mb_lib.t6g(sch_1):page72";
BODY = "Q_CAP","I1": #LOCATION = "C2298" !CDS_LOCATION = "C2298" &SEC = "1" #&CDS_SEC = "1";
"A":   PN = "1"  !CDS_PN = "1";
"B":   PN = "2"  !CDS_PN = "2";
BODY = "Q_CAP","I3": #LOCATION = "C2304" !CDS_LOCATION = "C2304" &SEC = "1" #&CDS_SEC = "1";
"A":   PN = "1"  !CDS_PN = "1";
"B":   PN = "2"  !CDS_PN = "2";
BODY = "Q_CAP","I4": #LOCATION = "C2310" !CDS_LOCATION = "C2310" &SEC = "1" #&CDS_SEC = "1";
"A":   PN = "1"  !CDS_PN = "1";
"B":   PN = "2"  !CDS_PN = "2";
BODY = "Q_CAP","I5": #LOCATION = "C2297" !CDS_LOCATION = "C2297" &SEC = "1" #&CDS_SEC = "1";
"A":   PN = "1"  !CDS_PN = "1";
"B":   PN = "2"  !CDS_PN = "2";
BODY = "Q_CAP","I7": #LOCATION = "C2296" !CDS_LOCATION = "C2296" &SEC = "1" #&CDS_SEC = "1";
"A":   PN = "1"  !CDS_PN = "1";
"B":   PN = "2"  !CDS_PN = "2";
BODY = "Q_CAP","I9": #LOCATION = "C2295" !CDS_LOCATION = "C2295" &SEC = "1" #&CDS_SEC = "1";
"A":   PN = "1"  !CDS_PN = "1";
"B":   PN = "2"  !CDS_PN = "2";
BODY = "Q_CAP","I10": #LOCATION = "C2303" !CDS_LOCATION = "C2303" &SEC = "1" #&CDS_SEC = "1";
"A":   PN = "1"  !CDS_PN = "1";
"B":   PN = "2"  !CDS_PN = "2";
BODY = "Q_CAP","I11": #LOCATION = "C2309" !CDS_LOCATION = "C2309" &SEC = "1" #&CDS_SEC = "1";
"A":   PN = "1"  !CDS_PN = "1";
"B":   PN = "2"  !CDS_PN = "2";
BODY = "Q_CAP","I12": #LOCATION = "C2302" !CDS_LOCATION = "C2302" &SEC = "1" #&CDS_SEC = "1";
"A":   PN = "1"  !CDS_PN = "1";
"B":   PN = "2"  !CDS_PN = "2";
BODY = "Q_CAP","I13": #LOCATION = "C2301" !CDS_LOCATION = "C2301" &SEC = "1" #&CDS_SEC = "1";
"A":   PN = "1"  !CDS_PN = "1";
"B":   PN = "2"  !CDS_PN = "2";
BODY = "Q_CAP","I14": #LOCATION = "C2308" !CDS_LOCATION = "C2308" &SEC = "1" #&CDS_SEC = "1";
"A":   PN = "1"  !CDS_PN = "1";
"B":   PN = "2"  !CDS_PN = "2";
BODY = "Q_CAP","I15": #LOCATION = "C2307" !CDS_LOCATION = "C2307" &SEC = "1" #&CDS_SEC = "1";
"A":   PN = "1"  !CDS_PN = "1";
"B":   PN = "2"  !CDS_PN = "2";
BODY = "Q_CAP","I17": #LOCATION = "C2294" !CDS_LOCATION = "C2294" &SEC = "1" #&CDS_SEC = "1";
"A":   PN = "1"  !CDS_PN = "1";
"B":   PN = "2"  !CDS_PN = "2";
BODY = "Q_CAP","I19": #LOCATION = "C2300" !CDS_LOCATION = "C2300" &SEC = "1" #&CDS_SEC = "1";
"A":   PN = "1"  !CDS_PN = "1";
"B":   PN = "2"  !CDS_PN = "2";
BODY = "Q_CAP","I20": #LOCATION = "C2306" !CDS_LOCATION = "C2306" &SEC = "1" #&CDS_SEC = "1";
"A":   PN = "1"  !CDS_PN = "1";
"B":   PN = "2"  !CDS_PN = "2";
BODY = "Q_CAP","I21": #LOCATION = "C2316" !CDS_LOCATION = "C2316" &SEC = "1" #&CDS_SEC = "1";
"A":   PN = "1"  !CDS_PN = "1";
"B":   PN = "2"  !CDS_PN = "2";
BODY = "Q_CAP","I23": #LOCATION = "C2322" !CDS_LOCATION = "C2322" &SEC = "1" #&CDS_SEC = "1";
"A":   PN = "1"  !CDS_PN = "1";
"B":   PN = "2"  !CDS_PN = "2";
BODY = "Q_CAP","I24": #LOCATION = "C2315" !CDS_LOCATION = "C2315" &SEC = "1" #&CDS_SEC = "1";
"A":   PN = "1"  !CDS_PN = "1";
"B":   PN = "2"  !CDS_PN = "2";
BODY = "Q_CAP","I25": #LOCATION = "C2321" !CDS_LOCATION = "C2321" &SEC = "1" #&CDS_SEC = "1";
"A":   PN = "1"  !CDS_PN = "1";
"B":   PN = "2"  !CDS_PN = "2";
BODY = "Q_CAP","I26": #LOCATION = "C2327" !CDS_LOCATION = "C2327" &SEC = "1" #&CDS_SEC = "1";
"A":   PN = "1"  !CDS_PN = "1";
"B":   PN = "2"  !CDS_PN = "2";
BODY = "Q_CAP","I27": #LOCATION = "C2314" !CDS_LOCATION = "C2314" &SEC = "1" #&CDS_SEC = "1";
"A":   PN = "1"  !CDS_PN = "1";
"B":   PN = "2"  !CDS_PN = "2";
BODY = "Q_CAP","I28": #LOCATION = "C2313" !CDS_LOCATION = "C2313" &SEC = "1" #&CDS_SEC = "1";
"A":   PN = "1"  !CDS_PN = "1";
"B":   PN = "2"  !CDS_PN = "2";
BODY = "Q_CAP","I29": #LOCATION = "C2320" !CDS_LOCATION = "C2320" &SEC = "1" #&CDS_SEC = "1";
"A":   PN = "1"  !CDS_PN = "1";
"B":   PN = "2"  !CDS_PN = "2";
BODY = "Q_CAP","I30": #LOCATION = "C2326" !CDS_LOCATION = "C2326" &SEC = "1" #&CDS_SEC = "1";
"A":   PN = "1"  !CDS_PN = "1";
"B":   PN = "2"  !CDS_PN = "2";
BODY = "Q_CAP","I31": #LOCATION = "C2319" !CDS_LOCATION = "C2319" &SEC = "1" #&CDS_SEC = "1";
"A":   PN = "1"  !CDS_PN = "1";
"B":   PN = "2"  !CDS_PN = "2";
BODY = "Q_CAP","I32": #LOCATION = "C2325" !CDS_LOCATION = "C2325" &SEC = "1" #&CDS_SEC = "1";
"A":   PN = "1"  !CDS_PN = "1";
"B":   PN = "2"  !CDS_PN = "2";
BODY = "Q_CAP","I33": #LOCATION = "C2333" !CDS_LOCATION = "C2333" &SEC = "1" #&CDS_SEC = "1";
"A":   PN = "1"  !CDS_PN = "1";
"B":   PN = "2"  !CDS_PN = "2";
BODY = "Q_CAP","I34": #LOCATION = "C2338" !CDS_LOCATION = "C2338" &SEC = "1" #&CDS_SEC = "1";
"A":   PN = "1"  !CDS_PN = "1";
"B":   PN = "2"  !CDS_PN = "2";
BODY = "Q_CAP","I35": #LOCATION = "C2332" !CDS_LOCATION = "C2332" &SEC = "1" #&CDS_SEC = "1";
"A":   PN = "1"  !CDS_PN = "1";
"B":   PN = "2"  !CDS_PN = "2";
BODY = "Q_CAP","I36": #LOCATION = "C2331" !CDS_LOCATION = "C2331" &SEC = "1" #&CDS_SEC = "1";
"A":   PN = "1"  !CDS_PN = "1";
"B":   PN = "2"  !CDS_PN = "2";
BODY = "Q_CAP","I37": #LOCATION = "C2337" !CDS_LOCATION = "C2337" &SEC = "1" #&CDS_SEC = "1";
"A":   PN = "1"  !CDS_PN = "1";
"B":   PN = "2"  !CDS_PN = "2";
BODY = "Q_CAP","I38": #LOCATION = "C2336" !CDS_LOCATION = "C2336" &SEC = "1" #&CDS_SEC = "1";
"A":   PN = "1"  !CDS_PN = "1";
"B":   PN = "2"  !CDS_PN = "2";
BODY = "Q_CAP","I40": #LOCATION = "C2354" !CDS_LOCATION = "C2354" &SEC = "1" #&CDS_SEC = "1";
"A":   PN = "1"  !CDS_PN = "1";
"B":   PN = "2"  !CDS_PN = "2";
BODY = "Q_CAP","I41": #LOCATION = "C2360" !CDS_LOCATION = "C2360" &SEC = "1" #&CDS_SEC = "1";
"A":   PN = "1"  !CDS_PN = "1";
"B":   PN = "2"  !CDS_PN = "2";
BODY = "Q_CAP","I42": #LOCATION = "C2343" !CDS_LOCATION = "C2343" &SEC = "1" #&CDS_SEC = "1";
"A":   PN = "1"  !CDS_PN = "1";
"B":   PN = "2"  !CDS_PN = "2";
BODY = "Q_CAP","I44": #LOCATION = "C2348" !CDS_LOCATION = "C2348" &SEC = "1" #&CDS_SEC = "1";
"A":   PN = "1"  !CDS_PN = "1";
"B":   PN = "2"  !CDS_PN = "2";
BODY = "Q_CAP","I46": #LOCATION = "C2342" !CDS_LOCATION = "C2342" &SEC = "1" #&CDS_SEC = "1";
"A":   PN = "1"  !CDS_PN = "1";
"B":   PN = "2"  !CDS_PN = "2";
BODY = "Q_CAP","I47": #LOCATION = "C2341" !CDS_LOCATION = "C2341" &SEC = "1" #&CDS_SEC = "1";
"A":   PN = "1"  !CDS_PN = "1";
"B":   PN = "2"  !CDS_PN = "2";
BODY = "Q_CAP","I48": #LOCATION = "C2347" !CDS_LOCATION = "C2347" &SEC = "1" #&CDS_SEC = "1";
"A":   PN = "1"  !CDS_PN = "1";
"B":   PN = "2"  !CDS_PN = "2";
BODY = "Q_CAP","I50": #LOCATION = "C2346" !CDS_LOCATION = "C2346" &SEC = "1" #&CDS_SEC = "1";
"A":   PN = "1"  !CDS_PN = "1";
"B":   PN = "2"  !CDS_PN = "2";
BODY = "Q_CAP","I51": #LOCATION = "C2353" !CDS_LOCATION = "C2353" &SEC = "1" #&CDS_SEC = "1";
"A":   PN = "1"  !CDS_PN = "1";
"B":   PN = "2"  !CDS_PN = "2";
BODY = "Q_CAP","I53": #LOCATION = "C2359" !CDS_LOCATION = "C2359" &SEC = "1" #&CDS_SEC = "1";
"A":   PN = "1"  !CDS_PN = "1";
"B":   PN = "2"  !CDS_PN = "2";
BODY = "Q_CAP","I55": #LOCATION = "C2352" !CDS_LOCATION = "C2352" &SEC = "1" #&CDS_SEC = "1";
"A":   PN = "1"  !CDS_PN = "1";
"B":   PN = "2"  !CDS_PN = "2";
BODY = "Q_CAP","I56": #LOCATION = "C2351" !CDS_LOCATION = "C2351" &SEC = "1" #&CDS_SEC = "1";
"A":   PN = "1"  !CDS_PN = "1";
"B":   PN = "2"  !CDS_PN = "2";
BODY = "Q_CAP","I57": #LOCATION = "C2358" !CDS_LOCATION = "C2358" &SEC = "1" #&CDS_SEC = "1";
"A":   PN = "1"  !CDS_PN = "1";
"B":   PN = "2"  !CDS_PN = "2";
BODY = "Q_CAP","I58": #LOCATION = "C2357" !CDS_LOCATION = "C2357" &SEC = "1" #&CDS_SEC = "1";
"A":   PN = "1"  !CDS_PN = "1";
"B":   PN = "2"  !CDS_PN = "2";
BODY = "Q_CAP","I59": #LOCATION = "C2312" !CDS_LOCATION = "C2312" &SEC = "1" #&CDS_SEC = "1";
"A":   PN = "1"  !CDS_PN = "1";
"B":   PN = "2"  !CDS_PN = "2";
BODY = "Q_CAP","I60": #LOCATION = "C2318" !CDS_LOCATION = "C2318" &SEC = "1" #&CDS_SEC = "1";
"A":   PN = "1"  !CDS_PN = "1";
"B":   PN = "2"  !CDS_PN = "2";
BODY = "Q_CAP","I61": #LOCATION = "C2324" !CDS_LOCATION = "C2324" &SEC = "1" #&CDS_SEC = "1";
"A":   PN = "1"  !CDS_PN = "1";
"B":   PN = "2"  !CDS_PN = "2";
BODY = "Q_CAP","I62": #LOCATION = "C2330" !CDS_LOCATION = "C2330" &SEC = "1" #&CDS_SEC = "1";
"A":   PN = "1"  !CDS_PN = "1";
"B":   PN = "2"  !CDS_PN = "2";
BODY = "Q_CAP","I63": #LOCATION = "C2335" !CDS_LOCATION = "C2335" &SEC = "1" #&CDS_SEC = "1";
"A":   PN = "1"  !CDS_PN = "1";
"B":   PN = "2"  !CDS_PN = "2";
BODY = "Q_CAP","I64": #LOCATION = "C2340" !CDS_LOCATION = "C2340" &SEC = "1" #&CDS_SEC = "1";
"A":   PN = "1"  !CDS_PN = "1";
"B":   PN = "2"  !CDS_PN = "2";
BODY = "Q_CAP","I66": #LOCATION = "C2345" !CDS_LOCATION = "C2345" &SEC = "1" #&CDS_SEC = "1";
"A":   PN = "1"  !CDS_PN = "1";
"B":   PN = "2"  !CDS_PN = "2";
BODY = "Q_CAP","I68": #LOCATION = "C2356" !CDS_LOCATION = "C2356" &SEC = "1" #&CDS_SEC = "1";
"A":   PN = "1"  !CDS_PN = "1";
"B":   PN = "2"  !CDS_PN = "2";
BODY = "Q_CAP","I70": #LOCATION = "C2366" !CDS_LOCATION = "C2366" &SEC = "1" #&CDS_SEC = "1";
"A":   PN = "1"  !CDS_PN = "1";
"B":   PN = "2"  !CDS_PN = "2";
BODY = "Q_CAP","I71": #LOCATION = "C2372" !CDS_LOCATION = "C2372" &SEC = "1" #&CDS_SEC = "1";
"A":   PN = "1"  !CDS_PN = "1";
"B":   PN = "2"  !CDS_PN = "2";
BODY = "Q_CAP","I72": #LOCATION = "C2378" !CDS_LOCATION = "C2378" &SEC = "1" #&CDS_SEC = "1";
"A":   PN = "1"  !CDS_PN = "1";
"B":   PN = "2"  !CDS_PN = "2";
BODY = "Q_CAP","I74": #LOCATION = "C2365" !CDS_LOCATION = "C2365" &SEC = "1" #&CDS_SEC = "1";
"A":   PN = "1"  !CDS_PN = "1";
"B":   PN = "2"  !CDS_PN = "2";
BODY = "Q_CAP","I75": #LOCATION = "C2371" !CDS_LOCATION = "C2371" &SEC = "1" #&CDS_SEC = "1";
"A":   PN = "1"  !CDS_PN = "1";
"B":   PN = "2"  !CDS_PN = "2";
BODY = "Q_CAP","I76": #LOCATION = "C2364" !CDS_LOCATION = "C2364" &SEC = "1" #&CDS_SEC = "1";
"A":   PN = "1"  !CDS_PN = "1";
"B":   PN = "2"  !CDS_PN = "2";
BODY = "Q_CAP","I77": #LOCATION = "C2363" !CDS_LOCATION = "C2363" &SEC = "1" #&CDS_SEC = "1";
"A":   PN = "1"  !CDS_PN = "1";
"B":   PN = "2"  !CDS_PN = "2";
BODY = "Q_CAP","I78": #LOCATION = "C2370" !CDS_LOCATION = "C2370" &SEC = "1" #&CDS_SEC = "1";
"A":   PN = "1"  !CDS_PN = "1";
"B":   PN = "2"  !CDS_PN = "2";
BODY = "Q_CAP","I79": #LOCATION = "C2369" !CDS_LOCATION = "C2369" &SEC = "1" #&CDS_SEC = "1";
"A":   PN = "1"  !CDS_PN = "1";
"B":   PN = "2"  !CDS_PN = "2";
BODY = "Q_CAP","I80": #LOCATION = "C2376" !CDS_LOCATION = "C2376" &SEC = "1" #&CDS_SEC = "1";
"A":   PN = "1"  !CDS_PN = "1";
"B":   PN = "2"  !CDS_PN = "2";
BODY = "Q_CAP","I81": #LOCATION = "C2377" !CDS_LOCATION = "C2377" &SEC = "1" #&CDS_SEC = "1";
"A":   PN = "1"  !CDS_PN = "1";
"B":   PN = "2"  !CDS_PN = "2";
BODY = "Q_CAP","I82": #LOCATION = "C2383" !CDS_LOCATION = "C2383" &SEC = "1" #&CDS_SEC = "1";
"A":   PN = "1"  !CDS_PN = "1";
"B":   PN = "2"  !CDS_PN = "2";
BODY = "Q_CAP","I83": #LOCATION = "C2389" !CDS_LOCATION = "C2389" &SEC = "1" #&CDS_SEC = "1";
"A":   PN = "1"  !CDS_PN = "1";
"B":   PN = "2"  !CDS_PN = "2";
BODY = "Q_CAP","I84": #LOCATION = "C2382" !CDS_LOCATION = "C2382" &SEC = "1" #&CDS_SEC = "1";
"A":   PN = "1"  !CDS_PN = "1";
"B":   PN = "2"  !CDS_PN = "2";
BODY = "Q_CAP","I85": #LOCATION = "C2375" !CDS_LOCATION = "C2375" &SEC = "1" #&CDS_SEC = "1";
"A":   PN = "1"  !CDS_PN = "1";
"B":   PN = "2"  !CDS_PN = "2";
BODY = "Q_CAP","I86": #LOCATION = "C2381" !CDS_LOCATION = "C2381" &SEC = "1" #&CDS_SEC = "1";
"A":   PN = "1"  !CDS_PN = "1";
"B":   PN = "2"  !CDS_PN = "2";
BODY = "Q_CAP","I87": #LOCATION = "C2388" !CDS_LOCATION = "C2388" &SEC = "1" #&CDS_SEC = "1";
"A":   PN = "1"  !CDS_PN = "1";
"B":   PN = "2"  !CDS_PN = "2";
BODY = "Q_CAP","I88": #LOCATION = "C2387" !CDS_LOCATION = "C2387" &SEC = "1" #&CDS_SEC = "1";
"A":   PN = "1"  !CDS_PN = "1";
"B":   PN = "2"  !CDS_PN = "2";
BODY = "Q_CAP","I89": #LOCATION = "C2395" !CDS_LOCATION = "C2395" &SEC = "1" #&CDS_SEC = "1";
"A":   PN = "1"  !CDS_PN = "1";
"B":   PN = "2"  !CDS_PN = "2";
BODY = "Q_CAP","I90": #LOCATION = "C2400" !CDS_LOCATION = "C2400" &SEC = "1" #&CDS_SEC = "1";
"A":   PN = "1"  !CDS_PN = "1";
"B":   PN = "2"  !CDS_PN = "2";
BODY = "Q_CAP","I91": #LOCATION = "C2394" !CDS_LOCATION = "C2394" &SEC = "1" #&CDS_SEC = "1";
"A":   PN = "1"  !CDS_PN = "1";
"B":   PN = "2"  !CDS_PN = "2";
BODY = "Q_CAP","I92": #LOCATION = "C2393" !CDS_LOCATION = "C2393" &SEC = "1" #&CDS_SEC = "1";
"A":   PN = "1"  !CDS_PN = "1";
"B":   PN = "2"  !CDS_PN = "2";
BODY = "Q_CAP","I93": #LOCATION = "C2399" !CDS_LOCATION = "C2399" &SEC = "1" #&CDS_SEC = "1";
"A":   PN = "1"  !CDS_PN = "1";
"B":   PN = "2"  !CDS_PN = "2";
BODY = "Q_CAP","I94": #LOCATION = "C2398" !CDS_LOCATION = "C2398" &SEC = "1" #&CDS_SEC = "1";
"A":   PN = "1"  !CDS_PN = "1";
"B":   PN = "2"  !CDS_PN = "2";
BODY = "Q_CAP","I96": #LOCATION = "C2405" !CDS_LOCATION = "C2405" &SEC = "1" #&CDS_SEC = "1";
"A":   PN = "1"  !CDS_PN = "1";
"B":   PN = "2"  !CDS_PN = "2";
BODY = "Q_CAP","I98": #LOCATION = "C2404" !CDS_LOCATION = "C2404" &SEC = "1" #&CDS_SEC = "1";
"A":   PN = "1"  !CDS_PN = "1";
"B":   PN = "2"  !CDS_PN = "2";
BODY = "Q_CAP","I100": #LOCATION = "C2403" !CDS_LOCATION = "C2403" &SEC = "1" #&CDS_SEC = "1";
"A":   PN = "1"  !CDS_PN = "1";
"B":   PN = "2"  !CDS_PN = "2";
BODY = "Q_CAP","I101": #LOCATION = "C2362" !CDS_LOCATION = "C2362" &SEC = "1" #&CDS_SEC = "1";
"A":   PN = "1"  !CDS_PN = "1";
"B":   PN = "2"  !CDS_PN = "2";
BODY = "Q_CAP","I102": #LOCATION = "C2368" !CDS_LOCATION = "C2368" &SEC = "1" #&CDS_SEC = "1";
"A":   PN = "1"  !CDS_PN = "1";
"B":   PN = "2"  !CDS_PN = "2";
BODY = "Q_CAP","I103": #LOCATION = "C2374" !CDS_LOCATION = "C2374" &SEC = "1" #&CDS_SEC = "1";
"A":   PN = "1"  !CDS_PN = "1";
"B":   PN = "2"  !CDS_PN = "2";
BODY = "Q_CAP","I104": #LOCATION = "C2380" !CDS_LOCATION = "C2380" &SEC = "1" #&CDS_SEC = "1";
"A":   PN = "1"  !CDS_PN = "1";
"B":   PN = "2"  !CDS_PN = "2";
BODY = "Q_CAP","I105": #LOCATION = "C2386" !CDS_LOCATION = "C2386" &SEC = "1" #&CDS_SEC = "1";
"A":   PN = "1"  !CDS_PN = "1";
"B":   PN = "2"  !CDS_PN = "2";
BODY = "Q_CAP","I106": #LOCATION = "C2392" !CDS_LOCATION = "C2392" &SEC = "1" #&CDS_SEC = "1";
"A":   PN = "1"  !CDS_PN = "1";
"B":   PN = "2"  !CDS_PN = "2";
BODY = "Q_CAP","I107": #LOCATION = "C2397" !CDS_LOCATION = "C2397" &SEC = "1" #&CDS_SEC = "1";
"A":   PN = "1"  !CDS_PN = "1";
"B":   PN = "2"  !CDS_PN = "2";
BODY = "Q_CAP","I109": #LOCATION = "C2402" !CDS_LOCATION = "C2402" &SEC = "1" #&CDS_SEC = "1";
"A":   PN = "1"  !CDS_PN = "1";
"B":   PN = "2"  !CDS_PN = "2";
BODY = "Q_CAP","I110": #LOCATION = "C2350" !CDS_LOCATION = "C2350" &SEC = "1" #&CDS_SEC = "1";
"A":   PN = "1"  !CDS_PN = "1";
"B":   PN = "2"  !CDS_PN = "2";
DRAWING = "@t6g_mb_lib.t6g(sch_1):page73";
BODY = "Q_CAP","I1": #LOCATION = "C3912" !CDS_LOCATION = "C3912" &SEC = "1" #&CDS_SEC = "1";
"A":   PN = "1"  !CDS_PN = "1";
"B":   PN = "2"  !CDS_PN = "2";
BODY = "Q_CAP","I3": #LOCATION = "C2413" !CDS_LOCATION = "C2413" &SEC = "1" #&CDS_SEC = "1";
"A":   PN = "1"  !CDS_PN = "1";
"B":   PN = "2"  !CDS_PN = "2";
BODY = "Q_CAP","I4": #LOCATION = "C3913" !CDS_LOCATION = "C3913" &SEC = "1" #&CDS_SEC = "1";
"A":   PN = "1"  !CDS_PN = "1";
"B":   PN = "2"  !CDS_PN = "2";
BODY = "Q_CAP","I5": #LOCATION = "C2420" !CDS_LOCATION = "C2420" &SEC = "1" #&CDS_SEC = "1";
"A":   PN = "1"  !CDS_PN = "1";
"B":   PN = "2"  !CDS_PN = "2";
BODY = "Q_CAP","I6": #LOCATION = "C3914" !CDS_LOCATION = "C3914" &SEC = "1" #&CDS_SEC = "1";
"A":   PN = "1"  !CDS_PN = "1";
"B":   PN = "2"  !CDS_PN = "2";
BODY = "Q_CAP","I7": #LOCATION = "C2427" !CDS_LOCATION = "C2427" &SEC = "1" #&CDS_SEC = "1";
"A":   PN = "1"  !CDS_PN = "1";
"B":   PN = "2"  !CDS_PN = "2";
BODY = "Q_CAP","I8": #LOCATION = "C3915" !CDS_LOCATION = "C3915" &SEC = "1" #&CDS_SEC = "1";
"A":   PN = "1"  !CDS_PN = "1";
"B":   PN = "2"  !CDS_PN = "2";
BODY = "Q_CAP","I9": #LOCATION = "C2434" !CDS_LOCATION = "C2434" &SEC = "1" #&CDS_SEC = "1";
"A":   PN = "1"  !CDS_PN = "1";
"B":   PN = "2"  !CDS_PN = "2";
BODY = "Q_CAP","I11": #LOCATION = "C2412" !CDS_LOCATION = "C2412" &SEC = "1" #&CDS_SEC = "1";
"A":   PN = "1"  !CDS_PN = "1";
"B":   PN = "2"  !CDS_PN = "2";
BODY = "Q_CAP","I13": #LOCATION = "C2419" !CDS_LOCATION = "C2419" &SEC = "1" #&CDS_SEC = "1";
"A":   PN = "1"  !CDS_PN = "1";
"B":   PN = "2"  !CDS_PN = "2";
BODY = "Q_CAP","I14": #LOCATION = "C2411" !CDS_LOCATION = "C2411" &SEC = "1" #&CDS_SEC = "1";
"A":   PN = "1"  !CDS_PN = "1";
"B":   PN = "2"  !CDS_PN = "2";
BODY = "Q_CAP","I16": #LOCATION = "C2410" !CDS_LOCATION = "C2410" &SEC = "1" #&CDS_SEC = "1";
"A":   PN = "1"  !CDS_PN = "1";
"B":   PN = "2"  !CDS_PN = "2";
BODY = "Q_CAP","I17": #LOCATION = "C2418" !CDS_LOCATION = "C2418" &SEC = "1" #&CDS_SEC = "1";
"A":   PN = "1"  !CDS_PN = "1";
"B":   PN = "2"  !CDS_PN = "2";
BODY = "Q_CAP","I18": #LOCATION = "C2417" !CDS_LOCATION = "C2417" &SEC = "1" #&CDS_SEC = "1";
"A":   PN = "1"  !CDS_PN = "1";
"B":   PN = "2"  !CDS_PN = "2";
BODY = "Q_CAP","I19": #LOCATION = "C2426" !CDS_LOCATION = "C2426" &SEC = "1" #&CDS_SEC = "1";
"A":   PN = "1"  !CDS_PN = "1";
"B":   PN = "2"  !CDS_PN = "2";
BODY = "Q_CAP","I20": #LOCATION = "C2433" !CDS_LOCATION = "C2433" &SEC = "1" #&CDS_SEC = "1";
"A":   PN = "1"  !CDS_PN = "1";
"B":   PN = "2"  !CDS_PN = "2";
BODY = "Q_CAP","I21": #LOCATION = "C2425" !CDS_LOCATION = "C2425" &SEC = "1" #&CDS_SEC = "1";
"A":   PN = "1"  !CDS_PN = "1";
"B":   PN = "2"  !CDS_PN = "2";
BODY = "Q_CAP","I22": #LOCATION = "C2424" !CDS_LOCATION = "C2424" &SEC = "1" #&CDS_SEC = "1";
"A":   PN = "1"  !CDS_PN = "1";
"B":   PN = "2"  !CDS_PN = "2";
BODY = "Q_CAP","I23": #LOCATION = "C2432" !CDS_LOCATION = "C2432" &SEC = "1" #&CDS_SEC = "1";
"A":   PN = "1"  !CDS_PN = "1";
"B":   PN = "2"  !CDS_PN = "2";
BODY = "Q_CAP","I24": #LOCATION = "C2431" !CDS_LOCATION = "C2431" &SEC = "1" #&CDS_SEC = "1";
"A":   PN = "1"  !CDS_PN = "1";
"B":   PN = "2"  !CDS_PN = "2";
BODY = "Q_CAP","I25": #LOCATION = "C3916" !CDS_LOCATION = "C3916" &SEC = "1" #&CDS_SEC = "1";
"A":   PN = "1"  !CDS_PN = "1";
"B":   PN = "2"  !CDS_PN = "2";
BODY = "Q_CAP","I26": #LOCATION = "C2441" !CDS_LOCATION = "C2441" &SEC = "1" #&CDS_SEC = "1";
"A":   PN = "1"  !CDS_PN = "1";
"B":   PN = "2"  !CDS_PN = "2";
BODY = "Q_CAP","I27": #LOCATION = "C3917" !CDS_LOCATION = "C3917" &SEC = "1" #&CDS_SEC = "1";
"A":   PN = "1"  !CDS_PN = "1";
"B":   PN = "2"  !CDS_PN = "2";
BODY = "Q_CAP","I28": #LOCATION = "C2448" !CDS_LOCATION = "C2448" &SEC = "1" #&CDS_SEC = "1";
"A":   PN = "1"  !CDS_PN = "1";
"B":   PN = "2"  !CDS_PN = "2";
BODY = "Q_CAP","I29": #LOCATION = "C2455" !CDS_LOCATION = "C2455" &SEC = "1" #&CDS_SEC = "1";
"A":   PN = "1"  !CDS_PN = "1";
"B":   PN = "2"  !CDS_PN = "2";
BODY = "Q_CAP","I30": #LOCATION = "C3918" !CDS_LOCATION = "C3918" &SEC = "1" #&CDS_SEC = "1";
"A":   PN = "1"  !CDS_PN = "1";
"B":   PN = "2"  !CDS_PN = "2";
BODY = "Q_CAP","I32": #LOCATION = "C2462" !CDS_LOCATION = "C2462" &SEC = "1" #&CDS_SEC = "1";
"A":   PN = "1"  !CDS_PN = "1";
"B":   PN = "2"  !CDS_PN = "2";
BODY = "Q_CAP","I33": #LOCATION = "C2469" !CDS_LOCATION = "C2469" &SEC = "1" #&CDS_SEC = "1";
"A":   PN = "1"  !CDS_PN = "1";
"B":   PN = "2"  !CDS_PN = "2";
BODY = "Q_CAP","I34": #LOCATION = "C2440" !CDS_LOCATION = "C2440" &SEC = "1" #&CDS_SEC = "1";
"A":   PN = "1"  !CDS_PN = "1";
"B":   PN = "2"  !CDS_PN = "2";
BODY = "Q_CAP","I35": #LOCATION = "C2447" !CDS_LOCATION = "C2447" &SEC = "1" #&CDS_SEC = "1";
"A":   PN = "1"  !CDS_PN = "1";
"B":   PN = "2"  !CDS_PN = "2";
BODY = "Q_CAP","I36": #LOCATION = "C2439" !CDS_LOCATION = "C2439" &SEC = "1" #&CDS_SEC = "1";
"A":   PN = "1"  !CDS_PN = "1";
"B":   PN = "2"  !CDS_PN = "2";
BODY = "Q_CAP","I37": #LOCATION = "C2438" !CDS_LOCATION = "C2438" &SEC = "1" #&CDS_SEC = "1";
"A":   PN = "1"  !CDS_PN = "1";
"B":   PN = "2"  !CDS_PN = "2";
BODY = "Q_CAP","I38": #LOCATION = "C2446" !CDS_LOCATION = "C2446" &SEC = "1" #&CDS_SEC = "1";
"A":   PN = "1"  !CDS_PN = "1";
"B":   PN = "2"  !CDS_PN = "2";
BODY = "Q_CAP","I39": #LOCATION = "C2445" !CDS_LOCATION = "C2445" &SEC = "1" #&CDS_SEC = "1";
"A":   PN = "1"  !CDS_PN = "1";
"B":   PN = "2"  !CDS_PN = "2";
BODY = "Q_CAP","I40": #LOCATION = "C2452" !CDS_LOCATION = "C2452" &SEC = "1" #&CDS_SEC = "1";
"A":   PN = "1"  !CDS_PN = "1";
"B":   PN = "2"  !CDS_PN = "2";
BODY = "Q_CAP","I41": #LOCATION = "C2453" !CDS_LOCATION = "C2453" &SEC = "1" #&CDS_SEC = "1";
"A":   PN = "1"  !CDS_PN = "1";
"B":   PN = "2"  !CDS_PN = "2";
BODY = "Q_CAP","I42": #LOCATION = "C2454" !CDS_LOCATION = "C2454" &SEC = "1" #&CDS_SEC = "1";
"A":   PN = "1"  !CDS_PN = "1";
"B":   PN = "2"  !CDS_PN = "2";
BODY = "Q_CAP","I43": #LOCATION = "C2461" !CDS_LOCATION = "C2461" &SEC = "1" #&CDS_SEC = "1";
"A":   PN = "1"  !CDS_PN = "1";
"B":   PN = "2"  !CDS_PN = "2";
BODY = "Q_CAP","I44": #LOCATION = "C2468" !CDS_LOCATION = "C2468" &SEC = "1" #&CDS_SEC = "1";
"A":   PN = "1"  !CDS_PN = "1";
"B":   PN = "2"  !CDS_PN = "2";
BODY = "Q_CAP","I45": #LOCATION = "C2460" !CDS_LOCATION = "C2460" &SEC = "1" #&CDS_SEC = "1";
"A":   PN = "1"  !CDS_PN = "1";
"B":   PN = "2"  !CDS_PN = "2";
BODY = "Q_CAP","I46": #LOCATION = "C2459" !CDS_LOCATION = "C2459" &SEC = "1" #&CDS_SEC = "1";
"A":   PN = "1"  !CDS_PN = "1";
"B":   PN = "2"  !CDS_PN = "2";
BODY = "Q_CAP","I47": #LOCATION = "C2467" !CDS_LOCATION = "C2467" &SEC = "1" #&CDS_SEC = "1";
"A":   PN = "1"  !CDS_PN = "1";
"B":   PN = "2"  !CDS_PN = "2";
BODY = "Q_CAP","I48": #LOCATION = "C2466" !CDS_LOCATION = "C2466" &SEC = "1" #&CDS_SEC = "1";
"A":   PN = "1"  !CDS_PN = "1";
"B":   PN = "2"  !CDS_PN = "2";
BODY = "Q_CAP","I50": #LOCATION = "C2409" !CDS_LOCATION = "C2409" &SEC = "1" #&CDS_SEC = "1";
"A":   PN = "1"  !CDS_PN = "1";
"B":   PN = "2"  !CDS_PN = "2";
BODY = "Q_CAP","I52": #LOCATION = "C2416" !CDS_LOCATION = "C2416" &SEC = "1" #&CDS_SEC = "1";
"A":   PN = "1"  !CDS_PN = "1";
"B":   PN = "2"  !CDS_PN = "2";
BODY = "Q_CAP","I53": #LOCATION = "C2408" !CDS_LOCATION = "C2408" &SEC = "1" #&CDS_SEC = "1";
"A":   PN = "1"  !CDS_PN = "1";
"B":   PN = "2"  !CDS_PN = "2";
BODY = "Q_CAP","I55": #LOCATION = "C2407" !CDS_LOCATION = "C2407" &SEC = "1" #&CDS_SEC = "1";
"A":   PN = "1"  !CDS_PN = "1";
"B":   PN = "2"  !CDS_PN = "2";
BODY = "Q_CAP","I56": #LOCATION = "C2415" !CDS_LOCATION = "C2415" &SEC = "1" #&CDS_SEC = "1";
"A":   PN = "1"  !CDS_PN = "1";
"B":   PN = "2"  !CDS_PN = "2";
BODY = "Q_CAP","I57": #LOCATION = "C2414" !CDS_LOCATION = "C2414" &SEC = "1" #&CDS_SEC = "1";
"A":   PN = "1"  !CDS_PN = "1";
"B":   PN = "2"  !CDS_PN = "2";
BODY = "Q_CAP","I58": #LOCATION = "C2423" !CDS_LOCATION = "C2423" &SEC = "1" #&CDS_SEC = "1";
"A":   PN = "1"  !CDS_PN = "1";
"B":   PN = "2"  !CDS_PN = "2";
BODY = "Q_CAP","I59": #LOCATION = "C2430" !CDS_LOCATION = "C2430" &SEC = "1" #&CDS_SEC = "1";
"A":   PN = "1"  !CDS_PN = "1";
"B":   PN = "2"  !CDS_PN = "2";
BODY = "Q_CAP","I60": #LOCATION = "C2422" !CDS_LOCATION = "C2422" &SEC = "1" #&CDS_SEC = "1";
"A":   PN = "1"  !CDS_PN = "1";
"B":   PN = "2"  !CDS_PN = "2";
BODY = "Q_CAP","I61": #LOCATION = "C2421" !CDS_LOCATION = "C2421" &SEC = "1" #&CDS_SEC = "1";
"A":   PN = "1"  !CDS_PN = "1";
"B":   PN = "2"  !CDS_PN = "2";
BODY = "Q_CAP","I62": #LOCATION = "C2429" !CDS_LOCATION = "C2429" &SEC = "1" #&CDS_SEC = "1";
"A":   PN = "1"  !CDS_PN = "1";
"B":   PN = "2"  !CDS_PN = "2";
BODY = "Q_CAP","I64": #LOCATION = "C2437" !CDS_LOCATION = "C2437" &SEC = "1" #&CDS_SEC = "1";
"A":   PN = "1"  !CDS_PN = "1";
"B":   PN = "2"  !CDS_PN = "2";
BODY = "Q_CAP","I65": #LOCATION = "C2444" !CDS_LOCATION = "C2444" &SEC = "1" #&CDS_SEC = "1";
"A":   PN = "1"  !CDS_PN = "1";
"B":   PN = "2"  !CDS_PN = "2";
BODY = "Q_CAP","I66": #LOCATION = "C2436" !CDS_LOCATION = "C2436" &SEC = "1" #&CDS_SEC = "1";
"A":   PN = "1"  !CDS_PN = "1";
"B":   PN = "2"  !CDS_PN = "2";
BODY = "Q_CAP","I67": #LOCATION = "C2443" !CDS_LOCATION = "C2443" &SEC = "1" #&CDS_SEC = "1";
"A":   PN = "1"  !CDS_PN = "1";
"B":   PN = "2"  !CDS_PN = "2";
BODY = "Q_CAP","I68": #LOCATION = "C2449" !CDS_LOCATION = "C2449" &SEC = "1" #&CDS_SEC = "1";
"A":   PN = "1"  !CDS_PN = "1";
"B":   PN = "2"  !CDS_PN = "2";
BODY = "Q_CAP","I69": #LOCATION = "C2450" !CDS_LOCATION = "C2450" &SEC = "1" #&CDS_SEC = "1";
"A":   PN = "1"  !CDS_PN = "1";
"B":   PN = "2"  !CDS_PN = "2";
BODY = "Q_CAP","I70": #LOCATION = "C2451" !CDS_LOCATION = "C2451" &SEC = "1" #&CDS_SEC = "1";
"A":   PN = "1"  !CDS_PN = "1";
"B":   PN = "2"  !CDS_PN = "2";
BODY = "Q_CAP","I71": #LOCATION = "C2458" !CDS_LOCATION = "C2458" &SEC = "1" #&CDS_SEC = "1";
"A":   PN = "1"  !CDS_PN = "1";
"B":   PN = "2"  !CDS_PN = "2";
BODY = "Q_CAP","I72": #LOCATION = "C2465" !CDS_LOCATION = "C2465" &SEC = "1" #&CDS_SEC = "1";
"A":   PN = "1"  !CDS_PN = "1";
"B":   PN = "2"  !CDS_PN = "2";
BODY = "Q_CAP","I73": #LOCATION = "C2457" !CDS_LOCATION = "C2457" &SEC = "1" #&CDS_SEC = "1";
"A":   PN = "1"  !CDS_PN = "1";
"B":   PN = "2"  !CDS_PN = "2";
BODY = "Q_CAP","I74": #LOCATION = "C2456" !CDS_LOCATION = "C2456" &SEC = "1" #&CDS_SEC = "1";
"A":   PN = "1"  !CDS_PN = "1";
"B":   PN = "2"  !CDS_PN = "2";
BODY = "Q_CAP","I75": #LOCATION = "C2464" !CDS_LOCATION = "C2464" &SEC = "1" #&CDS_SEC = "1";
"A":   PN = "1"  !CDS_PN = "1";
"B":   PN = "2"  !CDS_PN = "2";
BODY = "Q_CAP","I76": #LOCATION = "C2463" !CDS_LOCATION = "C2463" &SEC = "1" #&CDS_SEC = "1";
"A":   PN = "1"  !CDS_PN = "1";
"B":   PN = "2"  !CDS_PN = "2";
BODY = "Q_CAP","I77": #LOCATION = "C3919" !CDS_LOCATION = "C3919" &SEC = "1" #&CDS_SEC = "1";
"A":   PN = "1"  !CDS_PN = "1";
"B":   PN = "2"  !CDS_PN = "2";
BODY = "Q_CAP","I79": #LOCATION = "C2476" !CDS_LOCATION = "C2476" &SEC = "1" #&CDS_SEC = "1";
"A":   PN = "1"  !CDS_PN = "1";
"B":   PN = "2"  !CDS_PN = "2";
BODY = "Q_CAP","I81": #LOCATION = "C2483" !CDS_LOCATION = "C2483" &SEC = "1" #&CDS_SEC = "1";
"A":   PN = "1"  !CDS_PN = "1";
"B":   PN = "2"  !CDS_PN = "2";
BODY = "Q_CAP","I84": #LOCATION = "C3920" !CDS_LOCATION = "C3920" &SEC = "1" #&CDS_SEC = "1";
"A":   PN = "1"  !CDS_PN = "1";
"B":   PN = "2"  !CDS_PN = "2";
BODY = "Q_CAP","I85": #LOCATION = "C2488" !CDS_LOCATION = "C2488" &SEC = "1" #&CDS_SEC = "1";
"A":   PN = "1"  !CDS_PN = "1";
"B":   PN = "2"  !CDS_PN = "2";
BODY = "Q_CAP","I86": #LOCATION = "C2492" !CDS_LOCATION = "C2492" &SEC = "1" #&CDS_SEC = "1";
"A":   PN = "1"  !CDS_PN = "1";
"B":   PN = "2"  !CDS_PN = "2";
BODY = "Q_CAP","I88": #LOCATION = "C2475" !CDS_LOCATION = "C2475" &SEC = "1" #&CDS_SEC = "1";
"A":   PN = "1"  !CDS_PN = "1";
"B":   PN = "2"  !CDS_PN = "2";
BODY = "Q_CAP","I90": #LOCATION = "C2482" !CDS_LOCATION = "C2482" &SEC = "1" #&CDS_SEC = "1";
"A":   PN = "1"  !CDS_PN = "1";
"B":   PN = "2"  !CDS_PN = "2";
BODY = "Q_CAP","I92": #LOCATION = "C2481" !CDS_LOCATION = "C2481" &SEC = "1" #&CDS_SEC = "1";
"A":   PN = "1"  !CDS_PN = "1";
"B":   PN = "2"  !CDS_PN = "2";
BODY = "Q_CAP","I94": #LOCATION = "C2474" !CDS_LOCATION = "C2474" &SEC = "1" #&CDS_SEC = "1";
"A":   PN = "1"  !CDS_PN = "1";
"B":   PN = "2"  !CDS_PN = "2";
BODY = "Q_CAP","I96": #LOCATION = "C2473" !CDS_LOCATION = "C2473" &SEC = "1" #&CDS_SEC = "1";
"A":   PN = "1"  !CDS_PN = "1";
"B":   PN = "2"  !CDS_PN = "2";
BODY = "Q_CAP","I97": #LOCATION = "C2480" !CDS_LOCATION = "C2480" &SEC = "1" #&CDS_SEC = "1";
"A":   PN = "1"  !CDS_PN = "1";
"B":   PN = "2"  !CDS_PN = "2";
BODY = "Q_CAP","I99": #LOCATION = "C2487" !CDS_LOCATION = "C2487" &SEC = "1" #&CDS_SEC = "1";
"A":   PN = "1"  !CDS_PN = "1";
"B":   PN = "2"  !CDS_PN = "2";
BODY = "Q_CAP","I100": #LOCATION = "C2486" !CDS_LOCATION = "C2486" &SEC = "1" #&CDS_SEC = "1";
"A":   PN = "1"  !CDS_PN = "1";
"B":   PN = "2"  !CDS_PN = "2";
BODY = "Q_CAP","I101": #LOCATION = "C2491" !CDS_LOCATION = "C2491" &SEC = "1" #&CDS_SEC = "1";
"A":   PN = "1"  !CDS_PN = "1";
"B":   PN = "2"  !CDS_PN = "2";
BODY = "Q_CAP","I102": #LOCATION = "C2490" !CDS_LOCATION = "C2490" &SEC = "1" #&CDS_SEC = "1";
"A":   PN = "1"  !CDS_PN = "1";
"B":   PN = "2"  !CDS_PN = "2";
BODY = "Q_CAP","I103": #LOCATION = "C2485" !CDS_LOCATION = "C2485" &SEC = "1" #&CDS_SEC = "1";
"A":   PN = "1"  !CDS_PN = "1";
"B":   PN = "2"  !CDS_PN = "2";
BODY = "Q_CAP","I104": #LOCATION = "C2489" !CDS_LOCATION = "C2489" &SEC = "1" #&CDS_SEC = "1";
"A":   PN = "1"  !CDS_PN = "1";
"B":   PN = "2"  !CDS_PN = "2";
BODY = "Q_CAP","I105": #LOCATION = "C2497" !CDS_LOCATION = "C2497" &SEC = "1" #&CDS_SEC = "1";
"A":   PN = "1"  !CDS_PN = "1";
"B":   PN = "2"  !CDS_PN = "2";
BODY = "Q_CAP","I106": #LOCATION = "C2502" !CDS_LOCATION = "C2502" &SEC = "1" #&CDS_SEC = "1";
"A":   PN = "1"  !CDS_PN = "1";
"B":   PN = "2"  !CDS_PN = "2";
BODY = "Q_CAP","I107": #LOCATION = "C2506" !CDS_LOCATION = "C2506" &SEC = "1" #&CDS_SEC = "1";
"A":   PN = "1"  !CDS_PN = "1";
"B":   PN = "2"  !CDS_PN = "2";
BODY = "Q_CAP","I108": #LOCATION = "C2115" !CDS_LOCATION = "C2115" &SEC = "1" #&CDS_SEC = "1";
"A":   PN = "1"  !CDS_PN = "1";
"B":   PN = "2"  !CDS_PN = "2";
BODY = "Q_CAP","I109": #LOCATION = "C2121" !CDS_LOCATION = "C2121" &SEC = "1" #&CDS_SEC = "1";
"A":   PN = "1"  !CDS_PN = "1";
"B":   PN = "2"  !CDS_PN = "2";
BODY = "Q_CAP","I110": #LOCATION = "C2496" !CDS_LOCATION = "C2496" &SEC = "1" #&CDS_SEC = "1";
"A":   PN = "1"  !CDS_PN = "1";
"B":   PN = "2"  !CDS_PN = "2";
BODY = "Q_CAP","I111": #LOCATION = "C2495" !CDS_LOCATION = "C2495" &SEC = "1" #&CDS_SEC = "1";
"A":   PN = "1"  !CDS_PN = "1";
"B":   PN = "2"  !CDS_PN = "2";
BODY = "Q_CAP","I112": #LOCATION = "C2501" !CDS_LOCATION = "C2501" &SEC = "1" #&CDS_SEC = "1";
"A":   PN = "1"  !CDS_PN = "1";
"B":   PN = "2"  !CDS_PN = "2";
BODY = "Q_CAP","I113": #LOCATION = "C2500" !CDS_LOCATION = "C2500" &SEC = "1" #&CDS_SEC = "1";
"A":   PN = "1"  !CDS_PN = "1";
"B":   PN = "2"  !CDS_PN = "2";
BODY = "Q_CAP","I114": #LOCATION = "C2494" !CDS_LOCATION = "C2494" &SEC = "1" #&CDS_SEC = "1";
"A":   PN = "1"  !CDS_PN = "1";
"B":   PN = "2"  !CDS_PN = "2";
BODY = "Q_CAP","I116": #LOCATION = "C2499" !CDS_LOCATION = "C2499" &SEC = "1" #&CDS_SEC = "1";
"A":   PN = "1"  !CDS_PN = "1";
"B":   PN = "2"  !CDS_PN = "2";
BODY = "Q_CAP","I117": #LOCATION = "C2505" !CDS_LOCATION = "C2505" &SEC = "1" #&CDS_SEC = "1";
"A":   PN = "1"  !CDS_PN = "1";
"B":   PN = "2"  !CDS_PN = "2";
BODY = "Q_CAP","I118": #LOCATION = "C2504" !CDS_LOCATION = "C2504" &SEC = "1" #&CDS_SEC = "1";
"A":   PN = "1"  !CDS_PN = "1";
"B":   PN = "2"  !CDS_PN = "2";
BODY = "Q_CAP","I119": #LOCATION = "C2113" !CDS_LOCATION = "C2113" &SEC = "1" #&CDS_SEC = "1";
"A":   PN = "1"  !CDS_PN = "1";
"B":   PN = "2"  !CDS_PN = "2";
BODY = "Q_CAP","I120": #LOCATION = "C2114" !CDS_LOCATION = "C2114" &SEC = "1" #&CDS_SEC = "1";
"A":   PN = "1"  !CDS_PN = "1";
"B":   PN = "2"  !CDS_PN = "2";
BODY = "Q_CAP","I121": #LOCATION = "C2120" !CDS_LOCATION = "C2120" &SEC = "1" #&CDS_SEC = "1";
"A":   PN = "1"  !CDS_PN = "1";
"B":   PN = "2"  !CDS_PN = "2";
BODY = "Q_CAP","I122": #LOCATION = "C2119" !CDS_LOCATION = "C2119" &SEC = "1" #&CDS_SEC = "1";
"A":   PN = "1"  !CDS_PN = "1";
"B":   PN = "2"  !CDS_PN = "2";
BODY = "Q_CAP","I123": #LOCATION = "C2503" !CDS_LOCATION = "C2503" &SEC = "1" #&CDS_SEC = "1";
"A":   PN = "1"  !CDS_PN = "1";
"B":   PN = "2"  !CDS_PN = "2";
BODY = "Q_CAP","I124": #LOCATION = "C2508" !CDS_LOCATION = "C2508" &SEC = "1" #&CDS_SEC = "1";
"A":   PN = "1"  !CDS_PN = "1";
"B":   PN = "2"  !CDS_PN = "2";
BODY = "Q_CAP","I125": #LOCATION = "C2118" !CDS_LOCATION = "C2118" &SEC = "1" #&CDS_SEC = "1";
"A":   PN = "1"  !CDS_PN = "1";
"B":   PN = "2"  !CDS_PN = "2";
BODY = "Q_CAP","I127": #LOCATION = "C2472" !CDS_LOCATION = "C2472" &SEC = "1" #&CDS_SEC = "1";
"A":   PN = "1"  !CDS_PN = "1";
"B":   PN = "2"  !CDS_PN = "2";
BODY = "Q_CAP","I129": #LOCATION = "C2479" !CDS_LOCATION = "C2479" &SEC = "1" #&CDS_SEC = "1";
"A":   PN = "1"  !CDS_PN = "1";
"B":   PN = "2"  !CDS_PN = "2";
BODY = "Q_CAP","I131": #LOCATION = "C2471" !CDS_LOCATION = "C2471" &SEC = "1" #&CDS_SEC = "1";
"A":   PN = "1"  !CDS_PN = "1";
"B":   PN = "2"  !CDS_PN = "2";
BODY = "Q_CAP","I133": #LOCATION = "C2470" !CDS_LOCATION = "C2470" &SEC = "1" #&CDS_SEC = "1";
"A":   PN = "1"  !CDS_PN = "1";
"B":   PN = "2"  !CDS_PN = "2";
BODY = "Q_CAP","I134": #LOCATION = "C2478" !CDS_LOCATION = "C2478" &SEC = "1" #&CDS_SEC = "1";
"A":   PN = "1"  !CDS_PN = "1";
"B":   PN = "2"  !CDS_PN = "2";
BODY = "Q_CAP","I136": #LOCATION = "C2477" !CDS_LOCATION = "C2477" &SEC = "1" #&CDS_SEC = "1";
"A":   PN = "1"  !CDS_PN = "1";
"B":   PN = "2"  !CDS_PN = "2";
BODY = "Q_CAP","I137": #LOCATION = "C2103" !CDS_LOCATION = "C2103" &SEC = "1" #&CDS_SEC = "1";
"A":   PN = "1"  !CDS_PN = "1";
"B":   PN = "2"  !CDS_PN = "2";
BODY = "Q_CAP","I138": #LOCATION = "C2106" !CDS_LOCATION = "C2106" &SEC = "1" #&CDS_SEC = "1";
"A":   PN = "1"  !CDS_PN = "1";
"B":   PN = "2"  !CDS_PN = "2";
BODY = "Q_CAP","I139": #LOCATION = "C2484" !CDS_LOCATION = "C2484" &SEC = "1" #&CDS_SEC = "1";
"A":   PN = "1"  !CDS_PN = "1";
"B":   PN = "2"  !CDS_PN = "2";
BODY = "Q_CAP","I140": #LOCATION = "C2102" !CDS_LOCATION = "C2102" &SEC = "1" #&CDS_SEC = "1";
"A":   PN = "1"  !CDS_PN = "1";
"B":   PN = "2"  !CDS_PN = "2";
BODY = "Q_CAP","I141": #LOCATION = "C2105" !CDS_LOCATION = "C2105" &SEC = "1" #&CDS_SEC = "1";
"A":   PN = "1"  !CDS_PN = "1";
"B":   PN = "2"  !CDS_PN = "2";
BODY = "Q_CAP","I142": #LOCATION = "C2104" !CDS_LOCATION = "C2104" &SEC = "1" #&CDS_SEC = "1";
"A":   PN = "1"  !CDS_PN = "1";
"B":   PN = "2"  !CDS_PN = "2";
BODY = "Q_CAP","I144": #LOCATION = "C2108" !CDS_LOCATION = "C2108" &SEC = "1" #&CDS_SEC = "1";
"A":   PN = "1"  !CDS_PN = "1";
"B":   PN = "2"  !CDS_PN = "2";
BODY = "Q_CAP","I145": #LOCATION = "C2107" !CDS_LOCATION = "C2107" &SEC = "1" #&CDS_SEC = "1";
"A":   PN = "1"  !CDS_PN = "1";
"B":   PN = "2"  !CDS_PN = "2";
BODY = "Q_CAP","I146": #LOCATION = "C2493" !CDS_LOCATION = "C2493" &SEC = "1" #&CDS_SEC = "1";
"A":   PN = "1"  !CDS_PN = "1";
"B":   PN = "2"  !CDS_PN = "2";
BODY = "Q_CAP","I147": #LOCATION = "C2498" !CDS_LOCATION = "C2498" &SEC = "1" #&CDS_SEC = "1";
"A":   PN = "1"  !CDS_PN = "1";
"B":   PN = "2"  !CDS_PN = "2";
BODY = "Q_CAP","I148": #LOCATION = "C2109" !CDS_LOCATION = "C2109" &SEC = "1" #&CDS_SEC = "1";
"A":   PN = "1"  !CDS_PN = "1";
"B":   PN = "2"  !CDS_PN = "2";
BODY = "Q_CAP","I149": #LOCATION = "C2111" !CDS_LOCATION = "C2111" &SEC = "1" #&CDS_SEC = "1";
"A":   PN = "1"  !CDS_PN = "1";
"B":   PN = "2"  !CDS_PN = "2";
BODY = "Q_CAP","I150": #LOCATION = "C2112" !CDS_LOCATION = "C2112" &SEC = "1" #&CDS_SEC = "1";
"A":   PN = "1"  !CDS_PN = "1";
"B":   PN = "2"  !CDS_PN = "2";
BODY = "Q_CAP","I151": #LOCATION = "C2110" !CDS_LOCATION = "C2110" &SEC = "1" #&CDS_SEC = "1";
"A":   PN = "1"  !CDS_PN = "1";
"B":   PN = "2"  !CDS_PN = "2";
BODY = "Q_CAP","I152": #LOCATION = "C2507" !CDS_LOCATION = "C2507" &SEC = "1" #&CDS_SEC = "1";
"A":   PN = "1"  !CDS_PN = "1";
"B":   PN = "2"  !CDS_PN = "2";
BODY = "Q_CAP","I153": #LOCATION = "C2117" !CDS_LOCATION = "C2117" &SEC = "1" #&CDS_SEC = "1";
"A":   PN = "1"  !CDS_PN = "1";
"B":   PN = "2"  !CDS_PN = "2";
BODY = "Q_CAP","I154": #LOCATION = "C2116" !CDS_LOCATION = "C2116" &SEC = "1" #&CDS_SEC = "1";
"A":   PN = "1"  !CDS_PN = "1";
"B":   PN = "2"  !CDS_PN = "2";
BODY = "Q_CAP","I155": #LOCATION = "C3921" !CDS_LOCATION = "C3921" &SEC = "1" #&CDS_SEC = "1";
"A":   PN = "1"  !CDS_PN = "1";
"B":   PN = "2"  !CDS_PN = "2";
BODY = "Q_CAP","I157": #LOCATION = "C3922" !CDS_LOCATION = "C3922" &SEC = "1" #&CDS_SEC = "1";
"A":   PN = "1"  !CDS_PN = "1";
"B":   PN = "2"  !CDS_PN = "2";
BODY = "Q_CAP","I159": #LOCATION = "C2126" !CDS_LOCATION = "C2126" &SEC = "1" #&CDS_SEC = "1";
"A":   PN = "1"  !CDS_PN = "1";
"B":   PN = "2"  !CDS_PN = "2";
BODY = "Q_CAP","I160": #LOCATION = "C2125" !CDS_LOCATION = "C2125" &SEC = "1" #&CDS_SEC = "1";
"A":   PN = "1"  !CDS_PN = "1";
"B":   PN = "2"  !CDS_PN = "2";
BODY = "Q_CAP","I161": #LOCATION = "C2511" !CDS_LOCATION = "C2511" &SEC = "1" #&CDS_SEC = "1";
"A":   PN = "1"  !CDS_PN = "1";
"B":   PN = "2"  !CDS_PN = "2";
BODY = "Q_CAP","I163": #LOCATION = "C2510" !CDS_LOCATION = "C2510" &SEC = "1" #&CDS_SEC = "1";
"A":   PN = "1"  !CDS_PN = "1";
"B":   PN = "2"  !CDS_PN = "2";
BODY = "Q_CAP","I164": #LOCATION = "C2124" !CDS_LOCATION = "C2124" &SEC = "1" #&CDS_SEC = "1";
"A":   PN = "1"  !CDS_PN = "1";
"B":   PN = "2"  !CDS_PN = "2";
BODY = "Q_CAP","I166": #LOCATION = "C2128" !CDS_LOCATION = "C2128" &SEC = "1" #&CDS_SEC = "1";
"A":   PN = "1"  !CDS_PN = "1";
"B":   PN = "2"  !CDS_PN = "2";
BODY = "Q_CAP","I168": #LOCATION = "C2123" !CDS_LOCATION = "C2123" &SEC = "1" #&CDS_SEC = "1";
"A":   PN = "1"  !CDS_PN = "1";
"B":   PN = "2"  !CDS_PN = "2";
BODY = "Q_CAP","I169": #LOCATION = "C2122" !CDS_LOCATION = "C2122" &SEC = "1" #&CDS_SEC = "1";
"A":   PN = "1"  !CDS_PN = "1";
"B":   PN = "2"  !CDS_PN = "2";
BODY = "Q_CAP","I170": #LOCATION = "C2509" !CDS_LOCATION = "C2509" &SEC = "1" #&CDS_SEC = "1";
"A":   PN = "1"  !CDS_PN = "1";
"B":   PN = "2"  !CDS_PN = "2";
BODY = "Q_CAP","I172": #LOCATION = "C2127" !CDS_LOCATION = "C2127" &SEC = "1" #&CDS_SEC = "1";
"A":   PN = "1"  !CDS_PN = "1";
"B":   PN = "2"  !CDS_PN = "2";
BODY = "Q_CAP","I173": #LOCATION = "C2442" !CDS_LOCATION = "C2442" &SEC = "1" #&CDS_SEC = "1";
"A":   PN = "1"  !CDS_PN = "1";
"B":   PN = "2"  !CDS_PN = "2";
BODY = "Q_CAP","I174": #LOCATION = "C2435" !CDS_LOCATION = "C2435" &SEC = "1" #&CDS_SEC = "1";
"A":   PN = "1"  !CDS_PN = "1";
"B":   PN = "2"  !CDS_PN = "2";
BODY = "Q_CAP","I175": #LOCATION = "C2428" !CDS_LOCATION = "C2428" &SEC = "1" #&CDS_SEC = "1";
"A":   PN = "1"  !CDS_PN = "1";
"B":   PN = "2"  !CDS_PN = "2";
DRAWING = "@t6g_mb_lib.t6g(sch_1):page74";
BODY = "Q_CAP","I1": #LOCATION = "C2661" !CDS_LOCATION = "C2661" &SEC = "1" #&CDS_SEC = "1";
"A":   PN = "1"  !CDS_PN = "1";
"B":   PN = "2"  !CDS_PN = "2";
BODY = "Q_CAP","I3": #LOCATION = "C2660" !CDS_LOCATION = "C2660" &SEC = "1" #&CDS_SEC = "1";
"A":   PN = "1"  !CDS_PN = "1";
"B":   PN = "2"  !CDS_PN = "2";
BODY = "Q_CAP","I8": #LOCATION = "C2664" !CDS_LOCATION = "C2664" &SEC = "1" #&CDS_SEC = "1";
"A":   PN = "1"  !CDS_PN = "1";
"B":   PN = "2"  !CDS_PN = "2";
BODY = "Q_CAP","I9": #LOCATION = "C2663" !CDS_LOCATION = "C2663" &SEC = "1" #&CDS_SEC = "1";
"A":   PN = "1"  !CDS_PN = "1";
"B":   PN = "2"  !CDS_PN = "2";
BODY = "Q_CAP","I10": #LOCATION = "C2665" !CDS_LOCATION = "C2665" &SEC = "1" #&CDS_SEC = "1";
"A":   PN = "1"  !CDS_PN = "1";
"B":   PN = "2"  !CDS_PN = "2";
BODY = "Q_CAP","I11": #LOCATION = "C2667" !CDS_LOCATION = "C2667" &SEC = "1" #&CDS_SEC = "1";
"A":   PN = "1"  !CDS_PN = "1";
"B":   PN = "2"  !CDS_PN = "2";
BODY = "Q_CAP","I12": #LOCATION = "C2668" !CDS_LOCATION = "C2668" &SEC = "1" #&CDS_SEC = "1";
"A":   PN = "1"  !CDS_PN = "1";
"B":   PN = "2"  !CDS_PN = "2";
BODY = "Q_CAP","I13": #LOCATION = "C2669" !CDS_LOCATION = "C2669" &SEC = "1" #&CDS_SEC = "1";
"A":   PN = "1"  !CDS_PN = "1";
"B":   PN = "2"  !CDS_PN = "2";
BODY = "Q_CAP","I14": #LOCATION = "C2670" !CDS_LOCATION = "C2670" &SEC = "1" #&CDS_SEC = "1";
"A":   PN = "1"  !CDS_PN = "1";
"B":   PN = "2"  !CDS_PN = "2";
BODY = "Q_CAP","I15": #LOCATION = "C2671" !CDS_LOCATION = "C2671" &SEC = "1" #&CDS_SEC = "1";
"A":   PN = "1"  !CDS_PN = "1";
"B":   PN = "2"  !CDS_PN = "2";
BODY = "Q_CAP","I16": #LOCATION = "C2672" !CDS_LOCATION = "C2672" &SEC = "1" #&CDS_SEC = "1";
"A":   PN = "1"  !CDS_PN = "1";
"B":   PN = "2"  !CDS_PN = "2";
BODY = "Q_CAP","I18": #LOCATION = "C2673" !CDS_LOCATION = "C2673" &SEC = "1" #&CDS_SEC = "1";
"A":   PN = "1"  !CDS_PN = "1";
"B":   PN = "2"  !CDS_PN = "2";
BODY = "Q_CAP","I25": #LOCATION = "C2662" !CDS_LOCATION = "C2662" &SEC = "1" #&CDS_SEC = "1";
"A":   PN = "1"  !CDS_PN = "1";
"B":   PN = "2"  !CDS_PN = "2";
BODY = "Q_CAP","I26": #LOCATION = "C2659" !CDS_LOCATION = "C2659" &SEC = "1" #&CDS_SEC = "1";
"A":   PN = "1"  !CDS_PN = "1";
"B":   PN = "2"  !CDS_PN = "2";
DRAWING = "@t6g_mb_lib.t6g(sch_1):page75";
BODY = "Q_RES","I8": #LOCATION = "R747" !CDS_LOCATION = "R747" &SEC = "1" #&CDS_SEC = "1";
"A":   PN = "1"  !CDS_PN = "1";
"B":   PN = "2"  !CDS_PN = "2";
BODY = "Q_RES","I9": #LOCATION = "R748" !CDS_LOCATION = "R748" &SEC = "1" #&CDS_SEC = "1";
"A":   PN = "1"  !CDS_PN = "1";
"B":   PN = "2"  !CDS_PN = "2";
BODY = "Q_RES","I12": #LOCATION = "R751" !CDS_LOCATION = "R751" &SEC = "1" #&CDS_SEC = "1";
"A":   PN = "1"  !CDS_PN = "1";
"B":   PN = "2"  !CDS_PN = "2";
BODY = "Q_RES","I41": #LOCATION = "R729" !CDS_LOCATION = "R729" &SEC = "1" #&CDS_SEC = "1";
"A":   PN = "1"  !CDS_PN = "1";
"B":   PN = "2"  !CDS_PN = "2";
BODY = "Q_RES","I43": #LOCATION = "R737" !CDS_LOCATION = "R737" &SEC = "1" #&CDS_SEC = "1";
"A":   PN = "1"  !CDS_PN = "1";
"B":   PN = "2"  !CDS_PN = "2";
BODY = "Q_RES","I44": #LOCATION = "R740" !CDS_LOCATION = "R740" &SEC = "1" #&CDS_SEC = "1";
"A":   PN = "1"  !CDS_PN = "1";
"B":   PN = "2"  !CDS_PN = "2";
BODY = "Q_RES","I45": #LOCATION = "R739" !CDS_LOCATION = "R739" &SEC = "1" #&CDS_SEC = "1";
"A":   PN = "1"  !CDS_PN = "1";
"B":   PN = "2"  !CDS_PN = "2";
BODY = "Q_RES","I46": #LOCATION = "R742" !CDS_LOCATION = "R742" &SEC = "1" #&CDS_SEC = "1";
"A":   PN = "1"  !CDS_PN = "1";
"B":   PN = "2"  !CDS_PN = "2";
BODY = "Q_RES","I74": #LOCATION = "R750" !CDS_LOCATION = "R750" &SEC = "1" #&CDS_SEC = "1";
"A":   PN = "1"  !CDS_PN = "1";
"B":   PN = "2"  !CDS_PN = "2";
BODY = "Q_RES","I75": #LOCATION = "R753" !CDS_LOCATION = "R753" &SEC = "1" #&CDS_SEC = "1";
"A":   PN = "1"  !CDS_PN = "1";
"B":   PN = "2"  !CDS_PN = "2";
BODY = "Q_RES","I87": #LOCATION = "R730" !CDS_LOCATION = "R730" &SEC = "1" #&CDS_SEC = "1";
"A":   PN = "1"  !CDS_PN = "1";
"B":   PN = "2"  !CDS_PN = "2";
BODY = "Q_RES","I89": #LOCATION = "R736" !CDS_LOCATION = "R736" &SEC = "1" #&CDS_SEC = "1";
"A":   PN = "1"  !CDS_PN = "1";
"B":   PN = "2"  !CDS_PN = "2";
BODY = "Q_RES","I90": #LOCATION = "R1501" !CDS_LOCATION = "R1501" &SEC = "1" #&CDS_SEC = "1";
"A":   PN = "1"  !CDS_PN = "1";
"B":   PN = "2"  !CDS_PN = "2";
BODY = "Q_RES","I91": #LOCATION = "R754" !CDS_LOCATION = "R754" &SEC = "1" #&CDS_SEC = "1";
"A":   PN = "1"  !CDS_PN = "1";
"B":   PN = "2"  !CDS_PN = "2";
BODY = "Q_RES","I92": #LOCATION = "R760" !CDS_LOCATION = "R760" &SEC = "1" #&CDS_SEC = "1";
"A":   PN = "1"  !CDS_PN = "1";
"B":   PN = "2"  !CDS_PN = "2";
BODY = "Q_RES","I94": #LOCATION = "R1502" !CDS_LOCATION = "R1502" &SEC = "1" #&CDS_SEC = "1";
"A":   PN = "1"  !CDS_PN = "1";
"B":   PN = "2"  !CDS_PN = "2";
BODY = "Q_RES","I97": #LOCATION = "R743" !CDS_LOCATION = "R743" &SEC = "1" #&CDS_SEC = "1";
"A":   PN = "1"  !CDS_PN = "1";
"B":   PN = "2"  !CDS_PN = "2";
BODY = "Q_RES","I99": #LOCATION = "R6098" !CDS_LOCATION = "R6098" &SEC = "1" #&CDS_SEC = "1";
"A":   PN = "1"  !CDS_PN = "1";
"B":   PN = "2"  !CDS_PN = "2";
DRAWING = "@t6g_mb_lib.t6g(sch_1):page76";
BODY = "Q_CAP","I50": #LOCATION = "C1104" !CDS_LOCATION = "C1104" &SEC = "1" #&CDS_SEC = "1";
"A":   PN = "1"  !CDS_PN = "1";
"B":   PN = "2"  !CDS_PN = "2";
BODY = "Q_CAP","I53": #LOCATION = "C1102" !CDS_LOCATION = "C1102" &SEC = "1" #&CDS_SEC = "1";
"A":   PN = "1"  !CDS_PN = "1";
"B":   PN = "2"  !CDS_PN = "2";
BODY = "Q_CAP","I59": #LOCATION = "C1105" !CDS_LOCATION = "C1105" &SEC = "1" #&CDS_SEC = "1";
"A":   PN = "1"  !CDS_PN = "1";
"B":   PN = "2"  !CDS_PN = "2";
BODY = "SN74AVC4T774PWR","I63": #LOCATION = "U53" !CDS_LOCATION = "U53" &SEC = "1" #&CDS_SEC = "1";
"A1":   PN = "3"  !CDS_PN = "3";
"A2":   PN = "4"  !CDS_PN = "4";
"A3":   PN = "5"  !CDS_PN = "5";
"A4":   PN = "6"  !CDS_PN = "6";
"B1":   PN = "14"  !CDS_PN = "14";
"B2":   PN = "13"  !CDS_PN = "13";
"B3":   PN = "12"  !CDS_PN = "12";
"B4":   PN = "11"  !CDS_PN = "11";
"DIR1":   PN = "1"  !CDS_PN = "1";
"DIR2":   PN = "2"  !CDS_PN = "2";
"DIR3":   PN = "7"  !CDS_PN = "7";
"DIR4":   PN = "8"  !CDS_PN = "8";
"GND":   PN = "10"  !CDS_PN = "10";
"OE":   PN = "9"  !CDS_PN = "9";
"VCCA":   PN = "16"  !CDS_PN = "16";
"VCCB":   PN = "15"  !CDS_PN = "15";
BODY = "Q_CAP","I65": #LOCATION = "C1103" !CDS_LOCATION = "C1103" &SEC = "1" #&CDS_SEC = "1";
"A":   PN = "1"  !CDS_PN = "1";
"B":   PN = "2"  !CDS_PN = "2";
BODY = "PI4ULS3V304AZMAEX","I67": #LOCATION = "U54" !CDS_LOCATION = "U54" &SEC = "1" #&CDS_SEC = "1";
"A1":   PN = "2"  !CDS_PN = "2";
"A2":   PN = "3"  !CDS_PN = "3";
"A3":   PN = "4"  !CDS_PN = "4";
"A4":   PN = "5"  !CDS_PN = "5";
"B1":   PN = "10"  !CDS_PN = "10";
"B2":   PN = "9"  !CDS_PN = "9";
"B3":   PN = "8"  !CDS_PN = "8";
"B4":   PN = "7"  !CDS_PN = "7";
"EN":   PN = "12"  !CDS_PN = "12";
"GND":   PN = "6"  !CDS_PN = "6";
"VCCA":   PN = "1"  !CDS_PN = "1";
"VCCB":   PN = "11"  !CDS_PN = "11";
BODY = "Q_RES","I97": #LOCATION = "R610" !CDS_LOCATION = "R610" &SEC = "1" #&CDS_SEC = "1";
"A":   PN = "1"  !CDS_PN = "1";
"B":   PN = "2"  !CDS_PN = "2";
BODY = "Q_RES","I106": #LOCATION = "R811" !CDS_LOCATION = "R811" &SEC = "1" #&CDS_SEC = "1";
"A":   PN = "1"  !CDS_PN = "1";
"B":   PN = "2"  !CDS_PN = "2";
BODY = "Q_RES","I107": #LOCATION = "R659" !CDS_LOCATION = "R659" &SEC = "1" #&CDS_SEC = "1";
"A":   PN = "1"  !CDS_PN = "1";
"B":   PN = "2"  !CDS_PN = "2";
BODY = "Q_RES","I108": #LOCATION = "R601" !CDS_LOCATION = "R601" &SEC = "1" #&CDS_SEC = "1";
"A":   PN = "1"  !CDS_PN = "1";
"B":   PN = "2"  !CDS_PN = "2";
BODY = "Q_RES","I115": #LOCATION = "R20" !CDS_LOCATION = "R20" &SEC = "1" #&CDS_SEC = "1";
"A":   PN = "1"  !CDS_PN = "1";
"B":   PN = "2"  !CDS_PN = "2";
BODY = "Q_RES","I116": #LOCATION = "R21" !CDS_LOCATION = "R21" &SEC = "1" #&CDS_SEC = "1";
"A":   PN = "1"  !CDS_PN = "1";
"B":   PN = "2"  !CDS_PN = "2";
BODY = "Q_RES","I117": #LOCATION = "R127" !CDS_LOCATION = "R127" &SEC = "1" #&CDS_SEC = "1";
"A":   PN = "1"  !CDS_PN = "1";
"B":   PN = "2"  !CDS_PN = "2";
BODY = "Q_RES","I118": #LOCATION = "R128" !CDS_LOCATION = "R128" &SEC = "1" #&CDS_SEC = "1";
"A":   PN = "1"  !CDS_PN = "1";
"B":   PN = "2"  !CDS_PN = "2";
BODY = "Q_RES","I119": #LOCATION = "R129" !CDS_LOCATION = "R129" &SEC = "1" #&CDS_SEC = "1";
"A":   PN = "1"  !CDS_PN = "1";
"B":   PN = "2"  !CDS_PN = "2";
BODY = "Q_RES","I131": #LOCATION = "R1532" !CDS_LOCATION = "R1532" &SEC = "1" #&CDS_SEC = "1";
"A":   PN = "1"  !CDS_PN = "1";
"B":   PN = "2"  !CDS_PN = "2";
BODY = "Q_RES","I132": #LOCATION = "R1531" !CDS_LOCATION = "R1531" &SEC = "1" #&CDS_SEC = "1";
"A":   PN = "1"  !CDS_PN = "1";
"B":   PN = "2"  !CDS_PN = "2";
BODY = "Q_RES","I133": #LOCATION = "R1530" !CDS_LOCATION = "R1530" &SEC = "1" #&CDS_SEC = "1";
"A":   PN = "1"  !CDS_PN = "1";
"B":   PN = "2"  !CDS_PN = "2";
BODY = "Q_RES","I134": #LOCATION = "R1529" !CDS_LOCATION = "R1529" &SEC = "1" #&CDS_SEC = "1";
"A":   PN = "1"  !CDS_PN = "1";
"B":   PN = "2"  !CDS_PN = "2";
BODY = "Q_RES","I148": #LOCATION = "R1547" !CDS_LOCATION = "R1547" &SEC = "1" #&CDS_SEC = "1";
"A":   PN = "1"  !CDS_PN = "1";
"B":   PN = "2"  !CDS_PN = "2";
BODY = "Q_RES","I150": #LOCATION = "R1567" !CDS_LOCATION = "R1567" &SEC = "1" #&CDS_SEC = "1";
"A":   PN = "1"  !CDS_PN = "1";
"B":   PN = "2"  !CDS_PN = "2";
BODY = "Q_RES","I180": #LOCATION = "R600" !CDS_LOCATION = "R600" &SEC = "1" #&CDS_SEC = "1";
"A":   PN = "1"  !CDS_PN = "1";
"B":   PN = "2"  !CDS_PN = "2";
BODY = "Q_RES","I191": #LOCATION = "R1655" !CDS_LOCATION = "R1655" &SEC = "1" #&CDS_SEC = "1";
"A":   PN = "1"  !CDS_PN = "1";
"B":   PN = "2"  !CDS_PN = "2";
BODY = "Q_RES","I205": #LOCATION = "R606" !CDS_LOCATION = "R606" &SEC = "1" #&CDS_SEC = "1";
"A":   PN = "1"  !CDS_PN = "1";
"B":   PN = "2"  !CDS_PN = "2";
BODY = "Q_RES","I207": #LOCATION = "R607" !CDS_LOCATION = "R607" &SEC = "1" #&CDS_SEC = "1";
"A":   PN = "1"  !CDS_PN = "1";
"B":   PN = "2"  !CDS_PN = "2";
BODY = "Q_RES","I219": #LOCATION = "R605" !CDS_LOCATION = "R605" &SEC = "1" #&CDS_SEC = "1";
"A":   PN = "1"  !CDS_PN = "1";
"B":   PN = "2"  !CDS_PN = "2";
BODY = "Q_RES","I221": #LOCATION = "R604" !CDS_LOCATION = "R604" &SEC = "1" #&CDS_SEC = "1";
"A":   PN = "1"  !CDS_PN = "1";
"B":   PN = "2"  !CDS_PN = "2";
BODY = "Q_RES","I228": #LOCATION = "R603" !CDS_LOCATION = "R603" &SEC = "1" #&CDS_SEC = "1";
"A":   PN = "1"  !CDS_PN = "1";
"B":   PN = "2"  !CDS_PN = "2";
BODY = "Q_RES","I230": #LOCATION = "R602" !CDS_LOCATION = "R602" &SEC = "1" #&CDS_SEC = "1";
"A":   PN = "1"  !CDS_PN = "1";
"B":   PN = "2"  !CDS_PN = "2";
BODY = "Q_RES","I234": #LOCATION = "R8005" !CDS_LOCATION = "R8005" #SEC = "1" !CDS_SEC = "1";
"A":   PN = "1"  !CDS_PN = "1";
"B":   PN = "2"  !CDS_PN = "2";
BODY = "Q_RES","I239": #LOCATION = "R8006" !CDS_LOCATION = "R8006" #SEC = "1" !CDS_SEC = "1";
"A":   PN = "1"  !CDS_PN = "1";
"B":   PN = "2"  !CDS_PN = "2";
BODY = "Q_RES","I240": #LOCATION = "R8007" !CDS_LOCATION = "R8007" #SEC = "1" !CDS_SEC = "1";
"A":   PN = "1"  !CDS_PN = "1";
"B":   PN = "2"  !CDS_PN = "2";
BODY = "Q_RES","I241": #LOCATION = "R8008" !CDS_LOCATION = "R8008" #SEC = "1" !CDS_SEC = "1";
"A":   PN = "1"  !CDS_PN = "1";
"B":   PN = "2"  !CDS_PN = "2";
BODY = "Q_RES","I242": #LOCATION = "R608" !CDS_LOCATION = "R608" &SEC = "1" #&CDS_SEC = "1";
"A":   PN = "1"  !CDS_PN = "1";
"B":   PN = "2"  !CDS_PN = "2";
DRAWING = "@t6g_mb_lib.t6g(sch_1):page77";
BODY = "Q_RES","I1": #LOCATION = "R702" !CDS_LOCATION = "R702" &SEC = "1" #&CDS_SEC = "1";
"A":   PN = "1"  !CDS_PN = "1";
"B":   PN = "2"  !CDS_PN = "2";
BODY = "Q_RES","I5": #LOCATION = "R703" !CDS_LOCATION = "R703" &SEC = "1" #&CDS_SEC = "1";
"A":   PN = "1"  !CDS_PN = "1";
"B":   PN = "2"  !CDS_PN = "2";
BODY = "Q_CAP","I11": #LOCATION = "C223" !CDS_LOCATION = "C223" &SEC = "1" #&CDS_SEC = "1";
"A":   PN = "1"  !CDS_PN = "1";
"B":   PN = "2"  !CDS_PN = "2";
BODY = "SN74LVC2G07DCKR","I15": #LOCATION = "U29" !CDS_LOCATION = "U29" &SEC = "1" #&CDS_SEC = "1";
"1A":   PN = "1"  !CDS_PN = "1";
"1Y":   PN = "6"  !CDS_PN = "6";
"2A":   PN = "3"  !CDS_PN = "3";
"2Y":   PN = "4"  !CDS_PN = "4";
"GND":   PN = "2"  !CDS_PN = "2";
"VCC":   PN = "5"  !CDS_PN = "5";
BODY = "Q_CAP","I19": #LOCATION = "C224" !CDS_LOCATION = "C224" &SEC = "1" #&CDS_SEC = "1";
"A":   PN = "1"  !CDS_PN = "1";
"B":   PN = "2"  !CDS_PN = "2";
BODY = "SN74LVC2G07DCKR","I21": #LOCATION = "U40" !CDS_LOCATION = "U40" &SEC = "1" #&CDS_SEC = "1";
"1A":   PN = "1"  !CDS_PN = "1";
"1Y":   PN = "6"  !CDS_PN = "6";
"2A":   PN = "3"  !CDS_PN = "3";
"2Y":   PN = "4"  !CDS_PN = "4";
"GND":   PN = "2"  !CDS_PN = "2";
"VCC":   PN = "5"  !CDS_PN = "5";
DRAWING = "@t6g_mb_lib.t6g(sch_1):page85";
BODY = "Q_RES","I499": #LOCATION = "R7" !CDS_LOCATION = "R7" #SEC = "1" !CDS_SEC = "1";
"A":   PN = "1"  !CDS_PN = "1";
"B":   PN = "2"  !CDS_PN = "2";
BODY = "Q_CAP","I519": #LOCATION = "C89" !CDS_LOCATION = "C89" &SEC = "1" #&CDS_SEC = "1";
"A":   PN = "1"  !CDS_PN = "1";
"B":   PN = "2"  !CDS_PN = "2";
BODY = "Q_CAP","I523": #LOCATION = "C88" !CDS_LOCATION = "C88" &SEC = "1" #&CDS_SEC = "1";
"A":   PN = "1"  !CDS_PN = "1";
"B":   PN = "2"  !CDS_PN = "2";
BODY = "Q_RES","I525": #LOCATION = "R291" !CDS_LOCATION = "R291" &SEC = "1" #&CDS_SEC = "1";
"A":   PN = "1"  !CDS_PN = "1";
"B":   PN = "2"  !CDS_PN = "2";
BODY = "Q_RES","I526": #LOCATION = "R88" !CDS_LOCATION = "R88" &SEC = "1" #&CDS_SEC = "1";
"A":   PN = "1"  !CDS_PN = "1";
"B":   PN = "2"  !CDS_PN = "2";
BODY = "Q_RES","I528": #LOCATION = "R89" !CDS_LOCATION = "R89" &SEC = "1" #&CDS_SEC = "1";
"A":   PN = "1"  !CDS_PN = "1";
"B":   PN = "2"  !CDS_PN = "2";
BODY = "Q_CAP","I534": #LOCATION = "C142" !CDS_LOCATION = "C142" &SEC = "1" #&CDS_SEC = "1";
"A":   PN = "1"  !CDS_PN = "1";
"B":   PN = "2"  !CDS_PN = "2";
BODY = "SCONN288_DDR506112002KQ","I536": #LOCATION = "J1" !CDS_LOCATION = "J1" &SEC = "1" #&CDS_SEC = "1";
"ALERT_N":   PN = "62"  !CDS_PN = "62";
"CA0_A":   PN = "66"  !CDS_PN = "66";
"CA0_B":   PN = "76"  !CDS_PN = "76";
"CA1_A":   PN = "211"  !CDS_PN = "211";
"CA1_B":   PN = "221"  !CDS_PN = "221";
"CA2_A":   PN = "68"  !CDS_PN = "68";
"CA2_B":   PN = "78"  !CDS_PN = "78";
"CA3_A":   PN = "213"  !CDS_PN = "213";
"CA3_B":   PN = "223"  !CDS_PN = "223";
"CA4_A":   PN = "70"  !CDS_PN = "70";
"CA4_B":   PN = "80"  !CDS_PN = "80";
"CA5_A":   PN = "215"  !CDS_PN = "215";
"CA5_B":   PN = "225"  !CDS_PN = "225";
"CA6_A":   PN = "72"  !CDS_PN = "72";
"CA6_B":   PN = "82"  !CDS_PN = "82";
"CB0_A":   PN = "51"  !CDS_PN = "51";
"CB0_B":   PN = "96"  !CDS_PN = "96";
"CB1_A":   PN = "53"  !CDS_PN = "53";
"CB1_B":   PN = "98"  !CDS_PN = "98";
"CB2_A":   PN = "196"  !CDS_PN = "196";
"CB2_B":   PN = "241"  !CDS_PN = "241";
"CB3_A":   PN = "198"  !CDS_PN = "198";
"CB3_B":   PN = "243"  !CDS_PN = "243";
"CB4_A":   PN = "58"  !CDS_PN = "58";
"CB4_B":   PN = "89"  !CDS_PN = "89";
"CB5_A":   PN = "60"  !CDS_PN = "60";
"CB5_B":   PN = "91"  !CDS_PN = "91";
"CB6_A":   PN = "203"  !CDS_PN = "203";
"CB6_B":   PN = "234"  !CDS_PN = "234";
"CB7_A":   PN = "205"  !CDS_PN = "205";
"CB7_B":   PN = "236"  !CDS_PN = "236";
"CK_C":   PN = "218"  !CDS_PN = "218";
"CK_T":   PN = "217"  !CDS_PN = "217";
"CS0_A_N":   PN = "64"  !CDS_PN = "64";
"CS0_B_N":   PN = "84"  !CDS_PN = "84";
"CS1_A_N":   PN = "209"  !CDS_PN = "209";
"CS1_B_N":   PN = "229"  !CDS_PN = "229";
"DQ0_A":   PN = "7"  !CDS_PN = "7";
"DQ0_B":   PN = "100"  !CDS_PN = "100";
"DQ1_A":   PN = "9"  !CDS_PN = "9";
"DQ1_B":   PN = "102"  !CDS_PN = "102";
"DQ2_A":   PN = "152"  !CDS_PN = "152";
"DQ2_B":   PN = "245"  !CDS_PN = "245";
"DQ3_A":   PN = "154"  !CDS_PN = "154";
"DQ3_B":   PN = "247"  !CDS_PN = "247";
"DQ4_A":   PN = "14"  !CDS_PN = "14";
"DQ4_B":   PN = "107"  !CDS_PN = "107";
"DQ5_A":   PN = "16"  !CDS_PN = "16";
"DQ5_B":   PN = "109"  !CDS_PN = "109";
"DQ6_A":   PN = "159"  !CDS_PN = "159";
"DQ6_B":   PN = "252"  !CDS_PN = "252";
"DQ7_A":   PN = "161"  !CDS_PN = "161";
"DQ7_B":   PN = "254"  !CDS_PN = "254";
"DQ8_A":   PN = "18"  !CDS_PN = "18";
"DQ8_B":   PN = "111"  !CDS_PN = "111";
"DQ9_A":   PN = "20"  !CDS_PN = "20";
"DQ9_B":   PN = "113"  !CDS_PN = "113";
"DQ10_A":   PN = "163"  !CDS_PN = "163";
"DQ10_B":   PN = "256"  !CDS_PN = "256";
"DQ11_A":   PN = "165"  !CDS_PN = "165";
"DQ11_B":   PN = "258"  !CDS_PN = "258";
"DQ12_A":   PN = "25"  !CDS_PN = "25";
"DQ12_B":   PN = "118"  !CDS_PN = "118";
"DQ13_A":   PN = "27"  !CDS_PN = "27";
"DQ13_B":   PN = "120"  !CDS_PN = "120";
"DQ14_A":   PN = "170"  !CDS_PN = "170";
"DQ14_B":   PN = "263"  !CDS_PN = "263";
"DQ15_A":   PN = "172"  !CDS_PN = "172";
"DQ15_B":   PN = "265"  !CDS_PN = "265";
"DQ16_A":   PN = "29"  !CDS_PN = "29";
"DQ16_B":   PN = "122"  !CDS_PN = "122";
"DQ17_A":   PN = "31"  !CDS_PN = "31";
"DQ17_B":   PN = "124"  !CDS_PN = "124";
"DQ18_A":   PN = "174"  !CDS_PN = "174";
"DQ18_B":   PN = "267"  !CDS_PN = "267";
"DQ19_A":   PN = "176"  !CDS_PN = "176";
"DQ19_B":   PN = "269"  !CDS_PN = "269";
"DQ20_A":   PN = "36"  !CDS_PN = "36";
"DQ20_B":   PN = "129"  !CDS_PN = "129";
"DQ21_A":   PN = "38"  !CDS_PN = "38";
"DQ21_B":   PN = "131"  !CDS_PN = "131";
"DQ22_A":   PN = "181"  !CDS_PN = "181";
"DQ22_B":   PN = "274"  !CDS_PN = "274";
"DQ23_A":   PN = "183"  !CDS_PN = "183";
"DQ23_B":   PN = "276"  !CDS_PN = "276";
"DQ24_A":   PN = "40"  !CDS_PN = "40";
"DQ24_B":   PN = "133"  !CDS_PN = "133";
"DQ25_A":   PN = "42"  !CDS_PN = "42";
"DQ25_B":   PN = "135"  !CDS_PN = "135";
"DQ26_A":   PN = "185"  !CDS_PN = "185";
"DQ26_B":   PN = "278"  !CDS_PN = "278";
"DQ27_A":   PN = "187"  !CDS_PN = "187";
"DQ27_B":   PN = "280"  !CDS_PN = "280";
"DQ28_A":   PN = "47"  !CDS_PN = "47";
"DQ28_B":   PN = "140"  !CDS_PN = "140";
"DQ29_A":   PN = "49"  !CDS_PN = "49";
"DQ29_B":   PN = "142"  !CDS_PN = "142";
"DQ30_A":   PN = "192"  !CDS_PN = "192";
"DQ30_B":   PN = "285"  !CDS_PN = "285";
"DQ31_A":   PN = "194"  !CDS_PN = "194";
"DQ31_B":   PN = "287"  !CDS_PN = "287";
"HAS":   PN = "148"  !CDS_PN = "148";
"HSCL":   PN = "4"  !CDS_PN = "4";
"HSDA":   PN = "5"  !CDS_PN = "5";
"LBD||RSP_A_N":   PN = "86"  !CDS_PN = "86";
"LBS||RSP_B_N":   PN = "87"  !CDS_PN = "87";
"PAR_A":   PN = "74"  !CDS_PN = "74";
"PAR_B":   PN = "227"  !CDS_PN = "227";
"PWR_GOOD||FAIL_N":   PN = "147"  !CDS_PN = "147";
"RESET_N":   PN = "207"  !CDS_PN = "207";
"RFU0":   PN = "2"  !CDS_PN = "2";
"RFU1":   PN = "144"  !CDS_PN = "144";
"RFU2":   PN = "149"  !CDS_PN = "149";
"RFU3":   PN = "150"  !CDS_PN = "150";
"RFU4":   PN = "220"  !CDS_PN = "220";
"RFU5":   PN = "231"  !CDS_PN = "231";
"RFU6":   PN = "232"  !CDS_PN = "232";
"VIN_MGMT":   PN = "3"  !CDS_PN = "3";
BODY = "SCONN288_DDR506112002KQ","I537": #LOCATION = "J1" !CDS_LOCATION = "J1" &SEC = "2" #&CDS_SEC = "2";
"DQS0_A_C":   PN = "12"  !CDS_PN = "12";
"DQS0_A_T":   PN = "11"  !CDS_PN = "11";
"DQS0_B_C":   PN = "105"  !CDS_PN = "105";
"DQS0_B_T":   PN = "104"  !CDS_PN = "104";
"DQS1_A_C":   PN = "23"  !CDS_PN = "23";
"DQS1_A_T":   PN = "22"  !CDS_PN = "22";
"DQS1_B_C":   PN = "116"  !CDS_PN = "116";
"DQS1_B_T":   PN = "115"  !CDS_PN = "115";
"DQS2_A_C":   PN = "34"  !CDS_PN = "34";
"DQS2_A_T":   PN = "33"  !CDS_PN = "33";
"DQS2_B_C":   PN = "127"  !CDS_PN = "127";
"DQS2_B_T":   PN = "126"  !CDS_PN = "126";
"DQS3_A_C":   PN = "45"  !CDS_PN = "45";
"DQS3_A_T":   PN = "44"  !CDS_PN = "44";
"DQS3_B_C":   PN = "138"  !CDS_PN = "138";
"DQS3_B_T":   PN = "137"  !CDS_PN = "137";
"DQS4_A_C":   PN = "56"  !CDS_PN = "56";
"DQS4_A_T":   PN = "55"  !CDS_PN = "55";
"DQS4_B_C":   PN = "238"  !CDS_PN = "238";
"DQS4_B_T":   PN = "239"  !CDS_PN = "239";
"DQS5_A_C||TDQS5_A_C||DQS5_A_T||TDQS5_A_T":   PN = "156"  !CDS_PN = "156";
"DQS5_A_T||TDQS5_A_T":   PN = "157"  !CDS_PN = "157";
"DQS5_B_C||TDQS5_B_C":   PN = "249"  !CDS_PN = "249";
"DQS5_B_T||TDQS5_B_T":   PN = "250"  !CDS_PN = "250";
"DQS6_A_C||TDQS6_A_C||DQS6_A_T||TDQS6_A_T":   PN = "167"  !CDS_PN = "167";
"DQS6_A_T||TDQS6_A_T":   PN = "168"  !CDS_PN = "168";
"DQS6_B_C||TDQS6_B_C":   PN = "260"  !CDS_PN = "260";
"DQS6_B_T||TDQS6_B_T":   PN = "261"  !CDS_PN = "261";
"DQS7_A_C||TDQS7_A_C":   PN = "178"  !CDS_PN = "178";
"DQS7_A_T||TDQS7_A_T":   PN = "179"  !CDS_PN = "179";
"DQS7_B_C||TDQS7_B_C":   PN = "271"  !CDS_PN = "271";
"DQS7_B_T||TDQS7_B_T":   PN = "272"  !CDS_PN = "272";
"DQS8_A_C||TDQS8_A_C":   PN = "189"  !CDS_PN = "189";
"DQS8_A_T||TDQS8_A_T":   PN = "190"  !CDS_PN = "190";
"DQS8_B_C||TDQS8_B_C":   PN = "282"  !CDS_PN = "282";
"DQS8_B_T||TDQS8_B_T":   PN = "283"  !CDS_PN = "283";
"DQS9_A_C||TDQS9_A_C":   PN = "200"  !CDS_PN = "200";
"DQS9_A_T||TDQS9_A_T":   PN = "201"  !CDS_PN = "201";
"DQS9_B_C||TDQS9_B_C":   PN = "94"  !CDS_PN = "94";
"DQS9_B_T||TDQS9_B_T||DBI4_B_N":   PN = "93"  !CDS_PN = "93";
BODY = "SCONN288_DDR506112002KQ","I538": #LOCATION = "J1" !CDS_LOCATION = "J1" &SEC = "3" #&CDS_SEC = "3";
"G1":   PN = "G1"  !CDS_PN = "G1";
"G2":   PN = "G2"  !CDS_PN = "G2";
"G3":   PN = "G3"  !CDS_PN = "G3";
"VIN_BULK0":   PN = "1"  !CDS_PN = "1";
"VIN_BULK1":   PN = "145"  !CDS_PN = "145";
"VIN_BULK2":   PN = "146"  !CDS_PN = "146";
"VSS0":   PN = "6"  !CDS_PN = "6";
"VSS1":   PN = "8"  !CDS_PN = "8";
"VSS2":   PN = "10"  !CDS_PN = "10";
"VSS3":   PN = "13"  !CDS_PN = "13";
"VSS4":   PN = "15"  !CDS_PN = "15";
"VSS5":   PN = "17"  !CDS_PN = "17";
"VSS6":   PN = "19"  !CDS_PN = "19";
"VSS7":   PN = "21"  !CDS_PN = "21";
"VSS8":   PN = "24"  !CDS_PN = "24";
"VSS9":   PN = "26"  !CDS_PN = "26";
"VSS10":   PN = "28"  !CDS_PN = "28";
"VSS11":   PN = "30"  !CDS_PN = "30";
"VSS12":   PN = "32"  !CDS_PN = "32";
"VSS13":   PN = "35"  !CDS_PN = "35";
"VSS14":   PN = "37"  !CDS_PN = "37";
"VSS15":   PN = "39"  !CDS_PN = "39";
"VSS16":   PN = "41"  !CDS_PN = "41";
"VSS17":   PN = "43"  !CDS_PN = "43";
"VSS18":   PN = "46"  !CDS_PN = "46";
"VSS19":   PN = "48"  !CDS_PN = "48";
"VSS20":   PN = "50"  !CDS_PN = "50";
"VSS21":   PN = "52"  !CDS_PN = "52";
"VSS22":   PN = "54"  !CDS_PN = "54";
"VSS23":   PN = "57"  !CDS_PN = "57";
"VSS24":   PN = "59"  !CDS_PN = "59";
"VSS25":   PN = "61"  !CDS_PN = "61";
"VSS26":   PN = "63"  !CDS_PN = "63";
"VSS27":   PN = "65"  !CDS_PN = "65";
"VSS28":   PN = "67"  !CDS_PN = "67";
"VSS29":   PN = "69"  !CDS_PN = "69";
"VSS30":   PN = "71"  !CDS_PN = "71";
"VSS31":   PN = "73"  !CDS_PN = "73";
"VSS32":   PN = "75"  !CDS_PN = "75";
"VSS33":   PN = "77"  !CDS_PN = "77";
"VSS34":   PN = "79"  !CDS_PN = "79";
"VSS35":   PN = "81"  !CDS_PN = "81";
"VSS36":   PN = "83"  !CDS_PN = "83";
"VSS37":   PN = "85"  !CDS_PN = "85";
"VSS38":   PN = "88"  !CDS_PN = "88";
"VSS39":   PN = "90"  !CDS_PN = "90";
"VSS40":   PN = "92"  !CDS_PN = "92";
"VSS41":   PN = "95"  !CDS_PN = "95";
"VSS42":   PN = "97"  !CDS_PN = "97";
"VSS43":   PN = "99"  !CDS_PN = "99";
"VSS44":   PN = "101"  !CDS_PN = "101";
"VSS45":   PN = "103"  !CDS_PN = "103";
"VSS46":   PN = "106"  !CDS_PN = "106";
"VSS47":   PN = "108"  !CDS_PN = "108";
"VSS48":   PN = "110"  !CDS_PN = "110";
"VSS49":   PN = "112"  !CDS_PN = "112";
"VSS50":   PN = "114"  !CDS_PN = "114";
"VSS51":   PN = "117"  !CDS_PN = "117";
"VSS52":   PN = "119"  !CDS_PN = "119";
"VSS53":   PN = "121"  !CDS_PN = "121";
"VSS54":   PN = "123"  !CDS_PN = "123";
"VSS55":   PN = "125"  !CDS_PN = "125";
"VSS56":   PN = "128"  !CDS_PN = "128";
"VSS57":   PN = "130"  !CDS_PN = "130";
"VSS58":   PN = "132"  !CDS_PN = "132";
"VSS59":   PN = "134"  !CDS_PN = "134";
"VSS60":   PN = "136"  !CDS_PN = "136";
"VSS61":   PN = "139"  !CDS_PN = "139";
"VSS62":   PN = "141"  !CDS_PN = "141";
"VSS63":   PN = "143"  !CDS_PN = "143";
"VSS64":   PN = "151"  !CDS_PN = "151";
"VSS65":   PN = "153"  !CDS_PN = "153";
"VSS66":   PN = "155"  !CDS_PN = "155";
"VSS67":   PN = "158"  !CDS_PN = "158";
"VSS68":   PN = "160"  !CDS_PN = "160";
"VSS69":   PN = "162"  !CDS_PN = "162";
"VSS70":   PN = "164"  !CDS_PN = "164";
"VSS71":   PN = "166"  !CDS_PN = "166";
"VSS72":   PN = "169"  !CDS_PN = "169";
"VSS73":   PN = "171"  !CDS_PN = "171";
"VSS74":   PN = "173"  !CDS_PN = "173";
"VSS75":   PN = "175"  !CDS_PN = "175";
"VSS76":   PN = "177"  !CDS_PN = "177";
"VSS77":   PN = "180"  !CDS_PN = "180";
"VSS78":   PN = "182"  !CDS_PN = "182";
"VSS79":   PN = "184"  !CDS_PN = "184";
"VSS80":   PN = "186"  !CDS_PN = "186";
"VSS81":   PN = "188"  !CDS_PN = "188";
"VSS82":   PN = "191"  !CDS_PN = "191";
"VSS83":   PN = "193"  !CDS_PN = "193";
"VSS84":   PN = "195"  !CDS_PN = "195";
"VSS85":   PN = "197"  !CDS_PN = "197";
"VSS86":   PN = "199"  !CDS_PN = "199";
"VSS87":   PN = "202"  !CDS_PN = "202";
"VSS88":   PN = "204"  !CDS_PN = "204";
"VSS89":   PN = "206"  !CDS_PN = "206";
"VSS90":   PN = "208"  !CDS_PN = "208";
"VSS91":   PN = "210"  !CDS_PN = "210";
"VSS92":   PN = "212"  !CDS_PN = "212";
"VSS93":   PN = "214"  !CDS_PN = "214";
"VSS94":   PN = "216"  !CDS_PN = "216";
"VSS95":   PN = "219"  !CDS_PN = "219";
"VSS96":   PN = "222"  !CDS_PN = "222";
"VSS97":   PN = "224"  !CDS_PN = "224";
"VSS98":   PN = "226"  !CDS_PN = "226";
"VSS99":   PN = "228"  !CDS_PN = "228";
"VSS100":   PN = "230"  !CDS_PN = "230";
"VSS101":   PN = "233"  !CDS_PN = "233";
"VSS102":   PN = "235"  !CDS_PN = "235";
"VSS103":   PN = "237"  !CDS_PN = "237";
"VSS104":   PN = "240"  !CDS_PN = "240";
"VSS105":   PN = "242"  !CDS_PN = "242";
"VSS106":   PN = "244"  !CDS_PN = "244";
"VSS107":   PN = "246"  !CDS_PN = "246";
"VSS108":   PN = "248"  !CDS_PN = "248";
"VSS109":   PN = "251"  !CDS_PN = "251";
"VSS110":   PN = "253"  !CDS_PN = "253";
"VSS111":   PN = "255"  !CDS_PN = "255";
"VSS112":   PN = "257"  !CDS_PN = "257";
"VSS113":   PN = "259"  !CDS_PN = "259";
"VSS114":   PN = "262"  !CDS_PN = "262";
"VSS115":   PN = "264"  !CDS_PN = "264";
"VSS116":   PN = "266"  !CDS_PN = "266";
"VSS117":   PN = "268"  !CDS_PN = "268";
"VSS118":   PN = "270"  !CDS_PN = "270";
"VSS119":   PN = "273"  !CDS_PN = "273";
"VSS120":   PN = "275"  !CDS_PN = "275";
"VSS121":   PN = "277"  !CDS_PN = "277";
"VSS122":   PN = "279"  !CDS_PN = "279";
"VSS123":   PN = "281"  !CDS_PN = "281";
"VSS124":   PN = "284"  !CDS_PN = "284";
"VSS125":   PN = "286"  !CDS_PN = "286";
"VSS126":   PN = "288"  !CDS_PN = "288";
BODY = "Q_RES","I539": #LOCATION = "R1568" !CDS_LOCATION = "R1568" &SEC = "1" #&CDS_SEC = "1";
"A":   PN = "1"  !CDS_PN = "1";
"B":   PN = "2"  !CDS_PN = "2";
BODY = "Q_RES","I540": #LOCATION = "R8037" !CDS_LOCATION = "R8037" &SEC = "1" #&CDS_SEC = "1";
"A":   PN = "1"  !CDS_PN = "1";
"B":   PN = "2"  !CDS_PN = "2";
BODY = "Q_RES","I544": #LOCATION = "R8080" !CDS_LOCATION = "R8080" &SEC = "1" #&CDS_SEC = "1";
"A":   PN = "1"  !CDS_PN = "1";
"B":   PN = "2"  !CDS_PN = "2";
BODY = "Q_RES","I545": #LOCATION = "R8081" !CDS_LOCATION = "R8081" &SEC = "1" #&CDS_SEC = "1";
"A":   PN = "1"  !CDS_PN = "1";
"B":   PN = "2"  !CDS_PN = "2";
BODY = "Q_RES","I547": #LOCATION = "R8082" !CDS_LOCATION = "R8082" &SEC = "1" #&CDS_SEC = "1";
"A":   PN = "1"  !CDS_PN = "1";
"B":   PN = "2"  !CDS_PN = "2";
BODY = "SCHOTTKY_12","I549": #LOCATION = "D8003" !CDS_LOCATION = "D8003" #SEC = "1" !CDS_SEC = "1";
"A":   PN = "1"  !CDS_PN = "1";
"C":   PN = "2"  !CDS_PN = "2";
BODY = "Q_RES","I554": #LOCATION = "R1674" !CDS_LOCATION = "R1674" #SEC = "1" !CDS_SEC = "1";
"A":   PN = "1"  !CDS_PN = "1";
"B":   PN = "2"  !CDS_PN = "2";
DRAWING = "@t6g_mb_lib.t6g(sch_1):page86";
BODY = "Q_RES","I349": #LOCATION = "R761" !CDS_LOCATION = "R761" &SEC = "1" #&CDS_SEC = "1";
"A":   PN = "1"  !CDS_PN = "1";
"B":   PN = "2"  !CDS_PN = "2";
BODY = "SCONN288_DDR506112002KQ","I350": #LOCATION = "J15" !CDS_LOCATION = "J15" &SEC = "1" #&CDS_SEC = "1";
"ALERT_N":   PN = "62"  !CDS_PN = "62";
"CA0_A":   PN = "66"  !CDS_PN = "66";
"CA0_B":   PN = "76"  !CDS_PN = "76";
"CA1_A":   PN = "211"  !CDS_PN = "211";
"CA1_B":   PN = "221"  !CDS_PN = "221";
"CA2_A":   PN = "68"  !CDS_PN = "68";
"CA2_B":   PN = "78"  !CDS_PN = "78";
"CA3_A":   PN = "213"  !CDS_PN = "213";
"CA3_B":   PN = "223"  !CDS_PN = "223";
"CA4_A":   PN = "70"  !CDS_PN = "70";
"CA4_B":   PN = "80"  !CDS_PN = "80";
"CA5_A":   PN = "215"  !CDS_PN = "215";
"CA5_B":   PN = "225"  !CDS_PN = "225";
"CA6_A":   PN = "72"  !CDS_PN = "72";
"CA6_B":   PN = "82"  !CDS_PN = "82";
"CB0_A":   PN = "51"  !CDS_PN = "51";
"CB0_B":   PN = "96"  !CDS_PN = "96";
"CB1_A":   PN = "53"  !CDS_PN = "53";
"CB1_B":   PN = "98"  !CDS_PN = "98";
"CB2_A":   PN = "196"  !CDS_PN = "196";
"CB2_B":   PN = "241"  !CDS_PN = "241";
"CB3_A":   PN = "198"  !CDS_PN = "198";
"CB3_B":   PN = "243"  !CDS_PN = "243";
"CB4_A":   PN = "58"  !CDS_PN = "58";
"CB4_B":   PN = "89"  !CDS_PN = "89";
"CB5_A":   PN = "60"  !CDS_PN = "60";
"CB5_B":   PN = "91"  !CDS_PN = "91";
"CB6_A":   PN = "203"  !CDS_PN = "203";
"CB6_B":   PN = "234"  !CDS_PN = "234";
"CB7_A":   PN = "205"  !CDS_PN = "205";
"CB7_B":   PN = "236"  !CDS_PN = "236";
"CK_C":   PN = "218"  !CDS_PN = "218";
"CK_T":   PN = "217"  !CDS_PN = "217";
"CS0_A_N":   PN = "64"  !CDS_PN = "64";
"CS0_B_N":   PN = "84"  !CDS_PN = "84";
"CS1_A_N":   PN = "209"  !CDS_PN = "209";
"CS1_B_N":   PN = "229"  !CDS_PN = "229";
"DQ0_A":   PN = "7"  !CDS_PN = "7";
"DQ0_B":   PN = "100"  !CDS_PN = "100";
"DQ1_A":   PN = "9"  !CDS_PN = "9";
"DQ1_B":   PN = "102"  !CDS_PN = "102";
"DQ2_A":   PN = "152"  !CDS_PN = "152";
"DQ2_B":   PN = "245"  !CDS_PN = "245";
"DQ3_A":   PN = "154"  !CDS_PN = "154";
"DQ3_B":   PN = "247"  !CDS_PN = "247";
"DQ4_A":   PN = "14"  !CDS_PN = "14";
"DQ4_B":   PN = "107"  !CDS_PN = "107";
"DQ5_A":   PN = "16"  !CDS_PN = "16";
"DQ5_B":   PN = "109"  !CDS_PN = "109";
"DQ6_A":   PN = "159"  !CDS_PN = "159";
"DQ6_B":   PN = "252"  !CDS_PN = "252";
"DQ7_A":   PN = "161"  !CDS_PN = "161";
"DQ7_B":   PN = "254"  !CDS_PN = "254";
"DQ8_A":   PN = "18"  !CDS_PN = "18";
"DQ8_B":   PN = "111"  !CDS_PN = "111";
"DQ9_A":   PN = "20"  !CDS_PN = "20";
"DQ9_B":   PN = "113"  !CDS_PN = "113";
"DQ10_A":   PN = "163"  !CDS_PN = "163";
"DQ10_B":   PN = "256"  !CDS_PN = "256";
"DQ11_A":   PN = "165"  !CDS_PN = "165";
"DQ11_B":   PN = "258"  !CDS_PN = "258";
"DQ12_A":   PN = "25"  !CDS_PN = "25";
"DQ12_B":   PN = "118"  !CDS_PN = "118";
"DQ13_A":   PN = "27"  !CDS_PN = "27";
"DQ13_B":   PN = "120"  !CDS_PN = "120";
"DQ14_A":   PN = "170"  !CDS_PN = "170";
"DQ14_B":   PN = "263"  !CDS_PN = "263";
"DQ15_A":   PN = "172"  !CDS_PN = "172";
"DQ15_B":   PN = "265"  !CDS_PN = "265";
"DQ16_A":   PN = "29"  !CDS_PN = "29";
"DQ16_B":   PN = "122"  !CDS_PN = "122";
"DQ17_A":   PN = "31"  !CDS_PN = "31";
"DQ17_B":   PN = "124"  !CDS_PN = "124";
"DQ18_A":   PN = "174"  !CDS_PN = "174";
"DQ18_B":   PN = "267"  !CDS_PN = "267";
"DQ19_A":   PN = "176"  !CDS_PN = "176";
"DQ19_B":   PN = "269"  !CDS_PN = "269";
"DQ20_A":   PN = "36"  !CDS_PN = "36";
"DQ20_B":   PN = "129"  !CDS_PN = "129";
"DQ21_A":   PN = "38"  !CDS_PN = "38";
"DQ21_B":   PN = "131"  !CDS_PN = "131";
"DQ22_A":   PN = "181"  !CDS_PN = "181";
"DQ22_B":   PN = "274"  !CDS_PN = "274";
"DQ23_A":   PN = "183"  !CDS_PN = "183";
"DQ23_B":   PN = "276"  !CDS_PN = "276";
"DQ24_A":   PN = "40"  !CDS_PN = "40";
"DQ24_B":   PN = "133"  !CDS_PN = "133";
"DQ25_A":   PN = "42"  !CDS_PN = "42";
"DQ25_B":   PN = "135"  !CDS_PN = "135";
"DQ26_A":   PN = "185"  !CDS_PN = "185";
"DQ26_B":   PN = "278"  !CDS_PN = "278";
"DQ27_A":   PN = "187"  !CDS_PN = "187";
"DQ27_B":   PN = "280"  !CDS_PN = "280";
"DQ28_A":   PN = "47"  !CDS_PN = "47";
"DQ28_B":   PN = "140"  !CDS_PN = "140";
"DQ29_A":   PN = "49"  !CDS_PN = "49";
"DQ29_B":   PN = "142"  !CDS_PN = "142";
"DQ30_A":   PN = "192"  !CDS_PN = "192";
"DQ30_B":   PN = "285"  !CDS_PN = "285";
"DQ31_A":   PN = "194"  !CDS_PN = "194";
"DQ31_B":   PN = "287"  !CDS_PN = "287";
"HAS":   PN = "148"  !CDS_PN = "148";
"HSCL":   PN = "4"  !CDS_PN = "4";
"HSDA":   PN = "5"  !CDS_PN = "5";
"LBD||RSP_A_N":   PN = "86"  !CDS_PN = "86";
"LBS||RSP_B_N":   PN = "87"  !CDS_PN = "87";
"PAR_A":   PN = "74"  !CDS_PN = "74";
"PAR_B":   PN = "227"  !CDS_PN = "227";
"PWR_GOOD||FAIL_N":   PN = "147"  !CDS_PN = "147";
"RESET_N":   PN = "207"  !CDS_PN = "207";
"RFU0":   PN = "2"  !CDS_PN = "2";
"RFU1":   PN = "144"  !CDS_PN = "144";
"RFU2":   PN = "149"  !CDS_PN = "149";
"RFU3":   PN = "150"  !CDS_PN = "150";
"RFU4":   PN = "220"  !CDS_PN = "220";
"RFU5":   PN = "231"  !CDS_PN = "231";
"RFU6":   PN = "232"  !CDS_PN = "232";
"VIN_MGMT":   PN = "3"  !CDS_PN = "3";
BODY = "SCONN288_DDR506112002KQ","I352": #LOCATION = "J15" !CDS_LOCATION = "J15" &SEC = "3" #&CDS_SEC = "3";
"G1":   PN = "G1"  !CDS_PN = "G1";
"G2":   PN = "G2"  !CDS_PN = "G2";
"G3":   PN = "G3"  !CDS_PN = "G3";
"VIN_BULK0":   PN = "1"  !CDS_PN = "1";
"VIN_BULK1":   PN = "145"  !CDS_PN = "145";
"VIN_BULK2":   PN = "146"  !CDS_PN = "146";
"VSS0":   PN = "6"  !CDS_PN = "6";
"VSS1":   PN = "8"  !CDS_PN = "8";
"VSS2":   PN = "10"  !CDS_PN = "10";
"VSS3":   PN = "13"  !CDS_PN = "13";
"VSS4":   PN = "15"  !CDS_PN = "15";
"VSS5":   PN = "17"  !CDS_PN = "17";
"VSS6":   PN = "19"  !CDS_PN = "19";
"VSS7":   PN = "21"  !CDS_PN = "21";
"VSS8":   PN = "24"  !CDS_PN = "24";
"VSS9":   PN = "26"  !CDS_PN = "26";
"VSS10":   PN = "28"  !CDS_PN = "28";
"VSS11":   PN = "30"  !CDS_PN = "30";
"VSS12":   PN = "32"  !CDS_PN = "32";
"VSS13":   PN = "35"  !CDS_PN = "35";
"VSS14":   PN = "37"  !CDS_PN = "37";
"VSS15":   PN = "39"  !CDS_PN = "39";
"VSS16":   PN = "41"  !CDS_PN = "41";
"VSS17":   PN = "43"  !CDS_PN = "43";
"VSS18":   PN = "46"  !CDS_PN = "46";
"VSS19":   PN = "48"  !CDS_PN = "48";
"VSS20":   PN = "50"  !CDS_PN = "50";
"VSS21":   PN = "52"  !CDS_PN = "52";
"VSS22":   PN = "54"  !CDS_PN = "54";
"VSS23":   PN = "57"  !CDS_PN = "57";
"VSS24":   PN = "59"  !CDS_PN = "59";
"VSS25":   PN = "61"  !CDS_PN = "61";
"VSS26":   PN = "63"  !CDS_PN = "63";
"VSS27":   PN = "65"  !CDS_PN = "65";
"VSS28":   PN = "67"  !CDS_PN = "67";
"VSS29":   PN = "69"  !CDS_PN = "69";
"VSS30":   PN = "71"  !CDS_PN = "71";
"VSS31":   PN = "73"  !CDS_PN = "73";
"VSS32":   PN = "75"  !CDS_PN = "75";
"VSS33":   PN = "77"  !CDS_PN = "77";
"VSS34":   PN = "79"  !CDS_PN = "79";
"VSS35":   PN = "81"  !CDS_PN = "81";
"VSS36":   PN = "83"  !CDS_PN = "83";
"VSS37":   PN = "85"  !CDS_PN = "85";
"VSS38":   PN = "88"  !CDS_PN = "88";
"VSS39":   PN = "90"  !CDS_PN = "90";
"VSS40":   PN = "92"  !CDS_PN = "92";
"VSS41":   PN = "95"  !CDS_PN = "95";
"VSS42":   PN = "97"  !CDS_PN = "97";
"VSS43":   PN = "99"  !CDS_PN = "99";
"VSS44":   PN = "101"  !CDS_PN = "101";
"VSS45":   PN = "103"  !CDS_PN = "103";
"VSS46":   PN = "106"  !CDS_PN = "106";
"VSS47":   PN = "108"  !CDS_PN = "108";
"VSS48":   PN = "110"  !CDS_PN = "110";
"VSS49":   PN = "112"  !CDS_PN = "112";
"VSS50":   PN = "114"  !CDS_PN = "114";
"VSS51":   PN = "117"  !CDS_PN = "117";
"VSS52":   PN = "119"  !CDS_PN = "119";
"VSS53":   PN = "121"  !CDS_PN = "121";
"VSS54":   PN = "123"  !CDS_PN = "123";
"VSS55":   PN = "125"  !CDS_PN = "125";
"VSS56":   PN = "128"  !CDS_PN = "128";
"VSS57":   PN = "130"  !CDS_PN = "130";
"VSS58":   PN = "132"  !CDS_PN = "132";
"VSS59":   PN = "134"  !CDS_PN = "134";
"VSS60":   PN = "136"  !CDS_PN = "136";
"VSS61":   PN = "139"  !CDS_PN = "139";
"VSS62":   PN = "141"  !CDS_PN = "141";
"VSS63":   PN = "143"  !CDS_PN = "143";
"VSS64":   PN = "151"  !CDS_PN = "151";
"VSS65":   PN = "153"  !CDS_PN = "153";
"VSS66":   PN = "155"  !CDS_PN = "155";
"VSS67":   PN = "158"  !CDS_PN = "158";
"VSS68":   PN = "160"  !CDS_PN = "160";
"VSS69":   PN = "162"  !CDS_PN = "162";
"VSS70":   PN = "164"  !CDS_PN = "164";
"VSS71":   PN = "166"  !CDS_PN = "166";
"VSS72":   PN = "169"  !CDS_PN = "169";
"VSS73":   PN = "171"  !CDS_PN = "171";
"VSS74":   PN = "173"  !CDS_PN = "173";
"VSS75":   PN = "175"  !CDS_PN = "175";
"VSS76":   PN = "177"  !CDS_PN = "177";
"VSS77":   PN = "180"  !CDS_PN = "180";
"VSS78":   PN = "182"  !CDS_PN = "182";
"VSS79":   PN = "184"  !CDS_PN = "184";
"VSS80":   PN = "186"  !CDS_PN = "186";
"VSS81":   PN = "188"  !CDS_PN = "188";
"VSS82":   PN = "191"  !CDS_PN = "191";
"VSS83":   PN = "193"  !CDS_PN = "193";
"VSS84":   PN = "195"  !CDS_PN = "195";
"VSS85":   PN = "197"  !CDS_PN = "197";
"VSS86":   PN = "199"  !CDS_PN = "199";
"VSS87":   PN = "202"  !CDS_PN = "202";
"VSS88":   PN = "204"  !CDS_PN = "204";
"VSS89":   PN = "206"  !CDS_PN = "206";
"VSS90":   PN = "208"  !CDS_PN = "208";
"VSS91":   PN = "210"  !CDS_PN = "210";
"VSS92":   PN = "212"  !CDS_PN = "212";
"VSS93":   PN = "214"  !CDS_PN = "214";
"VSS94":   PN = "216"  !CDS_PN = "216";
"VSS95":   PN = "219"  !CDS_PN = "219";
"VSS96":   PN = "222"  !CDS_PN = "222";
"VSS97":   PN = "224"  !CDS_PN = "224";
"VSS98":   PN = "226"  !CDS_PN = "226";
"VSS99":   PN = "228"  !CDS_PN = "228";
"VSS100":   PN = "230"  !CDS_PN = "230";
"VSS101":   PN = "233"  !CDS_PN = "233";
"VSS102":   PN = "235"  !CDS_PN = "235";
"VSS103":   PN = "237"  !CDS_PN = "237";
"VSS104":   PN = "240"  !CDS_PN = "240";
"VSS105":   PN = "242"  !CDS_PN = "242";
"VSS106":   PN = "244"  !CDS_PN = "244";
"VSS107":   PN = "246"  !CDS_PN = "246";
"VSS108":   PN = "248"  !CDS_PN = "248";
"VSS109":   PN = "251"  !CDS_PN = "251";
"VSS110":   PN = "253"  !CDS_PN = "253";
"VSS111":   PN = "255"  !CDS_PN = "255";
"VSS112":   PN = "257"  !CDS_PN = "257";
"VSS113":   PN = "259"  !CDS_PN = "259";
"VSS114":   PN = "262"  !CDS_PN = "262";
"VSS115":   PN = "264"  !CDS_PN = "264";
"VSS116":   PN = "266"  !CDS_PN = "266";
"VSS117":   PN = "268"  !CDS_PN = "268";
"VSS118":   PN = "270"  !CDS_PN = "270";
"VSS119":   PN = "273"  !CDS_PN = "273";
"VSS120":   PN = "275"  !CDS_PN = "275";
"VSS121":   PN = "277"  !CDS_PN = "277";
"VSS122":   PN = "279"  !CDS_PN = "279";
"VSS123":   PN = "281"  !CDS_PN = "281";
"VSS124":   PN = "284"  !CDS_PN = "284";
"VSS125":   PN = "286"  !CDS_PN = "286";
"VSS126":   PN = "288"  !CDS_PN = "288";
BODY = "Q_CAP","I362": #LOCATION = "C92" !CDS_LOCATION = "C92" &SEC = "1" #&CDS_SEC = "1";
"A":   PN = "1"  !CDS_PN = "1";
"B":   PN = "2"  !CDS_PN = "2";
BODY = "Q_RES","I364": #LOCATION = "R292" !CDS_LOCATION = "R292" &SEC = "1" #&CDS_SEC = "1";
"A":   PN = "1"  !CDS_PN = "1";
"B":   PN = "2"  !CDS_PN = "2";
BODY = "Q_RES","I365": #LOCATION = "R90" !CDS_LOCATION = "R90" &SEC = "1" #&CDS_SEC = "1";
"A":   PN = "1"  !CDS_PN = "1";
"B":   PN = "2"  !CDS_PN = "2";
BODY = "SCONN288_DDR506112002KQ","I367": #LOCATION = "J15" !CDS_LOCATION = "J15" &SEC = "2" #&CDS_SEC = "2";
"DQS0_A_C":   PN = "12"  !CDS_PN = "12";
"DQS0_A_T":   PN = "11"  !CDS_PN = "11";
"DQS0_B_C":   PN = "105"  !CDS_PN = "105";
"DQS0_B_T":   PN = "104"  !CDS_PN = "104";
"DQS1_A_C":   PN = "23"  !CDS_PN = "23";
"DQS1_A_T":   PN = "22"  !CDS_PN = "22";
"DQS1_B_C":   PN = "116"  !CDS_PN = "116";
"DQS1_B_T":   PN = "115"  !CDS_PN = "115";
"DQS2_A_C":   PN = "34"  !CDS_PN = "34";
"DQS2_A_T":   PN = "33"  !CDS_PN = "33";
"DQS2_B_C":   PN = "127"  !CDS_PN = "127";
"DQS2_B_T":   PN = "126"  !CDS_PN = "126";
"DQS3_A_C":   PN = "45"  !CDS_PN = "45";
"DQS3_A_T":   PN = "44"  !CDS_PN = "44";
"DQS3_B_C":   PN = "138"  !CDS_PN = "138";
"DQS3_B_T":   PN = "137"  !CDS_PN = "137";
"DQS4_A_C":   PN = "56"  !CDS_PN = "56";
"DQS4_A_T":   PN = "55"  !CDS_PN = "55";
"DQS4_B_C":   PN = "238"  !CDS_PN = "238";
"DQS4_B_T":   PN = "239"  !CDS_PN = "239";
"DQS5_A_C||TDQS5_A_C||DQS5_A_T||TDQS5_A_T":   PN = "156"  !CDS_PN = "156";
"DQS5_A_T||TDQS5_A_T":   PN = "157"  !CDS_PN = "157";
"DQS5_B_C||TDQS5_B_C":   PN = "249"  !CDS_PN = "249";
"DQS5_B_T||TDQS5_B_T":   PN = "250"  !CDS_PN = "250";
"DQS6_A_C||TDQS6_A_C||DQS6_A_T||TDQS6_A_T":   PN = "167"  !CDS_PN = "167";
"DQS6_A_T||TDQS6_A_T":   PN = "168"  !CDS_PN = "168";
"DQS6_B_C||TDQS6_B_C":   PN = "260"  !CDS_PN = "260";
"DQS6_B_T||TDQS6_B_T":   PN = "261"  !CDS_PN = "261";
"DQS7_A_C||TDQS7_A_C":   PN = "178"  !CDS_PN = "178";
"DQS7_A_T||TDQS7_A_T":   PN = "179"  !CDS_PN = "179";
"DQS7_B_C||TDQS7_B_C":   PN = "271"  !CDS_PN = "271";
"DQS7_B_T||TDQS7_B_T":   PN = "272"  !CDS_PN = "272";
"DQS8_A_C||TDQS8_A_C":   PN = "189"  !CDS_PN = "189";
"DQS8_A_T||TDQS8_A_T":   PN = "190"  !CDS_PN = "190";
"DQS8_B_C||TDQS8_B_C":   PN = "282"  !CDS_PN = "282";
"DQS8_B_T||TDQS8_B_T":   PN = "283"  !CDS_PN = "283";
"DQS9_A_C||TDQS9_A_C":   PN = "200"  !CDS_PN = "200";
"DQS9_A_T||TDQS9_A_T":   PN = "201"  !CDS_PN = "201";
"DQS9_B_C||TDQS9_B_C":   PN = "94"  !CDS_PN = "94";
"DQS9_B_T||TDQS9_B_T||DBI4_B_N":   PN = "93"  !CDS_PN = "93";
BODY = "Q_CAP","I369": #LOCATION = "C143" !CDS_LOCATION = "C143" &SEC = "1" #&CDS_SEC = "1";
"A":   PN = "1"  !CDS_PN = "1";
"B":   PN = "2"  !CDS_PN = "2";
BODY = "Q_CAP","I370": #LOCATION = "C145" !CDS_LOCATION = "C145" &SEC = "1" #&CDS_SEC = "1";
"A":   PN = "1"  !CDS_PN = "1";
"B":   PN = "2"  !CDS_PN = "2";
BODY = "Q_RES","I372": #LOCATION = "R1569" !CDS_LOCATION = "R1569" &SEC = "1" #&CDS_SEC = "1";
"A":   PN = "1"  !CDS_PN = "1";
"B":   PN = "2"  !CDS_PN = "2";
BODY = "Q_RES","I373": #LOCATION = "R1675" !CDS_LOCATION = "R1675" #SEC = "1" !CDS_SEC = "1";
"A":   PN = "1"  !CDS_PN = "1";
"B":   PN = "2"  !CDS_PN = "2";
DRAWING = "@t6g_mb_lib.t6g(sch_1):page87";
BODY = "Q_RES","I349": #LOCATION = "R762" !CDS_LOCATION = "R762" &SEC = "1" #&CDS_SEC = "1";
"A":   PN = "1"  !CDS_PN = "1";
"B":   PN = "2"  !CDS_PN = "2";
BODY = "SCONN288_DDR506112002KQ","I350": #LOCATION = "J17" !CDS_LOCATION = "J17" &SEC = "1" #&CDS_SEC = "1";
"ALERT_N":   PN = "62"  !CDS_PN = "62";
"CA0_A":   PN = "66"  !CDS_PN = "66";
"CA0_B":   PN = "76"  !CDS_PN = "76";
"CA1_A":   PN = "211"  !CDS_PN = "211";
"CA1_B":   PN = "221"  !CDS_PN = "221";
"CA2_A":   PN = "68"  !CDS_PN = "68";
"CA2_B":   PN = "78"  !CDS_PN = "78";
"CA3_A":   PN = "213"  !CDS_PN = "213";
"CA3_B":   PN = "223"  !CDS_PN = "223";
"CA4_A":   PN = "70"  !CDS_PN = "70";
"CA4_B":   PN = "80"  !CDS_PN = "80";
"CA5_A":   PN = "215"  !CDS_PN = "215";
"CA5_B":   PN = "225"  !CDS_PN = "225";
"CA6_A":   PN = "72"  !CDS_PN = "72";
"CA6_B":   PN = "82"  !CDS_PN = "82";
"CB0_A":   PN = "51"  !CDS_PN = "51";
"CB0_B":   PN = "96"  !CDS_PN = "96";
"CB1_A":   PN = "53"  !CDS_PN = "53";
"CB1_B":   PN = "98"  !CDS_PN = "98";
"CB2_A":   PN = "196"  !CDS_PN = "196";
"CB2_B":   PN = "241"  !CDS_PN = "241";
"CB3_A":   PN = "198"  !CDS_PN = "198";
"CB3_B":   PN = "243"  !CDS_PN = "243";
"CB4_A":   PN = "58"  !CDS_PN = "58";
"CB4_B":   PN = "89"  !CDS_PN = "89";
"CB5_A":   PN = "60"  !CDS_PN = "60";
"CB5_B":   PN = "91"  !CDS_PN = "91";
"CB6_A":   PN = "203"  !CDS_PN = "203";
"CB6_B":   PN = "234"  !CDS_PN = "234";
"CB7_A":   PN = "205"  !CDS_PN = "205";
"CB7_B":   PN = "236"  !CDS_PN = "236";
"CK_C":   PN = "218"  !CDS_PN = "218";
"CK_T":   PN = "217"  !CDS_PN = "217";
"CS0_A_N":   PN = "64"  !CDS_PN = "64";
"CS0_B_N":   PN = "84"  !CDS_PN = "84";
"CS1_A_N":   PN = "209"  !CDS_PN = "209";
"CS1_B_N":   PN = "229"  !CDS_PN = "229";
"DQ0_A":   PN = "7"  !CDS_PN = "7";
"DQ0_B":   PN = "100"  !CDS_PN = "100";
"DQ1_A":   PN = "9"  !CDS_PN = "9";
"DQ1_B":   PN = "102"  !CDS_PN = "102";
"DQ2_A":   PN = "152"  !CDS_PN = "152";
"DQ2_B":   PN = "245"  !CDS_PN = "245";
"DQ3_A":   PN = "154"  !CDS_PN = "154";
"DQ3_B":   PN = "247"  !CDS_PN = "247";
"DQ4_A":   PN = "14"  !CDS_PN = "14";
"DQ4_B":   PN = "107"  !CDS_PN = "107";
"DQ5_A":   PN = "16"  !CDS_PN = "16";
"DQ5_B":   PN = "109"  !CDS_PN = "109";
"DQ6_A":   PN = "159"  !CDS_PN = "159";
"DQ6_B":   PN = "252"  !CDS_PN = "252";
"DQ7_A":   PN = "161"  !CDS_PN = "161";
"DQ7_B":   PN = "254"  !CDS_PN = "254";
"DQ8_A":   PN = "18"  !CDS_PN = "18";
"DQ8_B":   PN = "111"  !CDS_PN = "111";
"DQ9_A":   PN = "20"  !CDS_PN = "20";
"DQ9_B":   PN = "113"  !CDS_PN = "113";
"DQ10_A":   PN = "163"  !CDS_PN = "163";
"DQ10_B":   PN = "256"  !CDS_PN = "256";
"DQ11_A":   PN = "165"  !CDS_PN = "165";
"DQ11_B":   PN = "258"  !CDS_PN = "258";
"DQ12_A":   PN = "25"  !CDS_PN = "25";
"DQ12_B":   PN = "118"  !CDS_PN = "118";
"DQ13_A":   PN = "27"  !CDS_PN = "27";
"DQ13_B":   PN = "120"  !CDS_PN = "120";
"DQ14_A":   PN = "170"  !CDS_PN = "170";
"DQ14_B":   PN = "263"  !CDS_PN = "263";
"DQ15_A":   PN = "172"  !CDS_PN = "172";
"DQ15_B":   PN = "265"  !CDS_PN = "265";
"DQ16_A":   PN = "29"  !CDS_PN = "29";
"DQ16_B":   PN = "122"  !CDS_PN = "122";
"DQ17_A":   PN = "31"  !CDS_PN = "31";
"DQ17_B":   PN = "124"  !CDS_PN = "124";
"DQ18_A":   PN = "174"  !CDS_PN = "174";
"DQ18_B":   PN = "267"  !CDS_PN = "267";
"DQ19_A":   PN = "176"  !CDS_PN = "176";
"DQ19_B":   PN = "269"  !CDS_PN = "269";
"DQ20_A":   PN = "36"  !CDS_PN = "36";
"DQ20_B":   PN = "129"  !CDS_PN = "129";
"DQ21_A":   PN = "38"  !CDS_PN = "38";
"DQ21_B":   PN = "131"  !CDS_PN = "131";
"DQ22_A":   PN = "181"  !CDS_PN = "181";
"DQ22_B":   PN = "274"  !CDS_PN = "274";
"DQ23_A":   PN = "183"  !CDS_PN = "183";
"DQ23_B":   PN = "276"  !CDS_PN = "276";
"DQ24_A":   PN = "40"  !CDS_PN = "40";
"DQ24_B":   PN = "133"  !CDS_PN = "133";
"DQ25_A":   PN = "42"  !CDS_PN = "42";
"DQ25_B":   PN = "135"  !CDS_PN = "135";
"DQ26_A":   PN = "185"  !CDS_PN = "185";
"DQ26_B":   PN = "278"  !CDS_PN = "278";
"DQ27_A":   PN = "187"  !CDS_PN = "187";
"DQ27_B":   PN = "280"  !CDS_PN = "280";
"DQ28_A":   PN = "47"  !CDS_PN = "47";
"DQ28_B":   PN = "140"  !CDS_PN = "140";
"DQ29_A":   PN = "49"  !CDS_PN = "49";
"DQ29_B":   PN = "142"  !CDS_PN = "142";
"DQ30_A":   PN = "192"  !CDS_PN = "192";
"DQ30_B":   PN = "285"  !CDS_PN = "285";
"DQ31_A":   PN = "194"  !CDS_PN = "194";
"DQ31_B":   PN = "287"  !CDS_PN = "287";
"HAS":   PN = "148"  !CDS_PN = "148";
"HSCL":   PN = "4"  !CDS_PN = "4";
"HSDA":   PN = "5"  !CDS_PN = "5";
"LBD||RSP_A_N":   PN = "86"  !CDS_PN = "86";
"LBS||RSP_B_N":   PN = "87"  !CDS_PN = "87";
"PAR_A":   PN = "74"  !CDS_PN = "74";
"PAR_B":   PN = "227"  !CDS_PN = "227";
"PWR_GOOD||FAIL_N":   PN = "147"  !CDS_PN = "147";
"RESET_N":   PN = "207"  !CDS_PN = "207";
"RFU0":   PN = "2"  !CDS_PN = "2";
"RFU1":   PN = "144"  !CDS_PN = "144";
"RFU2":   PN = "149"  !CDS_PN = "149";
"RFU3":   PN = "150"  !CDS_PN = "150";
"RFU4":   PN = "220"  !CDS_PN = "220";
"RFU5":   PN = "231"  !CDS_PN = "231";
"RFU6":   PN = "232"  !CDS_PN = "232";
"VIN_MGMT":   PN = "3"  !CDS_PN = "3";
BODY = "SCONN288_DDR506112002KQ","I352": #LOCATION = "J17" !CDS_LOCATION = "J17" &SEC = "3" #&CDS_SEC = "3";
"G1":   PN = "G1"  !CDS_PN = "G1";
"G2":   PN = "G2"  !CDS_PN = "G2";
"G3":   PN = "G3"  !CDS_PN = "G3";
"VIN_BULK0":   PN = "1"  !CDS_PN = "1";
"VIN_BULK1":   PN = "145"  !CDS_PN = "145";
"VIN_BULK2":   PN = "146"  !CDS_PN = "146";
"VSS0":   PN = "6"  !CDS_PN = "6";
"VSS1":   PN = "8"  !CDS_PN = "8";
"VSS2":   PN = "10"  !CDS_PN = "10";
"VSS3":   PN = "13"  !CDS_PN = "13";
"VSS4":   PN = "15"  !CDS_PN = "15";
"VSS5":   PN = "17"  !CDS_PN = "17";
"VSS6":   PN = "19"  !CDS_PN = "19";
"VSS7":   PN = "21"  !CDS_PN = "21";
"VSS8":   PN = "24"  !CDS_PN = "24";
"VSS9":   PN = "26"  !CDS_PN = "26";
"VSS10":   PN = "28"  !CDS_PN = "28";
"VSS11":   PN = "30"  !CDS_PN = "30";
"VSS12":   PN = "32"  !CDS_PN = "32";
"VSS13":   PN = "35"  !CDS_PN = "35";
"VSS14":   PN = "37"  !CDS_PN = "37";
"VSS15":   PN = "39"  !CDS_PN = "39";
"VSS16":   PN = "41"  !CDS_PN = "41";
"VSS17":   PN = "43"  !CDS_PN = "43";
"VSS18":   PN = "46"  !CDS_PN = "46";
"VSS19":   PN = "48"  !CDS_PN = "48";
"VSS20":   PN = "50"  !CDS_PN = "50";
"VSS21":   PN = "52"  !CDS_PN = "52";
"VSS22":   PN = "54"  !CDS_PN = "54";
"VSS23":   PN = "57"  !CDS_PN = "57";
"VSS24":   PN = "59"  !CDS_PN = "59";
"VSS25":   PN = "61"  !CDS_PN = "61";
"VSS26":   PN = "63"  !CDS_PN = "63";
"VSS27":   PN = "65"  !CDS_PN = "65";
"VSS28":   PN = "67"  !CDS_PN = "67";
"VSS29":   PN = "69"  !CDS_PN = "69";
"VSS30":   PN = "71"  !CDS_PN = "71";
"VSS31":   PN = "73"  !CDS_PN = "73";
"VSS32":   PN = "75"  !CDS_PN = "75";
"VSS33":   PN = "77"  !CDS_PN = "77";
"VSS34":   PN = "79"  !CDS_PN = "79";
"VSS35":   PN = "81"  !CDS_PN = "81";
"VSS36":   PN = "83"  !CDS_PN = "83";
"VSS37":   PN = "85"  !CDS_PN = "85";
"VSS38":   PN = "88"  !CDS_PN = "88";
"VSS39":   PN = "90"  !CDS_PN = "90";
"VSS40":   PN = "92"  !CDS_PN = "92";
"VSS41":   PN = "95"  !CDS_PN = "95";
"VSS42":   PN = "97"  !CDS_PN = "97";
"VSS43":   PN = "99"  !CDS_PN = "99";
"VSS44":   PN = "101"  !CDS_PN = "101";
"VSS45":   PN = "103"  !CDS_PN = "103";
"VSS46":   PN = "106"  !CDS_PN = "106";
"VSS47":   PN = "108"  !CDS_PN = "108";
"VSS48":   PN = "110"  !CDS_PN = "110";
"VSS49":   PN = "112"  !CDS_PN = "112";
"VSS50":   PN = "114"  !CDS_PN = "114";
"VSS51":   PN = "117"  !CDS_PN = "117";
"VSS52":   PN = "119"  !CDS_PN = "119";
"VSS53":   PN = "121"  !CDS_PN = "121";
"VSS54":   PN = "123"  !CDS_PN = "123";
"VSS55":   PN = "125"  !CDS_PN = "125";
"VSS56":   PN = "128"  !CDS_PN = "128";
"VSS57":   PN = "130"  !CDS_PN = "130";
"VSS58":   PN = "132"  !CDS_PN = "132";
"VSS59":   PN = "134"  !CDS_PN = "134";
"VSS60":   PN = "136"  !CDS_PN = "136";
"VSS61":   PN = "139"  !CDS_PN = "139";
"VSS62":   PN = "141"  !CDS_PN = "141";
"VSS63":   PN = "143"  !CDS_PN = "143";
"VSS64":   PN = "151"  !CDS_PN = "151";
"VSS65":   PN = "153"  !CDS_PN = "153";
"VSS66":   PN = "155"  !CDS_PN = "155";
"VSS67":   PN = "158"  !CDS_PN = "158";
"VSS68":   PN = "160"  !CDS_PN = "160";
"VSS69":   PN = "162"  !CDS_PN = "162";
"VSS70":   PN = "164"  !CDS_PN = "164";
"VSS71":   PN = "166"  !CDS_PN = "166";
"VSS72":   PN = "169"  !CDS_PN = "169";
"VSS73":   PN = "171"  !CDS_PN = "171";
"VSS74":   PN = "173"  !CDS_PN = "173";
"VSS75":   PN = "175"  !CDS_PN = "175";
"VSS76":   PN = "177"  !CDS_PN = "177";
"VSS77":   PN = "180"  !CDS_PN = "180";
"VSS78":   PN = "182"  !CDS_PN = "182";
"VSS79":   PN = "184"  !CDS_PN = "184";
"VSS80":   PN = "186"  !CDS_PN = "186";
"VSS81":   PN = "188"  !CDS_PN = "188";
"VSS82":   PN = "191"  !CDS_PN = "191";
"VSS83":   PN = "193"  !CDS_PN = "193";
"VSS84":   PN = "195"  !CDS_PN = "195";
"VSS85":   PN = "197"  !CDS_PN = "197";
"VSS86":   PN = "199"  !CDS_PN = "199";
"VSS87":   PN = "202"  !CDS_PN = "202";
"VSS88":   PN = "204"  !CDS_PN = "204";
"VSS89":   PN = "206"  !CDS_PN = "206";
"VSS90":   PN = "208"  !CDS_PN = "208";
"VSS91":   PN = "210"  !CDS_PN = "210";
"VSS92":   PN = "212"  !CDS_PN = "212";
"VSS93":   PN = "214"  !CDS_PN = "214";
"VSS94":   PN = "216"  !CDS_PN = "216";
"VSS95":   PN = "219"  !CDS_PN = "219";
"VSS96":   PN = "222"  !CDS_PN = "222";
"VSS97":   PN = "224"  !CDS_PN = "224";
"VSS98":   PN = "226"  !CDS_PN = "226";
"VSS99":   PN = "228"  !CDS_PN = "228";
"VSS100":   PN = "230"  !CDS_PN = "230";
"VSS101":   PN = "233"  !CDS_PN = "233";
"VSS102":   PN = "235"  !CDS_PN = "235";
"VSS103":   PN = "237"  !CDS_PN = "237";
"VSS104":   PN = "240"  !CDS_PN = "240";
"VSS105":   PN = "242"  !CDS_PN = "242";
"VSS106":   PN = "244"  !CDS_PN = "244";
"VSS107":   PN = "246"  !CDS_PN = "246";
"VSS108":   PN = "248"  !CDS_PN = "248";
"VSS109":   PN = "251"  !CDS_PN = "251";
"VSS110":   PN = "253"  !CDS_PN = "253";
"VSS111":   PN = "255"  !CDS_PN = "255";
"VSS112":   PN = "257"  !CDS_PN = "257";
"VSS113":   PN = "259"  !CDS_PN = "259";
"VSS114":   PN = "262"  !CDS_PN = "262";
"VSS115":   PN = "264"  !CDS_PN = "264";
"VSS116":   PN = "266"  !CDS_PN = "266";
"VSS117":   PN = "268"  !CDS_PN = "268";
"VSS118":   PN = "270"  !CDS_PN = "270";
"VSS119":   PN = "273"  !CDS_PN = "273";
"VSS120":   PN = "275"  !CDS_PN = "275";
"VSS121":   PN = "277"  !CDS_PN = "277";
"VSS122":   PN = "279"  !CDS_PN = "279";
"VSS123":   PN = "281"  !CDS_PN = "281";
"VSS124":   PN = "284"  !CDS_PN = "284";
"VSS125":   PN = "286"  !CDS_PN = "286";
"VSS126":   PN = "288"  !CDS_PN = "288";
BODY = "Q_CAP","I362": #LOCATION = "C96" !CDS_LOCATION = "C96" &SEC = "1" #&CDS_SEC = "1";
"A":   PN = "1"  !CDS_PN = "1";
"B":   PN = "2"  !CDS_PN = "2";
BODY = "Q_RES","I364": #LOCATION = "R293" !CDS_LOCATION = "R293" &SEC = "1" #&CDS_SEC = "1";
"A":   PN = "1"  !CDS_PN = "1";
"B":   PN = "2"  !CDS_PN = "2";
BODY = "Q_RES","I365": #LOCATION = "R91" !CDS_LOCATION = "R91" &SEC = "1" #&CDS_SEC = "1";
"A":   PN = "1"  !CDS_PN = "1";
"B":   PN = "2"  !CDS_PN = "2";
BODY = "SCONN288_DDR506112002KQ","I411": #LOCATION = "J17" !CDS_LOCATION = "J17" &SEC = "2" #&CDS_SEC = "2";
"DQS0_A_C":   PN = "12"  !CDS_PN = "12";
"DQS0_A_T":   PN = "11"  !CDS_PN = "11";
"DQS0_B_C":   PN = "105"  !CDS_PN = "105";
"DQS0_B_T":   PN = "104"  !CDS_PN = "104";
"DQS1_A_C":   PN = "23"  !CDS_PN = "23";
"DQS1_A_T":   PN = "22"  !CDS_PN = "22";
"DQS1_B_C":   PN = "116"  !CDS_PN = "116";
"DQS1_B_T":   PN = "115"  !CDS_PN = "115";
"DQS2_A_C":   PN = "34"  !CDS_PN = "34";
"DQS2_A_T":   PN = "33"  !CDS_PN = "33";
"DQS2_B_C":   PN = "127"  !CDS_PN = "127";
"DQS2_B_T":   PN = "126"  !CDS_PN = "126";
"DQS3_A_C":   PN = "45"  !CDS_PN = "45";
"DQS3_A_T":   PN = "44"  !CDS_PN = "44";
"DQS3_B_C":   PN = "138"  !CDS_PN = "138";
"DQS3_B_T":   PN = "137"  !CDS_PN = "137";
"DQS4_A_C":   PN = "56"  !CDS_PN = "56";
"DQS4_A_T":   PN = "55"  !CDS_PN = "55";
"DQS4_B_C":   PN = "238"  !CDS_PN = "238";
"DQS4_B_T":   PN = "239"  !CDS_PN = "239";
"DQS5_A_C||TDQS5_A_C||DQS5_A_T||TDQS5_A_T":   PN = "156"  !CDS_PN = "156";
"DQS5_A_T||TDQS5_A_T":   PN = "157"  !CDS_PN = "157";
"DQS5_B_C||TDQS5_B_C":   PN = "249"  !CDS_PN = "249";
"DQS5_B_T||TDQS5_B_T":   PN = "250"  !CDS_PN = "250";
"DQS6_A_C||TDQS6_A_C||DQS6_A_T||TDQS6_A_T":   PN = "167"  !CDS_PN = "167";
"DQS6_A_T||TDQS6_A_T":   PN = "168"  !CDS_PN = "168";
"DQS6_B_C||TDQS6_B_C":   PN = "260"  !CDS_PN = "260";
"DQS6_B_T||TDQS6_B_T":   PN = "261"  !CDS_PN = "261";
"DQS7_A_C||TDQS7_A_C":   PN = "178"  !CDS_PN = "178";
"DQS7_A_T||TDQS7_A_T":   PN = "179"  !CDS_PN = "179";
"DQS7_B_C||TDQS7_B_C":   PN = "271"  !CDS_PN = "271";
"DQS7_B_T||TDQS7_B_T":   PN = "272"  !CDS_PN = "272";
"DQS8_A_C||TDQS8_A_C":   PN = "189"  !CDS_PN = "189";
"DQS8_A_T||TDQS8_A_T":   PN = "190"  !CDS_PN = "190";
"DQS8_B_C||TDQS8_B_C":   PN = "282"  !CDS_PN = "282";
"DQS8_B_T||TDQS8_B_T":   PN = "283"  !CDS_PN = "283";
"DQS9_A_C||TDQS9_A_C":   PN = "200"  !CDS_PN = "200";
"DQS9_A_T||TDQS9_A_T":   PN = "201"  !CDS_PN = "201";
"DQS9_B_C||TDQS9_B_C":   PN = "94"  !CDS_PN = "94";
"DQS9_B_T||TDQS9_B_T||DBI4_B_N":   PN = "93"  !CDS_PN = "93";
BODY = "Q_CAP","I413": #LOCATION = "C146" !CDS_LOCATION = "C146" &SEC = "1" #&CDS_SEC = "1";
"A":   PN = "1"  !CDS_PN = "1";
"B":   PN = "2"  !CDS_PN = "2";
BODY = "Q_CAP","I414": #LOCATION = "C147" !CDS_LOCATION = "C147" &SEC = "1" #&CDS_SEC = "1";
"A":   PN = "1"  !CDS_PN = "1";
"B":   PN = "2"  !CDS_PN = "2";
BODY = "Q_RES","I417": #LOCATION = "R1570" !CDS_LOCATION = "R1570" &SEC = "1" #&CDS_SEC = "1";
"A":   PN = "1"  !CDS_PN = "1";
"B":   PN = "2"  !CDS_PN = "2";
BODY = "Q_RES","I418": #LOCATION = "R1677" !CDS_LOCATION = "R1677" &SEC = "1" #&CDS_SEC = "1";
"A":   PN = "1"  !CDS_PN = "1";
"B":   PN = "2"  !CDS_PN = "2";
DRAWING = "@t6g_mb_lib.t6g(sch_1):page88";
BODY = "Q_RES","I349": #LOCATION = "R763" !CDS_LOCATION = "R763" &SEC = "1" #&CDS_SEC = "1";
"A":   PN = "1"  !CDS_PN = "1";
"B":   PN = "2"  !CDS_PN = "2";
BODY = "SCONN288_DDR506112002KQ","I350": #LOCATION = "J19" !CDS_LOCATION = "J19" &SEC = "1" #&CDS_SEC = "1";
"ALERT_N":   PN = "62"  !CDS_PN = "62";
"CA0_A":   PN = "66"  !CDS_PN = "66";
"CA0_B":   PN = "76"  !CDS_PN = "76";
"CA1_A":   PN = "211"  !CDS_PN = "211";
"CA1_B":   PN = "221"  !CDS_PN = "221";
"CA2_A":   PN = "68"  !CDS_PN = "68";
"CA2_B":   PN = "78"  !CDS_PN = "78";
"CA3_A":   PN = "213"  !CDS_PN = "213";
"CA3_B":   PN = "223"  !CDS_PN = "223";
"CA4_A":   PN = "70"  !CDS_PN = "70";
"CA4_B":   PN = "80"  !CDS_PN = "80";
"CA5_A":   PN = "215"  !CDS_PN = "215";
"CA5_B":   PN = "225"  !CDS_PN = "225";
"CA6_A":   PN = "72"  !CDS_PN = "72";
"CA6_B":   PN = "82"  !CDS_PN = "82";
"CB0_A":   PN = "51"  !CDS_PN = "51";
"CB0_B":   PN = "96"  !CDS_PN = "96";
"CB1_A":   PN = "53"  !CDS_PN = "53";
"CB1_B":   PN = "98"  !CDS_PN = "98";
"CB2_A":   PN = "196"  !CDS_PN = "196";
"CB2_B":   PN = "241"  !CDS_PN = "241";
"CB3_A":   PN = "198"  !CDS_PN = "198";
"CB3_B":   PN = "243"  !CDS_PN = "243";
"CB4_A":   PN = "58"  !CDS_PN = "58";
"CB4_B":   PN = "89"  !CDS_PN = "89";
"CB5_A":   PN = "60"  !CDS_PN = "60";
"CB5_B":   PN = "91"  !CDS_PN = "91";
"CB6_A":   PN = "203"  !CDS_PN = "203";
"CB6_B":   PN = "234"  !CDS_PN = "234";
"CB7_A":   PN = "205"  !CDS_PN = "205";
"CB7_B":   PN = "236"  !CDS_PN = "236";
"CK_C":   PN = "218"  !CDS_PN = "218";
"CK_T":   PN = "217"  !CDS_PN = "217";
"CS0_A_N":   PN = "64"  !CDS_PN = "64";
"CS0_B_N":   PN = "84"  !CDS_PN = "84";
"CS1_A_N":   PN = "209"  !CDS_PN = "209";
"CS1_B_N":   PN = "229"  !CDS_PN = "229";
"DQ0_A":   PN = "7"  !CDS_PN = "7";
"DQ0_B":   PN = "100"  !CDS_PN = "100";
"DQ1_A":   PN = "9"  !CDS_PN = "9";
"DQ1_B":   PN = "102"  !CDS_PN = "102";
"DQ2_A":   PN = "152"  !CDS_PN = "152";
"DQ2_B":   PN = "245"  !CDS_PN = "245";
"DQ3_A":   PN = "154"  !CDS_PN = "154";
"DQ3_B":   PN = "247"  !CDS_PN = "247";
"DQ4_A":   PN = "14"  !CDS_PN = "14";
"DQ4_B":   PN = "107"  !CDS_PN = "107";
"DQ5_A":   PN = "16"  !CDS_PN = "16";
"DQ5_B":   PN = "109"  !CDS_PN = "109";
"DQ6_A":   PN = "159"  !CDS_PN = "159";
"DQ6_B":   PN = "252"  !CDS_PN = "252";
"DQ7_A":   PN = "161"  !CDS_PN = "161";
"DQ7_B":   PN = "254"  !CDS_PN = "254";
"DQ8_A":   PN = "18"  !CDS_PN = "18";
"DQ8_B":   PN = "111"  !CDS_PN = "111";
"DQ9_A":   PN = "20"  !CDS_PN = "20";
"DQ9_B":   PN = "113"  !CDS_PN = "113";
"DQ10_A":   PN = "163"  !CDS_PN = "163";
"DQ10_B":   PN = "256"  !CDS_PN = "256";
"DQ11_A":   PN = "165"  !CDS_PN = "165";
"DQ11_B":   PN = "258"  !CDS_PN = "258";
"DQ12_A":   PN = "25"  !CDS_PN = "25";
"DQ12_B":   PN = "118"  !CDS_PN = "118";
"DQ13_A":   PN = "27"  !CDS_PN = "27";
"DQ13_B":   PN = "120"  !CDS_PN = "120";
"DQ14_A":   PN = "170"  !CDS_PN = "170";
"DQ14_B":   PN = "263"  !CDS_PN = "263";
"DQ15_A":   PN = "172"  !CDS_PN = "172";
"DQ15_B":   PN = "265"  !CDS_PN = "265";
"DQ16_A":   PN = "29"  !CDS_PN = "29";
"DQ16_B":   PN = "122"  !CDS_PN = "122";
"DQ17_A":   PN = "31"  !CDS_PN = "31";
"DQ17_B":   PN = "124"  !CDS_PN = "124";
"DQ18_A":   PN = "174"  !CDS_PN = "174";
"DQ18_B":   PN = "267"  !CDS_PN = "267";
"DQ19_A":   PN = "176"  !CDS_PN = "176";
"DQ19_B":   PN = "269"  !CDS_PN = "269";
"DQ20_A":   PN = "36"  !CDS_PN = "36";
"DQ20_B":   PN = "129"  !CDS_PN = "129";
"DQ21_A":   PN = "38"  !CDS_PN = "38";
"DQ21_B":   PN = "131"  !CDS_PN = "131";
"DQ22_A":   PN = "181"  !CDS_PN = "181";
"DQ22_B":   PN = "274"  !CDS_PN = "274";
"DQ23_A":   PN = "183"  !CDS_PN = "183";
"DQ23_B":   PN = "276"  !CDS_PN = "276";
"DQ24_A":   PN = "40"  !CDS_PN = "40";
"DQ24_B":   PN = "133"  !CDS_PN = "133";
"DQ25_A":   PN = "42"  !CDS_PN = "42";
"DQ25_B":   PN = "135"  !CDS_PN = "135";
"DQ26_A":   PN = "185"  !CDS_PN = "185";
"DQ26_B":   PN = "278"  !CDS_PN = "278";
"DQ27_A":   PN = "187"  !CDS_PN = "187";
"DQ27_B":   PN = "280"  !CDS_PN = "280";
"DQ28_A":   PN = "47"  !CDS_PN = "47";
"DQ28_B":   PN = "140"  !CDS_PN = "140";
"DQ29_A":   PN = "49"  !CDS_PN = "49";
"DQ29_B":   PN = "142"  !CDS_PN = "142";
"DQ30_A":   PN = "192"  !CDS_PN = "192";
"DQ30_B":   PN = "285"  !CDS_PN = "285";
"DQ31_A":   PN = "194"  !CDS_PN = "194";
"DQ31_B":   PN = "287"  !CDS_PN = "287";
"HAS":   PN = "148"  !CDS_PN = "148";
"HSCL":   PN = "4"  !CDS_PN = "4";
"HSDA":   PN = "5"  !CDS_PN = "5";
"LBD||RSP_A_N":   PN = "86"  !CDS_PN = "86";
"LBS||RSP_B_N":   PN = "87"  !CDS_PN = "87";
"PAR_A":   PN = "74"  !CDS_PN = "74";
"PAR_B":   PN = "227"  !CDS_PN = "227";
"PWR_GOOD||FAIL_N":   PN = "147"  !CDS_PN = "147";
"RESET_N":   PN = "207"  !CDS_PN = "207";
"RFU0":   PN = "2"  !CDS_PN = "2";
"RFU1":   PN = "144"  !CDS_PN = "144";
"RFU2":   PN = "149"  !CDS_PN = "149";
"RFU3":   PN = "150"  !CDS_PN = "150";
"RFU4":   PN = "220"  !CDS_PN = "220";
"RFU5":   PN = "231"  !CDS_PN = "231";
"RFU6":   PN = "232"  !CDS_PN = "232";
"VIN_MGMT":   PN = "3"  !CDS_PN = "3";
BODY = "SCONN288_DDR506112002KQ","I352": #LOCATION = "J19" !CDS_LOCATION = "J19" &SEC = "3" #&CDS_SEC = "3";
"G1":   PN = "G1"  !CDS_PN = "G1";
"G2":   PN = "G2"  !CDS_PN = "G2";
"G3":   PN = "G3"  !CDS_PN = "G3";
"VIN_BULK0":   PN = "1"  !CDS_PN = "1";
"VIN_BULK1":   PN = "145"  !CDS_PN = "145";
"VIN_BULK2":   PN = "146"  !CDS_PN = "146";
"VSS0":   PN = "6"  !CDS_PN = "6";
"VSS1":   PN = "8"  !CDS_PN = "8";
"VSS2":   PN = "10"  !CDS_PN = "10";
"VSS3":   PN = "13"  !CDS_PN = "13";
"VSS4":   PN = "15"  !CDS_PN = "15";
"VSS5":   PN = "17"  !CDS_PN = "17";
"VSS6":   PN = "19"  !CDS_PN = "19";
"VSS7":   PN = "21"  !CDS_PN = "21";
"VSS8":   PN = "24"  !CDS_PN = "24";
"VSS9":   PN = "26"  !CDS_PN = "26";
"VSS10":   PN = "28"  !CDS_PN = "28";
"VSS11":   PN = "30"  !CDS_PN = "30";
"VSS12":   PN = "32"  !CDS_PN = "32";
"VSS13":   PN = "35"  !CDS_PN = "35";
"VSS14":   PN = "37"  !CDS_PN = "37";
"VSS15":   PN = "39"  !CDS_PN = "39";
"VSS16":   PN = "41"  !CDS_PN = "41";
"VSS17":   PN = "43"  !CDS_PN = "43";
"VSS18":   PN = "46"  !CDS_PN = "46";
"VSS19":   PN = "48"  !CDS_PN = "48";
"VSS20":   PN = "50"  !CDS_PN = "50";
"VSS21":   PN = "52"  !CDS_PN = "52";
"VSS22":   PN = "54"  !CDS_PN = "54";
"VSS23":   PN = "57"  !CDS_PN = "57";
"VSS24":   PN = "59"  !CDS_PN = "59";
"VSS25":   PN = "61"  !CDS_PN = "61";
"VSS26":   PN = "63"  !CDS_PN = "63";
"VSS27":   PN = "65"  !CDS_PN = "65";
"VSS28":   PN = "67"  !CDS_PN = "67";
"VSS29":   PN = "69"  !CDS_PN = "69";
"VSS30":   PN = "71"  !CDS_PN = "71";
"VSS31":   PN = "73"  !CDS_PN = "73";
"VSS32":   PN = "75"  !CDS_PN = "75";
"VSS33":   PN = "77"  !CDS_PN = "77";
"VSS34":   PN = "79"  !CDS_PN = "79";
"VSS35":   PN = "81"  !CDS_PN = "81";
"VSS36":   PN = "83"  !CDS_PN = "83";
"VSS37":   PN = "85"  !CDS_PN = "85";
"VSS38":   PN = "88"  !CDS_PN = "88";
"VSS39":   PN = "90"  !CDS_PN = "90";
"VSS40":   PN = "92"  !CDS_PN = "92";
"VSS41":   PN = "95"  !CDS_PN = "95";
"VSS42":   PN = "97"  !CDS_PN = "97";
"VSS43":   PN = "99"  !CDS_PN = "99";
"VSS44":   PN = "101"  !CDS_PN = "101";
"VSS45":   PN = "103"  !CDS_PN = "103";
"VSS46":   PN = "106"  !CDS_PN = "106";
"VSS47":   PN = "108"  !CDS_PN = "108";
"VSS48":   PN = "110"  !CDS_PN = "110";
"VSS49":   PN = "112"  !CDS_PN = "112";
"VSS50":   PN = "114"  !CDS_PN = "114";
"VSS51":   PN = "117"  !CDS_PN = "117";
"VSS52":   PN = "119"  !CDS_PN = "119";
"VSS53":   PN = "121"  !CDS_PN = "121";
"VSS54":   PN = "123"  !CDS_PN = "123";
"VSS55":   PN = "125"  !CDS_PN = "125";
"VSS56":   PN = "128"  !CDS_PN = "128";
"VSS57":   PN = "130"  !CDS_PN = "130";
"VSS58":   PN = "132"  !CDS_PN = "132";
"VSS59":   PN = "134"  !CDS_PN = "134";
"VSS60":   PN = "136"  !CDS_PN = "136";
"VSS61":   PN = "139"  !CDS_PN = "139";
"VSS62":   PN = "141"  !CDS_PN = "141";
"VSS63":   PN = "143"  !CDS_PN = "143";
"VSS64":   PN = "151"  !CDS_PN = "151";
"VSS65":   PN = "153"  !CDS_PN = "153";
"VSS66":   PN = "155"  !CDS_PN = "155";
"VSS67":   PN = "158"  !CDS_PN = "158";
"VSS68":   PN = "160"  !CDS_PN = "160";
"VSS69":   PN = "162"  !CDS_PN = "162";
"VSS70":   PN = "164"  !CDS_PN = "164";
"VSS71":   PN = "166"  !CDS_PN = "166";
"VSS72":   PN = "169"  !CDS_PN = "169";
"VSS73":   PN = "171"  !CDS_PN = "171";
"VSS74":   PN = "173"  !CDS_PN = "173";
"VSS75":   PN = "175"  !CDS_PN = "175";
"VSS76":   PN = "177"  !CDS_PN = "177";
"VSS77":   PN = "180"  !CDS_PN = "180";
"VSS78":   PN = "182"  !CDS_PN = "182";
"VSS79":   PN = "184"  !CDS_PN = "184";
"VSS80":   PN = "186"  !CDS_PN = "186";
"VSS81":   PN = "188"  !CDS_PN = "188";
"VSS82":   PN = "191"  !CDS_PN = "191";
"VSS83":   PN = "193"  !CDS_PN = "193";
"VSS84":   PN = "195"  !CDS_PN = "195";
"VSS85":   PN = "197"  !CDS_PN = "197";
"VSS86":   PN = "199"  !CDS_PN = "199";
"VSS87":   PN = "202"  !CDS_PN = "202";
"VSS88":   PN = "204"  !CDS_PN = "204";
"VSS89":   PN = "206"  !CDS_PN = "206";
"VSS90":   PN = "208"  !CDS_PN = "208";
"VSS91":   PN = "210"  !CDS_PN = "210";
"VSS92":   PN = "212"  !CDS_PN = "212";
"VSS93":   PN = "214"  !CDS_PN = "214";
"VSS94":   PN = "216"  !CDS_PN = "216";
"VSS95":   PN = "219"  !CDS_PN = "219";
"VSS96":   PN = "222"  !CDS_PN = "222";
"VSS97":   PN = "224"  !CDS_PN = "224";
"VSS98":   PN = "226"  !CDS_PN = "226";
"VSS99":   PN = "228"  !CDS_PN = "228";
"VSS100":   PN = "230"  !CDS_PN = "230";
"VSS101":   PN = "233"  !CDS_PN = "233";
"VSS102":   PN = "235"  !CDS_PN = "235";
"VSS103":   PN = "237"  !CDS_PN = "237";
"VSS104":   PN = "240"  !CDS_PN = "240";
"VSS105":   PN = "242"  !CDS_PN = "242";
"VSS106":   PN = "244"  !CDS_PN = "244";
"VSS107":   PN = "246"  !CDS_PN = "246";
"VSS108":   PN = "248"  !CDS_PN = "248";
"VSS109":   PN = "251"  !CDS_PN = "251";
"VSS110":   PN = "253"  !CDS_PN = "253";
"VSS111":   PN = "255"  !CDS_PN = "255";
"VSS112":   PN = "257"  !CDS_PN = "257";
"VSS113":   PN = "259"  !CDS_PN = "259";
"VSS114":   PN = "262"  !CDS_PN = "262";
"VSS115":   PN = "264"  !CDS_PN = "264";
"VSS116":   PN = "266"  !CDS_PN = "266";
"VSS117":   PN = "268"  !CDS_PN = "268";
"VSS118":   PN = "270"  !CDS_PN = "270";
"VSS119":   PN = "273"  !CDS_PN = "273";
"VSS120":   PN = "275"  !CDS_PN = "275";
"VSS121":   PN = "277"  !CDS_PN = "277";
"VSS122":   PN = "279"  !CDS_PN = "279";
"VSS123":   PN = "281"  !CDS_PN = "281";
"VSS124":   PN = "284"  !CDS_PN = "284";
"VSS125":   PN = "286"  !CDS_PN = "286";
"VSS126":   PN = "288"  !CDS_PN = "288";
BODY = "Q_CAP","I362": #LOCATION = "C100" !CDS_LOCATION = "C100" &SEC = "1" #&CDS_SEC = "1";
"A":   PN = "1"  !CDS_PN = "1";
"B":   PN = "2"  !CDS_PN = "2";
BODY = "Q_RES","I367": #LOCATION = "R92" !CDS_LOCATION = "R92" &SEC = "1" #&CDS_SEC = "1";
"A":   PN = "1"  !CDS_PN = "1";
"B":   PN = "2"  !CDS_PN = "2";
BODY = "Q_RES","I369": #LOCATION = "R294" !CDS_LOCATION = "R294" &SEC = "1" #&CDS_SEC = "1";
"A":   PN = "1"  !CDS_PN = "1";
"B":   PN = "2"  !CDS_PN = "2";
BODY = "SCONN288_DDR506112002KQ","I415": #LOCATION = "J19" !CDS_LOCATION = "J19" &SEC = "2" #&CDS_SEC = "2";
"DQS0_A_C":   PN = "12"  !CDS_PN = "12";
"DQS0_A_T":   PN = "11"  !CDS_PN = "11";
"DQS0_B_C":   PN = "105"  !CDS_PN = "105";
"DQS0_B_T":   PN = "104"  !CDS_PN = "104";
"DQS1_A_C":   PN = "23"  !CDS_PN = "23";
"DQS1_A_T":   PN = "22"  !CDS_PN = "22";
"DQS1_B_C":   PN = "116"  !CDS_PN = "116";
"DQS1_B_T":   PN = "115"  !CDS_PN = "115";
"DQS2_A_C":   PN = "34"  !CDS_PN = "34";
"DQS2_A_T":   PN = "33"  !CDS_PN = "33";
"DQS2_B_C":   PN = "127"  !CDS_PN = "127";
"DQS2_B_T":   PN = "126"  !CDS_PN = "126";
"DQS3_A_C":   PN = "45"  !CDS_PN = "45";
"DQS3_A_T":   PN = "44"  !CDS_PN = "44";
"DQS3_B_C":   PN = "138"  !CDS_PN = "138";
"DQS3_B_T":   PN = "137"  !CDS_PN = "137";
"DQS4_A_C":   PN = "56"  !CDS_PN = "56";
"DQS4_A_T":   PN = "55"  !CDS_PN = "55";
"DQS4_B_C":   PN = "238"  !CDS_PN = "238";
"DQS4_B_T":   PN = "239"  !CDS_PN = "239";
"DQS5_A_C||TDQS5_A_C||DQS5_A_T||TDQS5_A_T":   PN = "156"  !CDS_PN = "156";
"DQS5_A_T||TDQS5_A_T":   PN = "157"  !CDS_PN = "157";
"DQS5_B_C||TDQS5_B_C":   PN = "249"  !CDS_PN = "249";
"DQS5_B_T||TDQS5_B_T":   PN = "250"  !CDS_PN = "250";
"DQS6_A_C||TDQS6_A_C||DQS6_A_T||TDQS6_A_T":   PN = "167"  !CDS_PN = "167";
"DQS6_A_T||TDQS6_A_T":   PN = "168"  !CDS_PN = "168";
"DQS6_B_C||TDQS6_B_C":   PN = "260"  !CDS_PN = "260";
"DQS6_B_T||TDQS6_B_T":   PN = "261"  !CDS_PN = "261";
"DQS7_A_C||TDQS7_A_C":   PN = "178"  !CDS_PN = "178";
"DQS7_A_T||TDQS7_A_T":   PN = "179"  !CDS_PN = "179";
"DQS7_B_C||TDQS7_B_C":   PN = "271"  !CDS_PN = "271";
"DQS7_B_T||TDQS7_B_T":   PN = "272"  !CDS_PN = "272";
"DQS8_A_C||TDQS8_A_C":   PN = "189"  !CDS_PN = "189";
"DQS8_A_T||TDQS8_A_T":   PN = "190"  !CDS_PN = "190";
"DQS8_B_C||TDQS8_B_C":   PN = "282"  !CDS_PN = "282";
"DQS8_B_T||TDQS8_B_T":   PN = "283"  !CDS_PN = "283";
"DQS9_A_C||TDQS9_A_C":   PN = "200"  !CDS_PN = "200";
"DQS9_A_T||TDQS9_A_T":   PN = "201"  !CDS_PN = "201";
"DQS9_B_C||TDQS9_B_C":   PN = "94"  !CDS_PN = "94";
"DQS9_B_T||TDQS9_B_T||DBI4_B_N":   PN = "93"  !CDS_PN = "93";
BODY = "Q_CAP","I417": #LOCATION = "C149" !CDS_LOCATION = "C149" &SEC = "1" #&CDS_SEC = "1";
"A":   PN = "1"  !CDS_PN = "1";
"B":   PN = "2"  !CDS_PN = "2";
BODY = "Q_CAP","I418": #LOCATION = "C150" !CDS_LOCATION = "C150" &SEC = "1" #&CDS_SEC = "1";
"A":   PN = "1"  !CDS_PN = "1";
"B":   PN = "2"  !CDS_PN = "2";
BODY = "Q_RES","I421": #LOCATION = "R1" !CDS_LOCATION = "R1" &SEC = "1" #&CDS_SEC = "1";
"A":   PN = "1"  !CDS_PN = "1";
"B":   PN = "2"  !CDS_PN = "2";
BODY = "Q_RES","I422": #LOCATION = "R1676" !CDS_LOCATION = "R1676" #SEC = "1" !CDS_SEC = "1";
"A":   PN = "1"  !CDS_PN = "1";
"B":   PN = "2"  !CDS_PN = "2";
DRAWING = "@t6g_mb_lib.t6g(sch_1):page89";
BODY = "Q_RES","I331": #LOCATION = "R5" !CDS_LOCATION = "R5" #SEC = "1" !CDS_SEC = "1";
"A":   PN = "1"  !CDS_PN = "1";
"B":   PN = "2"  !CDS_PN = "2";
BODY = "SCONN288_DDR506112002KQ","I348": #LOCATION = "J21" !CDS_LOCATION = "J21" &SEC = "1" #&CDS_SEC = "1";
"ALERT_N":   PN = "62"  !CDS_PN = "62";
"CA0_A":   PN = "66"  !CDS_PN = "66";
"CA0_B":   PN = "76"  !CDS_PN = "76";
"CA1_A":   PN = "211"  !CDS_PN = "211";
"CA1_B":   PN = "221"  !CDS_PN = "221";
"CA2_A":   PN = "68"  !CDS_PN = "68";
"CA2_B":   PN = "78"  !CDS_PN = "78";
"CA3_A":   PN = "213"  !CDS_PN = "213";
"CA3_B":   PN = "223"  !CDS_PN = "223";
"CA4_A":   PN = "70"  !CDS_PN = "70";
"CA4_B":   PN = "80"  !CDS_PN = "80";
"CA5_A":   PN = "215"  !CDS_PN = "215";
"CA5_B":   PN = "225"  !CDS_PN = "225";
"CA6_A":   PN = "72"  !CDS_PN = "72";
"CA6_B":   PN = "82"  !CDS_PN = "82";
"CB0_A":   PN = "51"  !CDS_PN = "51";
"CB0_B":   PN = "96"  !CDS_PN = "96";
"CB1_A":   PN = "53"  !CDS_PN = "53";
"CB1_B":   PN = "98"  !CDS_PN = "98";
"CB2_A":   PN = "196"  !CDS_PN = "196";
"CB2_B":   PN = "241"  !CDS_PN = "241";
"CB3_A":   PN = "198"  !CDS_PN = "198";
"CB3_B":   PN = "243"  !CDS_PN = "243";
"CB4_A":   PN = "58"  !CDS_PN = "58";
"CB4_B":   PN = "89"  !CDS_PN = "89";
"CB5_A":   PN = "60"  !CDS_PN = "60";
"CB5_B":   PN = "91"  !CDS_PN = "91";
"CB6_A":   PN = "203"  !CDS_PN = "203";
"CB6_B":   PN = "234"  !CDS_PN = "234";
"CB7_A":   PN = "205"  !CDS_PN = "205";
"CB7_B":   PN = "236"  !CDS_PN = "236";
"CK_C":   PN = "218"  !CDS_PN = "218";
"CK_T":   PN = "217"  !CDS_PN = "217";
"CS0_A_N":   PN = "64"  !CDS_PN = "64";
"CS0_B_N":   PN = "84"  !CDS_PN = "84";
"CS1_A_N":   PN = "209"  !CDS_PN = "209";
"CS1_B_N":   PN = "229"  !CDS_PN = "229";
"DQ0_A":   PN = "7"  !CDS_PN = "7";
"DQ0_B":   PN = "100"  !CDS_PN = "100";
"DQ1_A":   PN = "9"  !CDS_PN = "9";
"DQ1_B":   PN = "102"  !CDS_PN = "102";
"DQ2_A":   PN = "152"  !CDS_PN = "152";
"DQ2_B":   PN = "245"  !CDS_PN = "245";
"DQ3_A":   PN = "154"  !CDS_PN = "154";
"DQ3_B":   PN = "247"  !CDS_PN = "247";
"DQ4_A":   PN = "14"  !CDS_PN = "14";
"DQ4_B":   PN = "107"  !CDS_PN = "107";
"DQ5_A":   PN = "16"  !CDS_PN = "16";
"DQ5_B":   PN = "109"  !CDS_PN = "109";
"DQ6_A":   PN = "159"  !CDS_PN = "159";
"DQ6_B":   PN = "252"  !CDS_PN = "252";
"DQ7_A":   PN = "161"  !CDS_PN = "161";
"DQ7_B":   PN = "254"  !CDS_PN = "254";
"DQ8_A":   PN = "18"  !CDS_PN = "18";
"DQ8_B":   PN = "111"  !CDS_PN = "111";
"DQ9_A":   PN = "20"  !CDS_PN = "20";
"DQ9_B":   PN = "113"  !CDS_PN = "113";
"DQ10_A":   PN = "163"  !CDS_PN = "163";
"DQ10_B":   PN = "256"  !CDS_PN = "256";
"DQ11_A":   PN = "165"  !CDS_PN = "165";
"DQ11_B":   PN = "258"  !CDS_PN = "258";
"DQ12_A":   PN = "25"  !CDS_PN = "25";
"DQ12_B":   PN = "118"  !CDS_PN = "118";
"DQ13_A":   PN = "27"  !CDS_PN = "27";
"DQ13_B":   PN = "120"  !CDS_PN = "120";
"DQ14_A":   PN = "170"  !CDS_PN = "170";
"DQ14_B":   PN = "263"  !CDS_PN = "263";
"DQ15_A":   PN = "172"  !CDS_PN = "172";
"DQ15_B":   PN = "265"  !CDS_PN = "265";
"DQ16_A":   PN = "29"  !CDS_PN = "29";
"DQ16_B":   PN = "122"  !CDS_PN = "122";
"DQ17_A":   PN = "31"  !CDS_PN = "31";
"DQ17_B":   PN = "124"  !CDS_PN = "124";
"DQ18_A":   PN = "174"  !CDS_PN = "174";
"DQ18_B":   PN = "267"  !CDS_PN = "267";
"DQ19_A":   PN = "176"  !CDS_PN = "176";
"DQ19_B":   PN = "269"  !CDS_PN = "269";
"DQ20_A":   PN = "36"  !CDS_PN = "36";
"DQ20_B":   PN = "129"  !CDS_PN = "129";
"DQ21_A":   PN = "38"  !CDS_PN = "38";
"DQ21_B":   PN = "131"  !CDS_PN = "131";
"DQ22_A":   PN = "181"  !CDS_PN = "181";
"DQ22_B":   PN = "274"  !CDS_PN = "274";
"DQ23_A":   PN = "183"  !CDS_PN = "183";
"DQ23_B":   PN = "276"  !CDS_PN = "276";
"DQ24_A":   PN = "40"  !CDS_PN = "40";
"DQ24_B":   PN = "133"  !CDS_PN = "133";
"DQ25_A":   PN = "42"  !CDS_PN = "42";
"DQ25_B":   PN = "135"  !CDS_PN = "135";
"DQ26_A":   PN = "185"  !CDS_PN = "185";
"DQ26_B":   PN = "278"  !CDS_PN = "278";
"DQ27_A":   PN = "187"  !CDS_PN = "187";
"DQ27_B":   PN = "280"  !CDS_PN = "280";
"DQ28_A":   PN = "47"  !CDS_PN = "47";
"DQ28_B":   PN = "140"  !CDS_PN = "140";
"DQ29_A":   PN = "49"  !CDS_PN = "49";
"DQ29_B":   PN = "142"  !CDS_PN = "142";
"DQ30_A":   PN = "192"  !CDS_PN = "192";
"DQ30_B":   PN = "285"  !CDS_PN = "285";
"DQ31_A":   PN = "194"  !CDS_PN = "194";
"DQ31_B":   PN = "287"  !CDS_PN = "287";
"HAS":   PN = "148"  !CDS_PN = "148";
"HSCL":   PN = "4"  !CDS_PN = "4";
"HSDA":   PN = "5"  !CDS_PN = "5";
"LBD||RSP_A_N":   PN = "86"  !CDS_PN = "86";
"LBS||RSP_B_N":   PN = "87"  !CDS_PN = "87";
"PAR_A":   PN = "74"  !CDS_PN = "74";
"PAR_B":   PN = "227"  !CDS_PN = "227";
"PWR_GOOD||FAIL_N":   PN = "147"  !CDS_PN = "147";
"RESET_N":   PN = "207"  !CDS_PN = "207";
"RFU0":   PN = "2"  !CDS_PN = "2";
"RFU1":   PN = "144"  !CDS_PN = "144";
"RFU2":   PN = "149"  !CDS_PN = "149";
"RFU3":   PN = "150"  !CDS_PN = "150";
"RFU4":   PN = "220"  !CDS_PN = "220";
"RFU5":   PN = "231"  !CDS_PN = "231";
"RFU6":   PN = "232"  !CDS_PN = "232";
"VIN_MGMT":   PN = "3"  !CDS_PN = "3";
BODY = "SCONN288_DDR506112002KQ","I350": #LOCATION = "J21" !CDS_LOCATION = "J21" &SEC = "3" #&CDS_SEC = "3";
"G1":   PN = "G1"  !CDS_PN = "G1";
"G2":   PN = "G2"  !CDS_PN = "G2";
"G3":   PN = "G3"  !CDS_PN = "G3";
"VIN_BULK0":   PN = "1"  !CDS_PN = "1";
"VIN_BULK1":   PN = "145"  !CDS_PN = "145";
"VIN_BULK2":   PN = "146"  !CDS_PN = "146";
"VSS0":   PN = "6"  !CDS_PN = "6";
"VSS1":   PN = "8"  !CDS_PN = "8";
"VSS2":   PN = "10"  !CDS_PN = "10";
"VSS3":   PN = "13"  !CDS_PN = "13";
"VSS4":   PN = "15"  !CDS_PN = "15";
"VSS5":   PN = "17"  !CDS_PN = "17";
"VSS6":   PN = "19"  !CDS_PN = "19";
"VSS7":   PN = "21"  !CDS_PN = "21";
"VSS8":   PN = "24"  !CDS_PN = "24";
"VSS9":   PN = "26"  !CDS_PN = "26";
"VSS10":   PN = "28"  !CDS_PN = "28";
"VSS11":   PN = "30"  !CDS_PN = "30";
"VSS12":   PN = "32"  !CDS_PN = "32";
"VSS13":   PN = "35"  !CDS_PN = "35";
"VSS14":   PN = "37"  !CDS_PN = "37";
"VSS15":   PN = "39"  !CDS_PN = "39";
"VSS16":   PN = "41"  !CDS_PN = "41";
"VSS17":   PN = "43"  !CDS_PN = "43";
"VSS18":   PN = "46"  !CDS_PN = "46";
"VSS19":   PN = "48"  !CDS_PN = "48";
"VSS20":   PN = "50"  !CDS_PN = "50";
"VSS21":   PN = "52"  !CDS_PN = "52";
"VSS22":   PN = "54"  !CDS_PN = "54";
"VSS23":   PN = "57"  !CDS_PN = "57";
"VSS24":   PN = "59"  !CDS_PN = "59";
"VSS25":   PN = "61"  !CDS_PN = "61";
"VSS26":   PN = "63"  !CDS_PN = "63";
"VSS27":   PN = "65"  !CDS_PN = "65";
"VSS28":   PN = "67"  !CDS_PN = "67";
"VSS29":   PN = "69"  !CDS_PN = "69";
"VSS30":   PN = "71"  !CDS_PN = "71";
"VSS31":   PN = "73"  !CDS_PN = "73";
"VSS32":   PN = "75"  !CDS_PN = "75";
"VSS33":   PN = "77"  !CDS_PN = "77";
"VSS34":   PN = "79"  !CDS_PN = "79";
"VSS35":   PN = "81"  !CDS_PN = "81";
"VSS36":   PN = "83"  !CDS_PN = "83";
"VSS37":   PN = "85"  !CDS_PN = "85";
"VSS38":   PN = "88"  !CDS_PN = "88";
"VSS39":   PN = "90"  !CDS_PN = "90";
"VSS40":   PN = "92"  !CDS_PN = "92";
"VSS41":   PN = "95"  !CDS_PN = "95";
"VSS42":   PN = "97"  !CDS_PN = "97";
"VSS43":   PN = "99"  !CDS_PN = "99";
"VSS44":   PN = "101"  !CDS_PN = "101";
"VSS45":   PN = "103"  !CDS_PN = "103";
"VSS46":   PN = "106"  !CDS_PN = "106";
"VSS47":   PN = "108"  !CDS_PN = "108";
"VSS48":   PN = "110"  !CDS_PN = "110";
"VSS49":   PN = "112"  !CDS_PN = "112";
"VSS50":   PN = "114"  !CDS_PN = "114";
"VSS51":   PN = "117"  !CDS_PN = "117";
"VSS52":   PN = "119"  !CDS_PN = "119";
"VSS53":   PN = "121"  !CDS_PN = "121";
"VSS54":   PN = "123"  !CDS_PN = "123";
"VSS55":   PN = "125"  !CDS_PN = "125";
"VSS56":   PN = "128"  !CDS_PN = "128";
"VSS57":   PN = "130"  !CDS_PN = "130";
"VSS58":   PN = "132"  !CDS_PN = "132";
"VSS59":   PN = "134"  !CDS_PN = "134";
"VSS60":   PN = "136"  !CDS_PN = "136";
"VSS61":   PN = "139"  !CDS_PN = "139";
"VSS62":   PN = "141"  !CDS_PN = "141";
"VSS63":   PN = "143"  !CDS_PN = "143";
"VSS64":   PN = "151"  !CDS_PN = "151";
"VSS65":   PN = "153"  !CDS_PN = "153";
"VSS66":   PN = "155"  !CDS_PN = "155";
"VSS67":   PN = "158"  !CDS_PN = "158";
"VSS68":   PN = "160"  !CDS_PN = "160";
"VSS69":   PN = "162"  !CDS_PN = "162";
"VSS70":   PN = "164"  !CDS_PN = "164";
"VSS71":   PN = "166"  !CDS_PN = "166";
"VSS72":   PN = "169"  !CDS_PN = "169";
"VSS73":   PN = "171"  !CDS_PN = "171";
"VSS74":   PN = "173"  !CDS_PN = "173";
"VSS75":   PN = "175"  !CDS_PN = "175";
"VSS76":   PN = "177"  !CDS_PN = "177";
"VSS77":   PN = "180"  !CDS_PN = "180";
"VSS78":   PN = "182"  !CDS_PN = "182";
"VSS79":   PN = "184"  !CDS_PN = "184";
"VSS80":   PN = "186"  !CDS_PN = "186";
"VSS81":   PN = "188"  !CDS_PN = "188";
"VSS82":   PN = "191"  !CDS_PN = "191";
"VSS83":   PN = "193"  !CDS_PN = "193";
"VSS84":   PN = "195"  !CDS_PN = "195";
"VSS85":   PN = "197"  !CDS_PN = "197";
"VSS86":   PN = "199"  !CDS_PN = "199";
"VSS87":   PN = "202"  !CDS_PN = "202";
"VSS88":   PN = "204"  !CDS_PN = "204";
"VSS89":   PN = "206"  !CDS_PN = "206";
"VSS90":   PN = "208"  !CDS_PN = "208";
"VSS91":   PN = "210"  !CDS_PN = "210";
"VSS92":   PN = "212"  !CDS_PN = "212";
"VSS93":   PN = "214"  !CDS_PN = "214";
"VSS94":   PN = "216"  !CDS_PN = "216";
"VSS95":   PN = "219"  !CDS_PN = "219";
"VSS96":   PN = "222"  !CDS_PN = "222";
"VSS97":   PN = "224"  !CDS_PN = "224";
"VSS98":   PN = "226"  !CDS_PN = "226";
"VSS99":   PN = "228"  !CDS_PN = "228";
"VSS100":   PN = "230"  !CDS_PN = "230";
"VSS101":   PN = "233"  !CDS_PN = "233";
"VSS102":   PN = "235"  !CDS_PN = "235";
"VSS103":   PN = "237"  !CDS_PN = "237";
"VSS104":   PN = "240"  !CDS_PN = "240";
"VSS105":   PN = "242"  !CDS_PN = "242";
"VSS106":   PN = "244"  !CDS_PN = "244";
"VSS107":   PN = "246"  !CDS_PN = "246";
"VSS108":   PN = "248"  !CDS_PN = "248";
"VSS109":   PN = "251"  !CDS_PN = "251";
"VSS110":   PN = "253"  !CDS_PN = "253";
"VSS111":   PN = "255"  !CDS_PN = "255";
"VSS112":   PN = "257"  !CDS_PN = "257";
"VSS113":   PN = "259"  !CDS_PN = "259";
"VSS114":   PN = "262"  !CDS_PN = "262";
"VSS115":   PN = "264"  !CDS_PN = "264";
"VSS116":   PN = "266"  !CDS_PN = "266";
"VSS117":   PN = "268"  !CDS_PN = "268";
"VSS118":   PN = "270"  !CDS_PN = "270";
"VSS119":   PN = "273"  !CDS_PN = "273";
"VSS120":   PN = "275"  !CDS_PN = "275";
"VSS121":   PN = "277"  !CDS_PN = "277";
"VSS122":   PN = "279"  !CDS_PN = "279";
"VSS123":   PN = "281"  !CDS_PN = "281";
"VSS124":   PN = "284"  !CDS_PN = "284";
"VSS125":   PN = "286"  !CDS_PN = "286";
"VSS126":   PN = "288"  !CDS_PN = "288";
BODY = "Q_CAP","I360": #LOCATION = "C104" !CDS_LOCATION = "C104" &SEC = "1" #&CDS_SEC = "1";
"A":   PN = "1"  !CDS_PN = "1";
"B":   PN = "2"  !CDS_PN = "2";
BODY = "Q_RES","I362": #LOCATION = "R295" !CDS_LOCATION = "R295" &SEC = "1" #&CDS_SEC = "1";
"A":   PN = "1"  !CDS_PN = "1";
"B":   PN = "2"  !CDS_PN = "2";
BODY = "Q_RES","I364": #LOCATION = "R93" !CDS_LOCATION = "R93" &SEC = "1" #&CDS_SEC = "1";
"A":   PN = "1"  !CDS_PN = "1";
"B":   PN = "2"  !CDS_PN = "2";
BODY = "SCONN288_DDR506112002KQ","I410": #LOCATION = "J21" !CDS_LOCATION = "J21" &SEC = "2" #&CDS_SEC = "2";
"DQS0_A_C":   PN = "12"  !CDS_PN = "12";
"DQS0_A_T":   PN = "11"  !CDS_PN = "11";
"DQS0_B_C":   PN = "105"  !CDS_PN = "105";
"DQS0_B_T":   PN = "104"  !CDS_PN = "104";
"DQS1_A_C":   PN = "23"  !CDS_PN = "23";
"DQS1_A_T":   PN = "22"  !CDS_PN = "22";
"DQS1_B_C":   PN = "116"  !CDS_PN = "116";
"DQS1_B_T":   PN = "115"  !CDS_PN = "115";
"DQS2_A_C":   PN = "34"  !CDS_PN = "34";
"DQS2_A_T":   PN = "33"  !CDS_PN = "33";
"DQS2_B_C":   PN = "127"  !CDS_PN = "127";
"DQS2_B_T":   PN = "126"  !CDS_PN = "126";
"DQS3_A_C":   PN = "45"  !CDS_PN = "45";
"DQS3_A_T":   PN = "44"  !CDS_PN = "44";
"DQS3_B_C":   PN = "138"  !CDS_PN = "138";
"DQS3_B_T":   PN = "137"  !CDS_PN = "137";
"DQS4_A_C":   PN = "56"  !CDS_PN = "56";
"DQS4_A_T":   PN = "55"  !CDS_PN = "55";
"DQS4_B_C":   PN = "238"  !CDS_PN = "238";
"DQS4_B_T":   PN = "239"  !CDS_PN = "239";
"DQS5_A_C||TDQS5_A_C||DQS5_A_T||TDQS5_A_T":   PN = "156"  !CDS_PN = "156";
"DQS5_A_T||TDQS5_A_T":   PN = "157"  !CDS_PN = "157";
"DQS5_B_C||TDQS5_B_C":   PN = "249"  !CDS_PN = "249";
"DQS5_B_T||TDQS5_B_T":   PN = "250"  !CDS_PN = "250";
"DQS6_A_C||TDQS6_A_C||DQS6_A_T||TDQS6_A_T":   PN = "167"  !CDS_PN = "167";
"DQS6_A_T||TDQS6_A_T":   PN = "168"  !CDS_PN = "168";
"DQS6_B_C||TDQS6_B_C":   PN = "260"  !CDS_PN = "260";
"DQS6_B_T||TDQS6_B_T":   PN = "261"  !CDS_PN = "261";
"DQS7_A_C||TDQS7_A_C":   PN = "178"  !CDS_PN = "178";
"DQS7_A_T||TDQS7_A_T":   PN = "179"  !CDS_PN = "179";
"DQS7_B_C||TDQS7_B_C":   PN = "271"  !CDS_PN = "271";
"DQS7_B_T||TDQS7_B_T":   PN = "272"  !CDS_PN = "272";
"DQS8_A_C||TDQS8_A_C":   PN = "189"  !CDS_PN = "189";
"DQS8_A_T||TDQS8_A_T":   PN = "190"  !CDS_PN = "190";
"DQS8_B_C||TDQS8_B_C":   PN = "282"  !CDS_PN = "282";
"DQS8_B_T||TDQS8_B_T":   PN = "283"  !CDS_PN = "283";
"DQS9_A_C||TDQS9_A_C":   PN = "200"  !CDS_PN = "200";
"DQS9_A_T||TDQS9_A_T":   PN = "201"  !CDS_PN = "201";
"DQS9_B_C||TDQS9_B_C":   PN = "94"  !CDS_PN = "94";
"DQS9_B_T||TDQS9_B_T||DBI4_B_N":   PN = "93"  !CDS_PN = "93";
BODY = "Q_CAP","I412": #LOCATION = "C151" !CDS_LOCATION = "C151" &SEC = "1" #&CDS_SEC = "1";
"A":   PN = "1"  !CDS_PN = "1";
"B":   PN = "2"  !CDS_PN = "2";
BODY = "Q_CAP","I413": #LOCATION = "C153" !CDS_LOCATION = "C153" &SEC = "1" #&CDS_SEC = "1";
"A":   PN = "1"  !CDS_PN = "1";
"B":   PN = "2"  !CDS_PN = "2";
BODY = "Q_RES","I416": #LOCATION = "R1572" !CDS_LOCATION = "R1572" &SEC = "1" #&CDS_SEC = "1";
"A":   PN = "1"  !CDS_PN = "1";
"B":   PN = "2"  !CDS_PN = "2";
BODY = "Q_RES","I418": #LOCATION = "R1678" !CDS_LOCATION = "R1678" &SEC = "1" #&CDS_SEC = "1";
"A":   PN = "1"  !CDS_PN = "1";
"B":   PN = "2"  !CDS_PN = "2";
DRAWING = "@t6g_mb_lib.t6g(sch_1):page90";
BODY = "Q_RES","I349": #LOCATION = "R764" !CDS_LOCATION = "R764" &SEC = "1" #&CDS_SEC = "1";
"A":   PN = "1"  !CDS_PN = "1";
"B":   PN = "2"  !CDS_PN = "2";
BODY = "SCONN288_DDR506112002KQ","I350": #LOCATION = "J23" !CDS_LOCATION = "J23" &SEC = "1" #&CDS_SEC = "1";
"ALERT_N":   PN = "62"  !CDS_PN = "62";
"CA0_A":   PN = "66"  !CDS_PN = "66";
"CA0_B":   PN = "76"  !CDS_PN = "76";
"CA1_A":   PN = "211"  !CDS_PN = "211";
"CA1_B":   PN = "221"  !CDS_PN = "221";
"CA2_A":   PN = "68"  !CDS_PN = "68";
"CA2_B":   PN = "78"  !CDS_PN = "78";
"CA3_A":   PN = "213"  !CDS_PN = "213";
"CA3_B":   PN = "223"  !CDS_PN = "223";
"CA4_A":   PN = "70"  !CDS_PN = "70";
"CA4_B":   PN = "80"  !CDS_PN = "80";
"CA5_A":   PN = "215"  !CDS_PN = "215";
"CA5_B":   PN = "225"  !CDS_PN = "225";
"CA6_A":   PN = "72"  !CDS_PN = "72";
"CA6_B":   PN = "82"  !CDS_PN = "82";
"CB0_A":   PN = "51"  !CDS_PN = "51";
"CB0_B":   PN = "96"  !CDS_PN = "96";
"CB1_A":   PN = "53"  !CDS_PN = "53";
"CB1_B":   PN = "98"  !CDS_PN = "98";
"CB2_A":   PN = "196"  !CDS_PN = "196";
"CB2_B":   PN = "241"  !CDS_PN = "241";
"CB3_A":   PN = "198"  !CDS_PN = "198";
"CB3_B":   PN = "243"  !CDS_PN = "243";
"CB4_A":   PN = "58"  !CDS_PN = "58";
"CB4_B":   PN = "89"  !CDS_PN = "89";
"CB5_A":   PN = "60"  !CDS_PN = "60";
"CB5_B":   PN = "91"  !CDS_PN = "91";
"CB6_A":   PN = "203"  !CDS_PN = "203";
"CB6_B":   PN = "234"  !CDS_PN = "234";
"CB7_A":   PN = "205"  !CDS_PN = "205";
"CB7_B":   PN = "236"  !CDS_PN = "236";
"CK_C":   PN = "218"  !CDS_PN = "218";
"CK_T":   PN = "217"  !CDS_PN = "217";
"CS0_A_N":   PN = "64"  !CDS_PN = "64";
"CS0_B_N":   PN = "84"  !CDS_PN = "84";
"CS1_A_N":   PN = "209"  !CDS_PN = "209";
"CS1_B_N":   PN = "229"  !CDS_PN = "229";
"DQ0_A":   PN = "7"  !CDS_PN = "7";
"DQ0_B":   PN = "100"  !CDS_PN = "100";
"DQ1_A":   PN = "9"  !CDS_PN = "9";
"DQ1_B":   PN = "102"  !CDS_PN = "102";
"DQ2_A":   PN = "152"  !CDS_PN = "152";
"DQ2_B":   PN = "245"  !CDS_PN = "245";
"DQ3_A":   PN = "154"  !CDS_PN = "154";
"DQ3_B":   PN = "247"  !CDS_PN = "247";
"DQ4_A":   PN = "14"  !CDS_PN = "14";
"DQ4_B":   PN = "107"  !CDS_PN = "107";
"DQ5_A":   PN = "16"  !CDS_PN = "16";
"DQ5_B":   PN = "109"  !CDS_PN = "109";
"DQ6_A":   PN = "159"  !CDS_PN = "159";
"DQ6_B":   PN = "252"  !CDS_PN = "252";
"DQ7_A":   PN = "161"  !CDS_PN = "161";
"DQ7_B":   PN = "254"  !CDS_PN = "254";
"DQ8_A":   PN = "18"  !CDS_PN = "18";
"DQ8_B":   PN = "111"  !CDS_PN = "111";
"DQ9_A":   PN = "20"  !CDS_PN = "20";
"DQ9_B":   PN = "113"  !CDS_PN = "113";
"DQ10_A":   PN = "163"  !CDS_PN = "163";
"DQ10_B":   PN = "256"  !CDS_PN = "256";
"DQ11_A":   PN = "165"  !CDS_PN = "165";
"DQ11_B":   PN = "258"  !CDS_PN = "258";
"DQ12_A":   PN = "25"  !CDS_PN = "25";
"DQ12_B":   PN = "118"  !CDS_PN = "118";
"DQ13_A":   PN = "27"  !CDS_PN = "27";
"DQ13_B":   PN = "120"  !CDS_PN = "120";
"DQ14_A":   PN = "170"  !CDS_PN = "170";
"DQ14_B":   PN = "263"  !CDS_PN = "263";
"DQ15_A":   PN = "172"  !CDS_PN = "172";
"DQ15_B":   PN = "265"  !CDS_PN = "265";
"DQ16_A":   PN = "29"  !CDS_PN = "29";
"DQ16_B":   PN = "122"  !CDS_PN = "122";
"DQ17_A":   PN = "31"  !CDS_PN = "31";
"DQ17_B":   PN = "124"  !CDS_PN = "124";
"DQ18_A":   PN = "174"  !CDS_PN = "174";
"DQ18_B":   PN = "267"  !CDS_PN = "267";
"DQ19_A":   PN = "176"  !CDS_PN = "176";
"DQ19_B":   PN = "269"  !CDS_PN = "269";
"DQ20_A":   PN = "36"  !CDS_PN = "36";
"DQ20_B":   PN = "129"  !CDS_PN = "129";
"DQ21_A":   PN = "38"  !CDS_PN = "38";
"DQ21_B":   PN = "131"  !CDS_PN = "131";
"DQ22_A":   PN = "181"  !CDS_PN = "181";
"DQ22_B":   PN = "274"  !CDS_PN = "274";
"DQ23_A":   PN = "183"  !CDS_PN = "183";
"DQ23_B":   PN = "276"  !CDS_PN = "276";
"DQ24_A":   PN = "40"  !CDS_PN = "40";
"DQ24_B":   PN = "133"  !CDS_PN = "133";
"DQ25_A":   PN = "42"  !CDS_PN = "42";
"DQ25_B":   PN = "135"  !CDS_PN = "135";
"DQ26_A":   PN = "185"  !CDS_PN = "185";
"DQ26_B":   PN = "278"  !CDS_PN = "278";
"DQ27_A":   PN = "187"  !CDS_PN = "187";
"DQ27_B":   PN = "280"  !CDS_PN = "280";
"DQ28_A":   PN = "47"  !CDS_PN = "47";
"DQ28_B":   PN = "140"  !CDS_PN = "140";
"DQ29_A":   PN = "49"  !CDS_PN = "49";
"DQ29_B":   PN = "142"  !CDS_PN = "142";
"DQ30_A":   PN = "192"  !CDS_PN = "192";
"DQ30_B":   PN = "285"  !CDS_PN = "285";
"DQ31_A":   PN = "194"  !CDS_PN = "194";
"DQ31_B":   PN = "287"  !CDS_PN = "287";
"HAS":   PN = "148"  !CDS_PN = "148";
"HSCL":   PN = "4"  !CDS_PN = "4";
"HSDA":   PN = "5"  !CDS_PN = "5";
"LBD||RSP_A_N":   PN = "86"  !CDS_PN = "86";
"LBS||RSP_B_N":   PN = "87"  !CDS_PN = "87";
"PAR_A":   PN = "74"  !CDS_PN = "74";
"PAR_B":   PN = "227"  !CDS_PN = "227";
"PWR_GOOD||FAIL_N":   PN = "147"  !CDS_PN = "147";
"RESET_N":   PN = "207"  !CDS_PN = "207";
"RFU0":   PN = "2"  !CDS_PN = "2";
"RFU1":   PN = "144"  !CDS_PN = "144";
"RFU2":   PN = "149"  !CDS_PN = "149";
"RFU3":   PN = "150"  !CDS_PN = "150";
"RFU4":   PN = "220"  !CDS_PN = "220";
"RFU5":   PN = "231"  !CDS_PN = "231";
"RFU6":   PN = "232"  !CDS_PN = "232";
"VIN_MGMT":   PN = "3"  !CDS_PN = "3";
BODY = "SCONN288_DDR506112002KQ","I352": #LOCATION = "J23" !CDS_LOCATION = "J23" &SEC = "3" #&CDS_SEC = "3";
"G1":   PN = "G1"  !CDS_PN = "G1";
"G2":   PN = "G2"  !CDS_PN = "G2";
"G3":   PN = "G3"  !CDS_PN = "G3";
"VIN_BULK0":   PN = "1"  !CDS_PN = "1";
"VIN_BULK1":   PN = "145"  !CDS_PN = "145";
"VIN_BULK2":   PN = "146"  !CDS_PN = "146";
"VSS0":   PN = "6"  !CDS_PN = "6";
"VSS1":   PN = "8"  !CDS_PN = "8";
"VSS2":   PN = "10"  !CDS_PN = "10";
"VSS3":   PN = "13"  !CDS_PN = "13";
"VSS4":   PN = "15"  !CDS_PN = "15";
"VSS5":   PN = "17"  !CDS_PN = "17";
"VSS6":   PN = "19"  !CDS_PN = "19";
"VSS7":   PN = "21"  !CDS_PN = "21";
"VSS8":   PN = "24"  !CDS_PN = "24";
"VSS9":   PN = "26"  !CDS_PN = "26";
"VSS10":   PN = "28"  !CDS_PN = "28";
"VSS11":   PN = "30"  !CDS_PN = "30";
"VSS12":   PN = "32"  !CDS_PN = "32";
"VSS13":   PN = "35"  !CDS_PN = "35";
"VSS14":   PN = "37"  !CDS_PN = "37";
"VSS15":   PN = "39"  !CDS_PN = "39";
"VSS16":   PN = "41"  !CDS_PN = "41";
"VSS17":   PN = "43"  !CDS_PN = "43";
"VSS18":   PN = "46"  !CDS_PN = "46";
"VSS19":   PN = "48"  !CDS_PN = "48";
"VSS20":   PN = "50"  !CDS_PN = "50";
"VSS21":   PN = "52"  !CDS_PN = "52";
"VSS22":   PN = "54"  !CDS_PN = "54";
"VSS23":   PN = "57"  !CDS_PN = "57";
"VSS24":   PN = "59"  !CDS_PN = "59";
"VSS25":   PN = "61"  !CDS_PN = "61";
"VSS26":   PN = "63"  !CDS_PN = "63";
"VSS27":   PN = "65"  !CDS_PN = "65";
"VSS28":   PN = "67"  !CDS_PN = "67";
"VSS29":   PN = "69"  !CDS_PN = "69";
"VSS30":   PN = "71"  !CDS_PN = "71";
"VSS31":   PN = "73"  !CDS_PN = "73";
"VSS32":   PN = "75"  !CDS_PN = "75";
"VSS33":   PN = "77"  !CDS_PN = "77";
"VSS34":   PN = "79"  !CDS_PN = "79";
"VSS35":   PN = "81"  !CDS_PN = "81";
"VSS36":   PN = "83"  !CDS_PN = "83";
"VSS37":   PN = "85"  !CDS_PN = "85";
"VSS38":   PN = "88"  !CDS_PN = "88";
"VSS39":   PN = "90"  !CDS_PN = "90";
"VSS40":   PN = "92"  !CDS_PN = "92";
"VSS41":   PN = "95"  !CDS_PN = "95";
"VSS42":   PN = "97"  !CDS_PN = "97";
"VSS43":   PN = "99"  !CDS_PN = "99";
"VSS44":   PN = "101"  !CDS_PN = "101";
"VSS45":   PN = "103"  !CDS_PN = "103";
"VSS46":   PN = "106"  !CDS_PN = "106";
"VSS47":   PN = "108"  !CDS_PN = "108";
"VSS48":   PN = "110"  !CDS_PN = "110";
"VSS49":   PN = "112"  !CDS_PN = "112";
"VSS50":   PN = "114"  !CDS_PN = "114";
"VSS51":   PN = "117"  !CDS_PN = "117";
"VSS52":   PN = "119"  !CDS_PN = "119";
"VSS53":   PN = "121"  !CDS_PN = "121";
"VSS54":   PN = "123"  !CDS_PN = "123";
"VSS55":   PN = "125"  !CDS_PN = "125";
"VSS56":   PN = "128"  !CDS_PN = "128";
"VSS57":   PN = "130"  !CDS_PN = "130";
"VSS58":   PN = "132"  !CDS_PN = "132";
"VSS59":   PN = "134"  !CDS_PN = "134";
"VSS60":   PN = "136"  !CDS_PN = "136";
"VSS61":   PN = "139"  !CDS_PN = "139";
"VSS62":   PN = "141"  !CDS_PN = "141";
"VSS63":   PN = "143"  !CDS_PN = "143";
"VSS64":   PN = "151"  !CDS_PN = "151";
"VSS65":   PN = "153"  !CDS_PN = "153";
"VSS66":   PN = "155"  !CDS_PN = "155";
"VSS67":   PN = "158"  !CDS_PN = "158";
"VSS68":   PN = "160"  !CDS_PN = "160";
"VSS69":   PN = "162"  !CDS_PN = "162";
"VSS70":   PN = "164"  !CDS_PN = "164";
"VSS71":   PN = "166"  !CDS_PN = "166";
"VSS72":   PN = "169"  !CDS_PN = "169";
"VSS73":   PN = "171"  !CDS_PN = "171";
"VSS74":   PN = "173"  !CDS_PN = "173";
"VSS75":   PN = "175"  !CDS_PN = "175";
"VSS76":   PN = "177"  !CDS_PN = "177";
"VSS77":   PN = "180"  !CDS_PN = "180";
"VSS78":   PN = "182"  !CDS_PN = "182";
"VSS79":   PN = "184"  !CDS_PN = "184";
"VSS80":   PN = "186"  !CDS_PN = "186";
"VSS81":   PN = "188"  !CDS_PN = "188";
"VSS82":   PN = "191"  !CDS_PN = "191";
"VSS83":   PN = "193"  !CDS_PN = "193";
"VSS84":   PN = "195"  !CDS_PN = "195";
"VSS85":   PN = "197"  !CDS_PN = "197";
"VSS86":   PN = "199"  !CDS_PN = "199";
"VSS87":   PN = "202"  !CDS_PN = "202";
"VSS88":   PN = "204"  !CDS_PN = "204";
"VSS89":   PN = "206"  !CDS_PN = "206";
"VSS90":   PN = "208"  !CDS_PN = "208";
"VSS91":   PN = "210"  !CDS_PN = "210";
"VSS92":   PN = "212"  !CDS_PN = "212";
"VSS93":   PN = "214"  !CDS_PN = "214";
"VSS94":   PN = "216"  !CDS_PN = "216";
"VSS95":   PN = "219"  !CDS_PN = "219";
"VSS96":   PN = "222"  !CDS_PN = "222";
"VSS97":   PN = "224"  !CDS_PN = "224";
"VSS98":   PN = "226"  !CDS_PN = "226";
"VSS99":   PN = "228"  !CDS_PN = "228";
"VSS100":   PN = "230"  !CDS_PN = "230";
"VSS101":   PN = "233"  !CDS_PN = "233";
"VSS102":   PN = "235"  !CDS_PN = "235";
"VSS103":   PN = "237"  !CDS_PN = "237";
"VSS104":   PN = "240"  !CDS_PN = "240";
"VSS105":   PN = "242"  !CDS_PN = "242";
"VSS106":   PN = "244"  !CDS_PN = "244";
"VSS107":   PN = "246"  !CDS_PN = "246";
"VSS108":   PN = "248"  !CDS_PN = "248";
"VSS109":   PN = "251"  !CDS_PN = "251";
"VSS110":   PN = "253"  !CDS_PN = "253";
"VSS111":   PN = "255"  !CDS_PN = "255";
"VSS112":   PN = "257"  !CDS_PN = "257";
"VSS113":   PN = "259"  !CDS_PN = "259";
"VSS114":   PN = "262"  !CDS_PN = "262";
"VSS115":   PN = "264"  !CDS_PN = "264";
"VSS116":   PN = "266"  !CDS_PN = "266";
"VSS117":   PN = "268"  !CDS_PN = "268";
"VSS118":   PN = "270"  !CDS_PN = "270";
"VSS119":   PN = "273"  !CDS_PN = "273";
"VSS120":   PN = "275"  !CDS_PN = "275";
"VSS121":   PN = "277"  !CDS_PN = "277";
"VSS122":   PN = "279"  !CDS_PN = "279";
"VSS123":   PN = "281"  !CDS_PN = "281";
"VSS124":   PN = "284"  !CDS_PN = "284";
"VSS125":   PN = "286"  !CDS_PN = "286";
"VSS126":   PN = "288"  !CDS_PN = "288";
BODY = "Q_CAP","I361": #LOCATION = "C108" !CDS_LOCATION = "C108" &SEC = "1" #&CDS_SEC = "1";
"A":   PN = "1"  !CDS_PN = "1";
"B":   PN = "2"  !CDS_PN = "2";
BODY = "Q_RES","I364": #LOCATION = "R296" !CDS_LOCATION = "R296" &SEC = "1" #&CDS_SEC = "1";
"A":   PN = "1"  !CDS_PN = "1";
"B":   PN = "2"  !CDS_PN = "2";
BODY = "Q_RES","I365": #LOCATION = "R94" !CDS_LOCATION = "R94" &SEC = "1" #&CDS_SEC = "1";
"A":   PN = "1"  !CDS_PN = "1";
"B":   PN = "2"  !CDS_PN = "2";
BODY = "SCONN288_DDR506112002KQ","I412": #LOCATION = "J23" !CDS_LOCATION = "J23" &SEC = "2" #&CDS_SEC = "2";
"DQS0_A_C":   PN = "12"  !CDS_PN = "12";
"DQS0_A_T":   PN = "11"  !CDS_PN = "11";
"DQS0_B_C":   PN = "105"  !CDS_PN = "105";
"DQS0_B_T":   PN = "104"  !CDS_PN = "104";
"DQS1_A_C":   PN = "23"  !CDS_PN = "23";
"DQS1_A_T":   PN = "22"  !CDS_PN = "22";
"DQS1_B_C":   PN = "116"  !CDS_PN = "116";
"DQS1_B_T":   PN = "115"  !CDS_PN = "115";
"DQS2_A_C":   PN = "34"  !CDS_PN = "34";
"DQS2_A_T":   PN = "33"  !CDS_PN = "33";
"DQS2_B_C":   PN = "127"  !CDS_PN = "127";
"DQS2_B_T":   PN = "126"  !CDS_PN = "126";
"DQS3_A_C":   PN = "45"  !CDS_PN = "45";
"DQS3_A_T":   PN = "44"  !CDS_PN = "44";
"DQS3_B_C":   PN = "138"  !CDS_PN = "138";
"DQS3_B_T":   PN = "137"  !CDS_PN = "137";
"DQS4_A_C":   PN = "56"  !CDS_PN = "56";
"DQS4_A_T":   PN = "55"  !CDS_PN = "55";
"DQS4_B_C":   PN = "238"  !CDS_PN = "238";
"DQS4_B_T":   PN = "239"  !CDS_PN = "239";
"DQS5_A_C||TDQS5_A_C||DQS5_A_T||TDQS5_A_T":   PN = "156"  !CDS_PN = "156";
"DQS5_A_T||TDQS5_A_T":   PN = "157"  !CDS_PN = "157";
"DQS5_B_C||TDQS5_B_C":   PN = "249"  !CDS_PN = "249";
"DQS5_B_T||TDQS5_B_T":   PN = "250"  !CDS_PN = "250";
"DQS6_A_C||TDQS6_A_C||DQS6_A_T||TDQS6_A_T":   PN = "167"  !CDS_PN = "167";
"DQS6_A_T||TDQS6_A_T":   PN = "168"  !CDS_PN = "168";
"DQS6_B_C||TDQS6_B_C":   PN = "260"  !CDS_PN = "260";
"DQS6_B_T||TDQS6_B_T":   PN = "261"  !CDS_PN = "261";
"DQS7_A_C||TDQS7_A_C":   PN = "178"  !CDS_PN = "178";
"DQS7_A_T||TDQS7_A_T":   PN = "179"  !CDS_PN = "179";
"DQS7_B_C||TDQS7_B_C":   PN = "271"  !CDS_PN = "271";
"DQS7_B_T||TDQS7_B_T":   PN = "272"  !CDS_PN = "272";
"DQS8_A_C||TDQS8_A_C":   PN = "189"  !CDS_PN = "189";
"DQS8_A_T||TDQS8_A_T":   PN = "190"  !CDS_PN = "190";
"DQS8_B_C||TDQS8_B_C":   PN = "282"  !CDS_PN = "282";
"DQS8_B_T||TDQS8_B_T":   PN = "283"  !CDS_PN = "283";
"DQS9_A_C||TDQS9_A_C":   PN = "200"  !CDS_PN = "200";
"DQS9_A_T||TDQS9_A_T":   PN = "201"  !CDS_PN = "201";
"DQS9_B_C||TDQS9_B_C":   PN = "94"  !CDS_PN = "94";
"DQS9_B_T||TDQS9_B_T||DBI4_B_N":   PN = "93"  !CDS_PN = "93";
BODY = "Q_CAP","I414": #LOCATION = "C154" !CDS_LOCATION = "C154" &SEC = "1" #&CDS_SEC = "1";
"A":   PN = "1"  !CDS_PN = "1";
"B":   PN = "2"  !CDS_PN = "2";
BODY = "Q_CAP","I415": #LOCATION = "C155" !CDS_LOCATION = "C155" &SEC = "1" #&CDS_SEC = "1";
"A":   PN = "1"  !CDS_PN = "1";
"B":   PN = "2"  !CDS_PN = "2";
BODY = "Q_RES","I418": #LOCATION = "R1573" !CDS_LOCATION = "R1573" &SEC = "1" #&CDS_SEC = "1";
"A":   PN = "1"  !CDS_PN = "1";
"B":   PN = "2"  !CDS_PN = "2";
BODY = "Q_RES","I419": #LOCATION = "R1679" !CDS_LOCATION = "R1679" &SEC = "1" #&CDS_SEC = "1";
"A":   PN = "1"  !CDS_PN = "1";
"B":   PN = "2"  !CDS_PN = "2";
DRAWING = "@t6g_mb_lib.t6g(sch_1):page91";
BODY = "SCONN288_DDR506112002KQ","I22": #LOCATION = "J16" !CDS_LOCATION = "J16" &SEC = "1" #&CDS_SEC = "1";
"ALERT_N":   PN = "62"  !CDS_PN = "62";
"CA0_A":   PN = "66"  !CDS_PN = "66";
"CA0_B":   PN = "76"  !CDS_PN = "76";
"CA1_A":   PN = "211"  !CDS_PN = "211";
"CA1_B":   PN = "221"  !CDS_PN = "221";
"CA2_A":   PN = "68"  !CDS_PN = "68";
"CA2_B":   PN = "78"  !CDS_PN = "78";
"CA3_A":   PN = "213"  !CDS_PN = "213";
"CA3_B":   PN = "223"  !CDS_PN = "223";
"CA4_A":   PN = "70"  !CDS_PN = "70";
"CA4_B":   PN = "80"  !CDS_PN = "80";
"CA5_A":   PN = "215"  !CDS_PN = "215";
"CA5_B":   PN = "225"  !CDS_PN = "225";
"CA6_A":   PN = "72"  !CDS_PN = "72";
"CA6_B":   PN = "82"  !CDS_PN = "82";
"CB0_A":   PN = "51"  !CDS_PN = "51";
"CB0_B":   PN = "96"  !CDS_PN = "96";
"CB1_A":   PN = "53"  !CDS_PN = "53";
"CB1_B":   PN = "98"  !CDS_PN = "98";
"CB2_A":   PN = "196"  !CDS_PN = "196";
"CB2_B":   PN = "241"  !CDS_PN = "241";
"CB3_A":   PN = "198"  !CDS_PN = "198";
"CB3_B":   PN = "243"  !CDS_PN = "243";
"CB4_A":   PN = "58"  !CDS_PN = "58";
"CB4_B":   PN = "89"  !CDS_PN = "89";
"CB5_A":   PN = "60"  !CDS_PN = "60";
"CB5_B":   PN = "91"  !CDS_PN = "91";
"CB6_A":   PN = "203"  !CDS_PN = "203";
"CB6_B":   PN = "234"  !CDS_PN = "234";
"CB7_A":   PN = "205"  !CDS_PN = "205";
"CB7_B":   PN = "236"  !CDS_PN = "236";
"CK_C":   PN = "218"  !CDS_PN = "218";
"CK_T":   PN = "217"  !CDS_PN = "217";
"CS0_A_N":   PN = "64"  !CDS_PN = "64";
"CS0_B_N":   PN = "84"  !CDS_PN = "84";
"CS1_A_N":   PN = "209"  !CDS_PN = "209";
"CS1_B_N":   PN = "229"  !CDS_PN = "229";
"DQ0_A":   PN = "7"  !CDS_PN = "7";
"DQ0_B":   PN = "100"  !CDS_PN = "100";
"DQ1_A":   PN = "9"  !CDS_PN = "9";
"DQ1_B":   PN = "102"  !CDS_PN = "102";
"DQ2_A":   PN = "152"  !CDS_PN = "152";
"DQ2_B":   PN = "245"  !CDS_PN = "245";
"DQ3_A":   PN = "154"  !CDS_PN = "154";
"DQ3_B":   PN = "247"  !CDS_PN = "247";
"DQ4_A":   PN = "14"  !CDS_PN = "14";
"DQ4_B":   PN = "107"  !CDS_PN = "107";
"DQ5_A":   PN = "16"  !CDS_PN = "16";
"DQ5_B":   PN = "109"  !CDS_PN = "109";
"DQ6_A":   PN = "159"  !CDS_PN = "159";
"DQ6_B":   PN = "252"  !CDS_PN = "252";
"DQ7_A":   PN = "161"  !CDS_PN = "161";
"DQ7_B":   PN = "254"  !CDS_PN = "254";
"DQ8_A":   PN = "18"  !CDS_PN = "18";
"DQ8_B":   PN = "111"  !CDS_PN = "111";
"DQ9_A":   PN = "20"  !CDS_PN = "20";
"DQ9_B":   PN = "113"  !CDS_PN = "113";
"DQ10_A":   PN = "163"  !CDS_PN = "163";
"DQ10_B":   PN = "256"  !CDS_PN = "256";
"DQ11_A":   PN = "165"  !CDS_PN = "165";
"DQ11_B":   PN = "258"  !CDS_PN = "258";
"DQ12_A":   PN = "25"  !CDS_PN = "25";
"DQ12_B":   PN = "118"  !CDS_PN = "118";
"DQ13_A":   PN = "27"  !CDS_PN = "27";
"DQ13_B":   PN = "120"  !CDS_PN = "120";
"DQ14_A":   PN = "170"  !CDS_PN = "170";
"DQ14_B":   PN = "263"  !CDS_PN = "263";
"DQ15_A":   PN = "172"  !CDS_PN = "172";
"DQ15_B":   PN = "265"  !CDS_PN = "265";
"DQ16_A":   PN = "29"  !CDS_PN = "29";
"DQ16_B":   PN = "122"  !CDS_PN = "122";
"DQ17_A":   PN = "31"  !CDS_PN = "31";
"DQ17_B":   PN = "124"  !CDS_PN = "124";
"DQ18_A":   PN = "174"  !CDS_PN = "174";
"DQ18_B":   PN = "267"  !CDS_PN = "267";
"DQ19_A":   PN = "176"  !CDS_PN = "176";
"DQ19_B":   PN = "269"  !CDS_PN = "269";
"DQ20_A":   PN = "36"  !CDS_PN = "36";
"DQ20_B":   PN = "129"  !CDS_PN = "129";
"DQ21_A":   PN = "38"  !CDS_PN = "38";
"DQ21_B":   PN = "131"  !CDS_PN = "131";
"DQ22_A":   PN = "181"  !CDS_PN = "181";
"DQ22_B":   PN = "274"  !CDS_PN = "274";
"DQ23_A":   PN = "183"  !CDS_PN = "183";
"DQ23_B":   PN = "276"  !CDS_PN = "276";
"DQ24_A":   PN = "40"  !CDS_PN = "40";
"DQ24_B":   PN = "133"  !CDS_PN = "133";
"DQ25_A":   PN = "42"  !CDS_PN = "42";
"DQ25_B":   PN = "135"  !CDS_PN = "135";
"DQ26_A":   PN = "185"  !CDS_PN = "185";
"DQ26_B":   PN = "278"  !CDS_PN = "278";
"DQ27_A":   PN = "187"  !CDS_PN = "187";
"DQ27_B":   PN = "280"  !CDS_PN = "280";
"DQ28_A":   PN = "47"  !CDS_PN = "47";
"DQ28_B":   PN = "140"  !CDS_PN = "140";
"DQ29_A":   PN = "49"  !CDS_PN = "49";
"DQ29_B":   PN = "142"  !CDS_PN = "142";
"DQ30_A":   PN = "192"  !CDS_PN = "192";
"DQ30_B":   PN = "285"  !CDS_PN = "285";
"DQ31_A":   PN = "194"  !CDS_PN = "194";
"DQ31_B":   PN = "287"  !CDS_PN = "287";
"HAS":   PN = "148"  !CDS_PN = "148";
"HSCL":   PN = "4"  !CDS_PN = "4";
"HSDA":   PN = "5"  !CDS_PN = "5";
"LBD||RSP_A_N":   PN = "86"  !CDS_PN = "86";
"LBS||RSP_B_N":   PN = "87"  !CDS_PN = "87";
"PAR_A":   PN = "74"  !CDS_PN = "74";
"PAR_B":   PN = "227"  !CDS_PN = "227";
"PWR_GOOD||FAIL_N":   PN = "147"  !CDS_PN = "147";
"RESET_N":   PN = "207"  !CDS_PN = "207";
"RFU0":   PN = "2"  !CDS_PN = "2";
"RFU1":   PN = "144"  !CDS_PN = "144";
"RFU2":   PN = "149"  !CDS_PN = "149";
"RFU3":   PN = "150"  !CDS_PN = "150";
"RFU4":   PN = "220"  !CDS_PN = "220";
"RFU5":   PN = "231"  !CDS_PN = "231";
"RFU6":   PN = "232"  !CDS_PN = "232";
"VIN_MGMT":   PN = "3"  !CDS_PN = "3";
BODY = "Q_RES","I129": #LOCATION = "R35" !CDS_LOCATION = "R35" #SEC = "1" !CDS_SEC = "1";
"A":   PN = "1"  !CDS_PN = "1";
"B":   PN = "2"  !CDS_PN = "2";
BODY = "SCONN288_DDR506112002KQ","I177": #LOCATION = "J16" !CDS_LOCATION = "J16" &SEC = "3" #&CDS_SEC = "3";
"G1":   PN = "G1"  !CDS_PN = "G1";
"G2":   PN = "G2"  !CDS_PN = "G2";
"G3":   PN = "G3"  !CDS_PN = "G3";
"VIN_BULK0":   PN = "1"  !CDS_PN = "1";
"VIN_BULK1":   PN = "145"  !CDS_PN = "145";
"VIN_BULK2":   PN = "146"  !CDS_PN = "146";
"VSS0":   PN = "6"  !CDS_PN = "6";
"VSS1":   PN = "8"  !CDS_PN = "8";
"VSS2":   PN = "10"  !CDS_PN = "10";
"VSS3":   PN = "13"  !CDS_PN = "13";
"VSS4":   PN = "15"  !CDS_PN = "15";
"VSS5":   PN = "17"  !CDS_PN = "17";
"VSS6":   PN = "19"  !CDS_PN = "19";
"VSS7":   PN = "21"  !CDS_PN = "21";
"VSS8":   PN = "24"  !CDS_PN = "24";
"VSS9":   PN = "26"  !CDS_PN = "26";
"VSS10":   PN = "28"  !CDS_PN = "28";
"VSS11":   PN = "30"  !CDS_PN = "30";
"VSS12":   PN = "32"  !CDS_PN = "32";
"VSS13":   PN = "35"  !CDS_PN = "35";
"VSS14":   PN = "37"  !CDS_PN = "37";
"VSS15":   PN = "39"  !CDS_PN = "39";
"VSS16":   PN = "41"  !CDS_PN = "41";
"VSS17":   PN = "43"  !CDS_PN = "43";
"VSS18":   PN = "46"  !CDS_PN = "46";
"VSS19":   PN = "48"  !CDS_PN = "48";
"VSS20":   PN = "50"  !CDS_PN = "50";
"VSS21":   PN = "52"  !CDS_PN = "52";
"VSS22":   PN = "54"  !CDS_PN = "54";
"VSS23":   PN = "57"  !CDS_PN = "57";
"VSS24":   PN = "59"  !CDS_PN = "59";
"VSS25":   PN = "61"  !CDS_PN = "61";
"VSS26":   PN = "63"  !CDS_PN = "63";
"VSS27":   PN = "65"  !CDS_PN = "65";
"VSS28":   PN = "67"  !CDS_PN = "67";
"VSS29":   PN = "69"  !CDS_PN = "69";
"VSS30":   PN = "71"  !CDS_PN = "71";
"VSS31":   PN = "73"  !CDS_PN = "73";
"VSS32":   PN = "75"  !CDS_PN = "75";
"VSS33":   PN = "77"  !CDS_PN = "77";
"VSS34":   PN = "79"  !CDS_PN = "79";
"VSS35":   PN = "81"  !CDS_PN = "81";
"VSS36":   PN = "83"  !CDS_PN = "83";
"VSS37":   PN = "85"  !CDS_PN = "85";
"VSS38":   PN = "88"  !CDS_PN = "88";
"VSS39":   PN = "90"  !CDS_PN = "90";
"VSS40":   PN = "92"  !CDS_PN = "92";
"VSS41":   PN = "95"  !CDS_PN = "95";
"VSS42":   PN = "97"  !CDS_PN = "97";
"VSS43":   PN = "99"  !CDS_PN = "99";
"VSS44":   PN = "101"  !CDS_PN = "101";
"VSS45":   PN = "103"  !CDS_PN = "103";
"VSS46":   PN = "106"  !CDS_PN = "106";
"VSS47":   PN = "108"  !CDS_PN = "108";
"VSS48":   PN = "110"  !CDS_PN = "110";
"VSS49":   PN = "112"  !CDS_PN = "112";
"VSS50":   PN = "114"  !CDS_PN = "114";
"VSS51":   PN = "117"  !CDS_PN = "117";
"VSS52":   PN = "119"  !CDS_PN = "119";
"VSS53":   PN = "121"  !CDS_PN = "121";
"VSS54":   PN = "123"  !CDS_PN = "123";
"VSS55":   PN = "125"  !CDS_PN = "125";
"VSS56":   PN = "128"  !CDS_PN = "128";
"VSS57":   PN = "130"  !CDS_PN = "130";
"VSS58":   PN = "132"  !CDS_PN = "132";
"VSS59":   PN = "134"  !CDS_PN = "134";
"VSS60":   PN = "136"  !CDS_PN = "136";
"VSS61":   PN = "139"  !CDS_PN = "139";
"VSS62":   PN = "141"  !CDS_PN = "141";
"VSS63":   PN = "143"  !CDS_PN = "143";
"VSS64":   PN = "151"  !CDS_PN = "151";
"VSS65":   PN = "153"  !CDS_PN = "153";
"VSS66":   PN = "155"  !CDS_PN = "155";
"VSS67":   PN = "158"  !CDS_PN = "158";
"VSS68":   PN = "160"  !CDS_PN = "160";
"VSS69":   PN = "162"  !CDS_PN = "162";
"VSS70":   PN = "164"  !CDS_PN = "164";
"VSS71":   PN = "166"  !CDS_PN = "166";
"VSS72":   PN = "169"  !CDS_PN = "169";
"VSS73":   PN = "171"  !CDS_PN = "171";
"VSS74":   PN = "173"  !CDS_PN = "173";
"VSS75":   PN = "175"  !CDS_PN = "175";
"VSS76":   PN = "177"  !CDS_PN = "177";
"VSS77":   PN = "180"  !CDS_PN = "180";
"VSS78":   PN = "182"  !CDS_PN = "182";
"VSS79":   PN = "184"  !CDS_PN = "184";
"VSS80":   PN = "186"  !CDS_PN = "186";
"VSS81":   PN = "188"  !CDS_PN = "188";
"VSS82":   PN = "191"  !CDS_PN = "191";
"VSS83":   PN = "193"  !CDS_PN = "193";
"VSS84":   PN = "195"  !CDS_PN = "195";
"VSS85":   PN = "197"  !CDS_PN = "197";
"VSS86":   PN = "199"  !CDS_PN = "199";
"VSS87":   PN = "202"  !CDS_PN = "202";
"VSS88":   PN = "204"  !CDS_PN = "204";
"VSS89":   PN = "206"  !CDS_PN = "206";
"VSS90":   PN = "208"  !CDS_PN = "208";
"VSS91":   PN = "210"  !CDS_PN = "210";
"VSS92":   PN = "212"  !CDS_PN = "212";
"VSS93":   PN = "214"  !CDS_PN = "214";
"VSS94":   PN = "216"  !CDS_PN = "216";
"VSS95":   PN = "219"  !CDS_PN = "219";
"VSS96":   PN = "222"  !CDS_PN = "222";
"VSS97":   PN = "224"  !CDS_PN = "224";
"VSS98":   PN = "226"  !CDS_PN = "226";
"VSS99":   PN = "228"  !CDS_PN = "228";
"VSS100":   PN = "230"  !CDS_PN = "230";
"VSS101":   PN = "233"  !CDS_PN = "233";
"VSS102":   PN = "235"  !CDS_PN = "235";
"VSS103":   PN = "237"  !CDS_PN = "237";
"VSS104":   PN = "240"  !CDS_PN = "240";
"VSS105":   PN = "242"  !CDS_PN = "242";
"VSS106":   PN = "244"  !CDS_PN = "244";
"VSS107":   PN = "246"  !CDS_PN = "246";
"VSS108":   PN = "248"  !CDS_PN = "248";
"VSS109":   PN = "251"  !CDS_PN = "251";
"VSS110":   PN = "253"  !CDS_PN = "253";
"VSS111":   PN = "255"  !CDS_PN = "255";
"VSS112":   PN = "257"  !CDS_PN = "257";
"VSS113":   PN = "259"  !CDS_PN = "259";
"VSS114":   PN = "262"  !CDS_PN = "262";
"VSS115":   PN = "264"  !CDS_PN = "264";
"VSS116":   PN = "266"  !CDS_PN = "266";
"VSS117":   PN = "268"  !CDS_PN = "268";
"VSS118":   PN = "270"  !CDS_PN = "270";
"VSS119":   PN = "273"  !CDS_PN = "273";
"VSS120":   PN = "275"  !CDS_PN = "275";
"VSS121":   PN = "277"  !CDS_PN = "277";
"VSS122":   PN = "279"  !CDS_PN = "279";
"VSS123":   PN = "281"  !CDS_PN = "281";
"VSS124":   PN = "284"  !CDS_PN = "284";
"VSS125":   PN = "286"  !CDS_PN = "286";
"VSS126":   PN = "288"  !CDS_PN = "288";
BODY = "Q_CAP","I183": #LOCATION = "C112" !CDS_LOCATION = "C112" &SEC = "1" #&CDS_SEC = "1";
"A":   PN = "1"  !CDS_PN = "1";
"B":   PN = "2"  !CDS_PN = "2";
BODY = "Q_RES","I186": #LOCATION = "R297" !CDS_LOCATION = "R297" &SEC = "1" #&CDS_SEC = "1";
"A":   PN = "1"  !CDS_PN = "1";
"B":   PN = "2"  !CDS_PN = "2";
BODY = "Q_RES","I187": #LOCATION = "R96" !CDS_LOCATION = "R96" &SEC = "1" #&CDS_SEC = "1";
"A":   PN = "1"  !CDS_PN = "1";
"B":   PN = "2"  !CDS_PN = "2";
BODY = "Q_RES","I190": #LOCATION = "R95" !CDS_LOCATION = "R95" &SEC = "1" #&CDS_SEC = "1";
"A":   PN = "1"  !CDS_PN = "1";
"B":   PN = "2"  !CDS_PN = "2";
BODY = "SCONN288_DDR506112002KQ","I236": #LOCATION = "J16" !CDS_LOCATION = "J16" &SEC = "2" #&CDS_SEC = "2";
"DQS0_A_C":   PN = "12"  !CDS_PN = "12";
"DQS0_A_T":   PN = "11"  !CDS_PN = "11";
"DQS0_B_C":   PN = "105"  !CDS_PN = "105";
"DQS0_B_T":   PN = "104"  !CDS_PN = "104";
"DQS1_A_C":   PN = "23"  !CDS_PN = "23";
"DQS1_A_T":   PN = "22"  !CDS_PN = "22";
"DQS1_B_C":   PN = "116"  !CDS_PN = "116";
"DQS1_B_T":   PN = "115"  !CDS_PN = "115";
"DQS2_A_C":   PN = "34"  !CDS_PN = "34";
"DQS2_A_T":   PN = "33"  !CDS_PN = "33";
"DQS2_B_C":   PN = "127"  !CDS_PN = "127";
"DQS2_B_T":   PN = "126"  !CDS_PN = "126";
"DQS3_A_C":   PN = "45"  !CDS_PN = "45";
"DQS3_A_T":   PN = "44"  !CDS_PN = "44";
"DQS3_B_C":   PN = "138"  !CDS_PN = "138";
"DQS3_B_T":   PN = "137"  !CDS_PN = "137";
"DQS4_A_C":   PN = "56"  !CDS_PN = "56";
"DQS4_A_T":   PN = "55"  !CDS_PN = "55";
"DQS4_B_C":   PN = "238"  !CDS_PN = "238";
"DQS4_B_T":   PN = "239"  !CDS_PN = "239";
"DQS5_A_C||TDQS5_A_C||DQS5_A_T||TDQS5_A_T":   PN = "156"  !CDS_PN = "156";
"DQS5_A_T||TDQS5_A_T":   PN = "157"  !CDS_PN = "157";
"DQS5_B_C||TDQS5_B_C":   PN = "249"  !CDS_PN = "249";
"DQS5_B_T||TDQS5_B_T":   PN = "250"  !CDS_PN = "250";
"DQS6_A_C||TDQS6_A_C||DQS6_A_T||TDQS6_A_T":   PN = "167"  !CDS_PN = "167";
"DQS6_A_T||TDQS6_A_T":   PN = "168"  !CDS_PN = "168";
"DQS6_B_C||TDQS6_B_C":   PN = "260"  !CDS_PN = "260";
"DQS6_B_T||TDQS6_B_T":   PN = "261"  !CDS_PN = "261";
"DQS7_A_C||TDQS7_A_C":   PN = "178"  !CDS_PN = "178";
"DQS7_A_T||TDQS7_A_T":   PN = "179"  !CDS_PN = "179";
"DQS7_B_C||TDQS7_B_C":   PN = "271"  !CDS_PN = "271";
"DQS7_B_T||TDQS7_B_T":   PN = "272"  !CDS_PN = "272";
"DQS8_A_C||TDQS8_A_C":   PN = "189"  !CDS_PN = "189";
"DQS8_A_T||TDQS8_A_T":   PN = "190"  !CDS_PN = "190";
"DQS8_B_C||TDQS8_B_C":   PN = "282"  !CDS_PN = "282";
"DQS8_B_T||TDQS8_B_T":   PN = "283"  !CDS_PN = "283";
"DQS9_A_C||TDQS9_A_C":   PN = "200"  !CDS_PN = "200";
"DQS9_A_T||TDQS9_A_T":   PN = "201"  !CDS_PN = "201";
"DQS9_B_C||TDQS9_B_C":   PN = "94"  !CDS_PN = "94";
"DQS9_B_T||TDQS9_B_T||DBI4_B_N":   PN = "93"  !CDS_PN = "93";
BODY = "Q_CAP","I238": #LOCATION = "C157" !CDS_LOCATION = "C157" &SEC = "1" #&CDS_SEC = "1";
"A":   PN = "1"  !CDS_PN = "1";
"B":   PN = "2"  !CDS_PN = "2";
BODY = "Q_CAP","I239": #LOCATION = "C158" !CDS_LOCATION = "C158" &SEC = "1" #&CDS_SEC = "1";
"A":   PN = "1"  !CDS_PN = "1";
"B":   PN = "2"  !CDS_PN = "2";
BODY = "Q_RES","I242": #LOCATION = "R1574" !CDS_LOCATION = "R1574" &SEC = "1" #&CDS_SEC = "1";
"A":   PN = "1"  !CDS_PN = "1";
"B":   PN = "2"  !CDS_PN = "2";
BODY = "Q_RES","I243": #LOCATION = "R8038" !CDS_LOCATION = "R8038" &SEC = "1" #&CDS_SEC = "1";
"A":   PN = "1"  !CDS_PN = "1";
"B":   PN = "2"  !CDS_PN = "2";
BODY = "Q_RES","I248": #LOCATION = "R8083" !CDS_LOCATION = "R8083" &SEC = "1" #&CDS_SEC = "1";
"A":   PN = "1"  !CDS_PN = "1";
"B":   PN = "2"  !CDS_PN = "2";
BODY = "Q_RES","I249": #LOCATION = "R8085" !CDS_LOCATION = "R8085" &SEC = "1" #&CDS_SEC = "1";
"A":   PN = "1"  !CDS_PN = "1";
"B":   PN = "2"  !CDS_PN = "2";
BODY = "Q_RES","I250": #LOCATION = "R8084" !CDS_LOCATION = "R8084" &SEC = "1" #&CDS_SEC = "1";
"A":   PN = "1"  !CDS_PN = "1";
"B":   PN = "2"  !CDS_PN = "2";
BODY = "SCHOTTKY_12","I251": #LOCATION = "D8004" !CDS_LOCATION = "D8004" &SEC = "1" #&CDS_SEC = "1";
"A":   PN = "1"  !CDS_PN = "1";
"C":   PN = "2"  !CDS_PN = "2";
BODY = "Q_RES","I254": #LOCATION = "R1680" !CDS_LOCATION = "R1680" &SEC = "1" #&CDS_SEC = "1";
"A":   PN = "1"  !CDS_PN = "1";
"B":   PN = "2"  !CDS_PN = "2";
DRAWING = "@t6g_mb_lib.t6g(sch_1):page92";
BODY = "SCONN288_DDR506112002KQ","I22": #LOCATION = "J69" !CDS_LOCATION = "J69" &SEC = "1" #&CDS_SEC = "1";
"ALERT_N":   PN = "62"  !CDS_PN = "62";
"CA0_A":   PN = "66"  !CDS_PN = "66";
"CA0_B":   PN = "76"  !CDS_PN = "76";
"CA1_A":   PN = "211"  !CDS_PN = "211";
"CA1_B":   PN = "221"  !CDS_PN = "221";
"CA2_A":   PN = "68"  !CDS_PN = "68";
"CA2_B":   PN = "78"  !CDS_PN = "78";
"CA3_A":   PN = "213"  !CDS_PN = "213";
"CA3_B":   PN = "223"  !CDS_PN = "223";
"CA4_A":   PN = "70"  !CDS_PN = "70";
"CA4_B":   PN = "80"  !CDS_PN = "80";
"CA5_A":   PN = "215"  !CDS_PN = "215";
"CA5_B":   PN = "225"  !CDS_PN = "225";
"CA6_A":   PN = "72"  !CDS_PN = "72";
"CA6_B":   PN = "82"  !CDS_PN = "82";
"CB0_A":   PN = "51"  !CDS_PN = "51";
"CB0_B":   PN = "96"  !CDS_PN = "96";
"CB1_A":   PN = "53"  !CDS_PN = "53";
"CB1_B":   PN = "98"  !CDS_PN = "98";
"CB2_A":   PN = "196"  !CDS_PN = "196";
"CB2_B":   PN = "241"  !CDS_PN = "241";
"CB3_A":   PN = "198"  !CDS_PN = "198";
"CB3_B":   PN = "243"  !CDS_PN = "243";
"CB4_A":   PN = "58"  !CDS_PN = "58";
"CB4_B":   PN = "89"  !CDS_PN = "89";
"CB5_A":   PN = "60"  !CDS_PN = "60";
"CB5_B":   PN = "91"  !CDS_PN = "91";
"CB6_A":   PN = "203"  !CDS_PN = "203";
"CB6_B":   PN = "234"  !CDS_PN = "234";
"CB7_A":   PN = "205"  !CDS_PN = "205";
"CB7_B":   PN = "236"  !CDS_PN = "236";
"CK_C":   PN = "218"  !CDS_PN = "218";
"CK_T":   PN = "217"  !CDS_PN = "217";
"CS0_A_N":   PN = "64"  !CDS_PN = "64";
"CS0_B_N":   PN = "84"  !CDS_PN = "84";
"CS1_A_N":   PN = "209"  !CDS_PN = "209";
"CS1_B_N":   PN = "229"  !CDS_PN = "229";
"DQ0_A":   PN = "7"  !CDS_PN = "7";
"DQ0_B":   PN = "100"  !CDS_PN = "100";
"DQ1_A":   PN = "9"  !CDS_PN = "9";
"DQ1_B":   PN = "102"  !CDS_PN = "102";
"DQ2_A":   PN = "152"  !CDS_PN = "152";
"DQ2_B":   PN = "245"  !CDS_PN = "245";
"DQ3_A":   PN = "154"  !CDS_PN = "154";
"DQ3_B":   PN = "247"  !CDS_PN = "247";
"DQ4_A":   PN = "14"  !CDS_PN = "14";
"DQ4_B":   PN = "107"  !CDS_PN = "107";
"DQ5_A":   PN = "16"  !CDS_PN = "16";
"DQ5_B":   PN = "109"  !CDS_PN = "109";
"DQ6_A":   PN = "159"  !CDS_PN = "159";
"DQ6_B":   PN = "252"  !CDS_PN = "252";
"DQ7_A":   PN = "161"  !CDS_PN = "161";
"DQ7_B":   PN = "254"  !CDS_PN = "254";
"DQ8_A":   PN = "18"  !CDS_PN = "18";
"DQ8_B":   PN = "111"  !CDS_PN = "111";
"DQ9_A":   PN = "20"  !CDS_PN = "20";
"DQ9_B":   PN = "113"  !CDS_PN = "113";
"DQ10_A":   PN = "163"  !CDS_PN = "163";
"DQ10_B":   PN = "256"  !CDS_PN = "256";
"DQ11_A":   PN = "165"  !CDS_PN = "165";
"DQ11_B":   PN = "258"  !CDS_PN = "258";
"DQ12_A":   PN = "25"  !CDS_PN = "25";
"DQ12_B":   PN = "118"  !CDS_PN = "118";
"DQ13_A":   PN = "27"  !CDS_PN = "27";
"DQ13_B":   PN = "120"  !CDS_PN = "120";
"DQ14_A":   PN = "170"  !CDS_PN = "170";
"DQ14_B":   PN = "263"  !CDS_PN = "263";
"DQ15_A":   PN = "172"  !CDS_PN = "172";
"DQ15_B":   PN = "265"  !CDS_PN = "265";
"DQ16_A":   PN = "29"  !CDS_PN = "29";
"DQ16_B":   PN = "122"  !CDS_PN = "122";
"DQ17_A":   PN = "31"  !CDS_PN = "31";
"DQ17_B":   PN = "124"  !CDS_PN = "124";
"DQ18_A":   PN = "174"  !CDS_PN = "174";
"DQ18_B":   PN = "267"  !CDS_PN = "267";
"DQ19_A":   PN = "176"  !CDS_PN = "176";
"DQ19_B":   PN = "269"  !CDS_PN = "269";
"DQ20_A":   PN = "36"  !CDS_PN = "36";
"DQ20_B":   PN = "129"  !CDS_PN = "129";
"DQ21_A":   PN = "38"  !CDS_PN = "38";
"DQ21_B":   PN = "131"  !CDS_PN = "131";
"DQ22_A":   PN = "181"  !CDS_PN = "181";
"DQ22_B":   PN = "274"  !CDS_PN = "274";
"DQ23_A":   PN = "183"  !CDS_PN = "183";
"DQ23_B":   PN = "276"  !CDS_PN = "276";
"DQ24_A":   PN = "40"  !CDS_PN = "40";
"DQ24_B":   PN = "133"  !CDS_PN = "133";
"DQ25_A":   PN = "42"  !CDS_PN = "42";
"DQ25_B":   PN = "135"  !CDS_PN = "135";
"DQ26_A":   PN = "185"  !CDS_PN = "185";
"DQ26_B":   PN = "278"  !CDS_PN = "278";
"DQ27_A":   PN = "187"  !CDS_PN = "187";
"DQ27_B":   PN = "280"  !CDS_PN = "280";
"DQ28_A":   PN = "47"  !CDS_PN = "47";
"DQ28_B":   PN = "140"  !CDS_PN = "140";
"DQ29_A":   PN = "49"  !CDS_PN = "49";
"DQ29_B":   PN = "142"  !CDS_PN = "142";
"DQ30_A":   PN = "192"  !CDS_PN = "192";
"DQ30_B":   PN = "285"  !CDS_PN = "285";
"DQ31_A":   PN = "194"  !CDS_PN = "194";
"DQ31_B":   PN = "287"  !CDS_PN = "287";
"HAS":   PN = "148"  !CDS_PN = "148";
"HSCL":   PN = "4"  !CDS_PN = "4";
"HSDA":   PN = "5"  !CDS_PN = "5";
"LBD||RSP_A_N":   PN = "86"  !CDS_PN = "86";
"LBS||RSP_B_N":   PN = "87"  !CDS_PN = "87";
"PAR_A":   PN = "74"  !CDS_PN = "74";
"PAR_B":   PN = "227"  !CDS_PN = "227";
"PWR_GOOD||FAIL_N":   PN = "147"  !CDS_PN = "147";
"RESET_N":   PN = "207"  !CDS_PN = "207";
"RFU0":   PN = "2"  !CDS_PN = "2";
"RFU1":   PN = "144"  !CDS_PN = "144";
"RFU2":   PN = "149"  !CDS_PN = "149";
"RFU3":   PN = "150"  !CDS_PN = "150";
"RFU4":   PN = "220"  !CDS_PN = "220";
"RFU5":   PN = "231"  !CDS_PN = "231";
"RFU6":   PN = "232"  !CDS_PN = "232";
"VIN_MGMT":   PN = "3"  !CDS_PN = "3";
BODY = "Q_RES","I129": #LOCATION = "R765" !CDS_LOCATION = "R765" &SEC = "1" #&CDS_SEC = "1";
"A":   PN = "1"  !CDS_PN = "1";
"B":   PN = "2"  !CDS_PN = "2";
BODY = "SCONN288_DDR506112002KQ","I177": #LOCATION = "J69" !CDS_LOCATION = "J69" &SEC = "3" #&CDS_SEC = "3";
"G1":   PN = "G1"  !CDS_PN = "G1";
"G2":   PN = "G2"  !CDS_PN = "G2";
"G3":   PN = "G3"  !CDS_PN = "G3";
"VIN_BULK0":   PN = "1"  !CDS_PN = "1";
"VIN_BULK1":   PN = "145"  !CDS_PN = "145";
"VIN_BULK2":   PN = "146"  !CDS_PN = "146";
"VSS0":   PN = "6"  !CDS_PN = "6";
"VSS1":   PN = "8"  !CDS_PN = "8";
"VSS2":   PN = "10"  !CDS_PN = "10";
"VSS3":   PN = "13"  !CDS_PN = "13";
"VSS4":   PN = "15"  !CDS_PN = "15";
"VSS5":   PN = "17"  !CDS_PN = "17";
"VSS6":   PN = "19"  !CDS_PN = "19";
"VSS7":   PN = "21"  !CDS_PN = "21";
"VSS8":   PN = "24"  !CDS_PN = "24";
"VSS9":   PN = "26"  !CDS_PN = "26";
"VSS10":   PN = "28"  !CDS_PN = "28";
"VSS11":   PN = "30"  !CDS_PN = "30";
"VSS12":   PN = "32"  !CDS_PN = "32";
"VSS13":   PN = "35"  !CDS_PN = "35";
"VSS14":   PN = "37"  !CDS_PN = "37";
"VSS15":   PN = "39"  !CDS_PN = "39";
"VSS16":   PN = "41"  !CDS_PN = "41";
"VSS17":   PN = "43"  !CDS_PN = "43";
"VSS18":   PN = "46"  !CDS_PN = "46";
"VSS19":   PN = "48"  !CDS_PN = "48";
"VSS20":   PN = "50"  !CDS_PN = "50";
"VSS21":   PN = "52"  !CDS_PN = "52";
"VSS22":   PN = "54"  !CDS_PN = "54";
"VSS23":   PN = "57"  !CDS_PN = "57";
"VSS24":   PN = "59"  !CDS_PN = "59";
"VSS25":   PN = "61"  !CDS_PN = "61";
"VSS26":   PN = "63"  !CDS_PN = "63";
"VSS27":   PN = "65"  !CDS_PN = "65";
"VSS28":   PN = "67"  !CDS_PN = "67";
"VSS29":   PN = "69"  !CDS_PN = "69";
"VSS30":   PN = "71"  !CDS_PN = "71";
"VSS31":   PN = "73"  !CDS_PN = "73";
"VSS32":   PN = "75"  !CDS_PN = "75";
"VSS33":   PN = "77"  !CDS_PN = "77";
"VSS34":   PN = "79"  !CDS_PN = "79";
"VSS35":   PN = "81"  !CDS_PN = "81";
"VSS36":   PN = "83"  !CDS_PN = "83";
"VSS37":   PN = "85"  !CDS_PN = "85";
"VSS38":   PN = "88"  !CDS_PN = "88";
"VSS39":   PN = "90"  !CDS_PN = "90";
"VSS40":   PN = "92"  !CDS_PN = "92";
"VSS41":   PN = "95"  !CDS_PN = "95";
"VSS42":   PN = "97"  !CDS_PN = "97";
"VSS43":   PN = "99"  !CDS_PN = "99";
"VSS44":   PN = "101"  !CDS_PN = "101";
"VSS45":   PN = "103"  !CDS_PN = "103";
"VSS46":   PN = "106"  !CDS_PN = "106";
"VSS47":   PN = "108"  !CDS_PN = "108";
"VSS48":   PN = "110"  !CDS_PN = "110";
"VSS49":   PN = "112"  !CDS_PN = "112";
"VSS50":   PN = "114"  !CDS_PN = "114";
"VSS51":   PN = "117"  !CDS_PN = "117";
"VSS52":   PN = "119"  !CDS_PN = "119";
"VSS53":   PN = "121"  !CDS_PN = "121";
"VSS54":   PN = "123"  !CDS_PN = "123";
"VSS55":   PN = "125"  !CDS_PN = "125";
"VSS56":   PN = "128"  !CDS_PN = "128";
"VSS57":   PN = "130"  !CDS_PN = "130";
"VSS58":   PN = "132"  !CDS_PN = "132";
"VSS59":   PN = "134"  !CDS_PN = "134";
"VSS60":   PN = "136"  !CDS_PN = "136";
"VSS61":   PN = "139"  !CDS_PN = "139";
"VSS62":   PN = "141"  !CDS_PN = "141";
"VSS63":   PN = "143"  !CDS_PN = "143";
"VSS64":   PN = "151"  !CDS_PN = "151";
"VSS65":   PN = "153"  !CDS_PN = "153";
"VSS66":   PN = "155"  !CDS_PN = "155";
"VSS67":   PN = "158"  !CDS_PN = "158";
"VSS68":   PN = "160"  !CDS_PN = "160";
"VSS69":   PN = "162"  !CDS_PN = "162";
"VSS70":   PN = "164"  !CDS_PN = "164";
"VSS71":   PN = "166"  !CDS_PN = "166";
"VSS72":   PN = "169"  !CDS_PN = "169";
"VSS73":   PN = "171"  !CDS_PN = "171";
"VSS74":   PN = "173"  !CDS_PN = "173";
"VSS75":   PN = "175"  !CDS_PN = "175";
"VSS76":   PN = "177"  !CDS_PN = "177";
"VSS77":   PN = "180"  !CDS_PN = "180";
"VSS78":   PN = "182"  !CDS_PN = "182";
"VSS79":   PN = "184"  !CDS_PN = "184";
"VSS80":   PN = "186"  !CDS_PN = "186";
"VSS81":   PN = "188"  !CDS_PN = "188";
"VSS82":   PN = "191"  !CDS_PN = "191";
"VSS83":   PN = "193"  !CDS_PN = "193";
"VSS84":   PN = "195"  !CDS_PN = "195";
"VSS85":   PN = "197"  !CDS_PN = "197";
"VSS86":   PN = "199"  !CDS_PN = "199";
"VSS87":   PN = "202"  !CDS_PN = "202";
"VSS88":   PN = "204"  !CDS_PN = "204";
"VSS89":   PN = "206"  !CDS_PN = "206";
"VSS90":   PN = "208"  !CDS_PN = "208";
"VSS91":   PN = "210"  !CDS_PN = "210";
"VSS92":   PN = "212"  !CDS_PN = "212";
"VSS93":   PN = "214"  !CDS_PN = "214";
"VSS94":   PN = "216"  !CDS_PN = "216";
"VSS95":   PN = "219"  !CDS_PN = "219";
"VSS96":   PN = "222"  !CDS_PN = "222";
"VSS97":   PN = "224"  !CDS_PN = "224";
"VSS98":   PN = "226"  !CDS_PN = "226";
"VSS99":   PN = "228"  !CDS_PN = "228";
"VSS100":   PN = "230"  !CDS_PN = "230";
"VSS101":   PN = "233"  !CDS_PN = "233";
"VSS102":   PN = "235"  !CDS_PN = "235";
"VSS103":   PN = "237"  !CDS_PN = "237";
"VSS104":   PN = "240"  !CDS_PN = "240";
"VSS105":   PN = "242"  !CDS_PN = "242";
"VSS106":   PN = "244"  !CDS_PN = "244";
"VSS107":   PN = "246"  !CDS_PN = "246";
"VSS108":   PN = "248"  !CDS_PN = "248";
"VSS109":   PN = "251"  !CDS_PN = "251";
"VSS110":   PN = "253"  !CDS_PN = "253";
"VSS111":   PN = "255"  !CDS_PN = "255";
"VSS112":   PN = "257"  !CDS_PN = "257";
"VSS113":   PN = "259"  !CDS_PN = "259";
"VSS114":   PN = "262"  !CDS_PN = "262";
"VSS115":   PN = "264"  !CDS_PN = "264";
"VSS116":   PN = "266"  !CDS_PN = "266";
"VSS117":   PN = "268"  !CDS_PN = "268";
"VSS118":   PN = "270"  !CDS_PN = "270";
"VSS119":   PN = "273"  !CDS_PN = "273";
"VSS120":   PN = "275"  !CDS_PN = "275";
"VSS121":   PN = "277"  !CDS_PN = "277";
"VSS122":   PN = "279"  !CDS_PN = "279";
"VSS123":   PN = "281"  !CDS_PN = "281";
"VSS124":   PN = "284"  !CDS_PN = "284";
"VSS125":   PN = "286"  !CDS_PN = "286";
"VSS126":   PN = "288"  !CDS_PN = "288";
BODY = "Q_CAP","I186": #LOCATION = "C116" !CDS_LOCATION = "C116" &SEC = "1" #&CDS_SEC = "1";
"A":   PN = "1"  !CDS_PN = "1";
"B":   PN = "2"  !CDS_PN = "2";
BODY = "Q_RES","I189": #LOCATION = "R298" !CDS_LOCATION = "R298" &SEC = "1" #&CDS_SEC = "1";
"A":   PN = "1"  !CDS_PN = "1";
"B":   PN = "2"  !CDS_PN = "2";
BODY = "Q_RES","I191": #LOCATION = "R97" !CDS_LOCATION = "R97" &SEC = "1" #&CDS_SEC = "1";
"A":   PN = "1"  !CDS_PN = "1";
"B":   PN = "2"  !CDS_PN = "2";
BODY = "SCONN288_DDR506112002KQ","I237": #LOCATION = "J69" !CDS_LOCATION = "J69" &SEC = "2" #&CDS_SEC = "2";
"DQS0_A_C":   PN = "12"  !CDS_PN = "12";
"DQS0_A_T":   PN = "11"  !CDS_PN = "11";
"DQS0_B_C":   PN = "105"  !CDS_PN = "105";
"DQS0_B_T":   PN = "104"  !CDS_PN = "104";
"DQS1_A_C":   PN = "23"  !CDS_PN = "23";
"DQS1_A_T":   PN = "22"  !CDS_PN = "22";
"DQS1_B_C":   PN = "116"  !CDS_PN = "116";
"DQS1_B_T":   PN = "115"  !CDS_PN = "115";
"DQS2_A_C":   PN = "34"  !CDS_PN = "34";
"DQS2_A_T":   PN = "33"  !CDS_PN = "33";
"DQS2_B_C":   PN = "127"  !CDS_PN = "127";
"DQS2_B_T":   PN = "126"  !CDS_PN = "126";
"DQS3_A_C":   PN = "45"  !CDS_PN = "45";
"DQS3_A_T":   PN = "44"  !CDS_PN = "44";
"DQS3_B_C":   PN = "138"  !CDS_PN = "138";
"DQS3_B_T":   PN = "137"  !CDS_PN = "137";
"DQS4_A_C":   PN = "56"  !CDS_PN = "56";
"DQS4_A_T":   PN = "55"  !CDS_PN = "55";
"DQS4_B_C":   PN = "238"  !CDS_PN = "238";
"DQS4_B_T":   PN = "239"  !CDS_PN = "239";
"DQS5_A_C||TDQS5_A_C||DQS5_A_T||TDQS5_A_T":   PN = "156"  !CDS_PN = "156";
"DQS5_A_T||TDQS5_A_T":   PN = "157"  !CDS_PN = "157";
"DQS5_B_C||TDQS5_B_C":   PN = "249"  !CDS_PN = "249";
"DQS5_B_T||TDQS5_B_T":   PN = "250"  !CDS_PN = "250";
"DQS6_A_C||TDQS6_A_C||DQS6_A_T||TDQS6_A_T":   PN = "167"  !CDS_PN = "167";
"DQS6_A_T||TDQS6_A_T":   PN = "168"  !CDS_PN = "168";
"DQS6_B_C||TDQS6_B_C":   PN = "260"  !CDS_PN = "260";
"DQS6_B_T||TDQS6_B_T":   PN = "261"  !CDS_PN = "261";
"DQS7_A_C||TDQS7_A_C":   PN = "178"  !CDS_PN = "178";
"DQS7_A_T||TDQS7_A_T":   PN = "179"  !CDS_PN = "179";
"DQS7_B_C||TDQS7_B_C":   PN = "271"  !CDS_PN = "271";
"DQS7_B_T||TDQS7_B_T":   PN = "272"  !CDS_PN = "272";
"DQS8_A_C||TDQS8_A_C":   PN = "189"  !CDS_PN = "189";
"DQS8_A_T||TDQS8_A_T":   PN = "190"  !CDS_PN = "190";
"DQS8_B_C||TDQS8_B_C":   PN = "282"  !CDS_PN = "282";
"DQS8_B_T||TDQS8_B_T":   PN = "283"  !CDS_PN = "283";
"DQS9_A_C||TDQS9_A_C":   PN = "200"  !CDS_PN = "200";
"DQS9_A_T||TDQS9_A_T":   PN = "201"  !CDS_PN = "201";
"DQS9_B_C||TDQS9_B_C":   PN = "94"  !CDS_PN = "94";
"DQS9_B_T||TDQS9_B_T||DBI4_B_N":   PN = "93"  !CDS_PN = "93";
BODY = "Q_CAP","I239": #LOCATION = "C159" !CDS_LOCATION = "C159" &SEC = "1" #&CDS_SEC = "1";
"A":   PN = "1"  !CDS_PN = "1";
"B":   PN = "2"  !CDS_PN = "2";
BODY = "Q_CAP","I240": #LOCATION = "C161" !CDS_LOCATION = "C161" &SEC = "1" #&CDS_SEC = "1";
"A":   PN = "1"  !CDS_PN = "1";
"B":   PN = "2"  !CDS_PN = "2";
BODY = "Q_RES","I243": #LOCATION = "R1575" !CDS_LOCATION = "R1575" &SEC = "1" #&CDS_SEC = "1";
"A":   PN = "1"  !CDS_PN = "1";
"B":   PN = "2"  !CDS_PN = "2";
BODY = "Q_RES","I244": #LOCATION = "R1681" !CDS_LOCATION = "R1681" &SEC = "1" #&CDS_SEC = "1";
"A":   PN = "1"  !CDS_PN = "1";
"B":   PN = "2"  !CDS_PN = "2";
DRAWING = "@t6g_mb_lib.t6g(sch_1):page93";
BODY = "SCONN288_DDR506112002KQ","I22": #LOCATION = "J18" !CDS_LOCATION = "J18" &SEC = "1" #&CDS_SEC = "1";
"ALERT_N":   PN = "62"  !CDS_PN = "62";
"CA0_A":   PN = "66"  !CDS_PN = "66";
"CA0_B":   PN = "76"  !CDS_PN = "76";
"CA1_A":   PN = "211"  !CDS_PN = "211";
"CA1_B":   PN = "221"  !CDS_PN = "221";
"CA2_A":   PN = "68"  !CDS_PN = "68";
"CA2_B":   PN = "78"  !CDS_PN = "78";
"CA3_A":   PN = "213"  !CDS_PN = "213";
"CA3_B":   PN = "223"  !CDS_PN = "223";
"CA4_A":   PN = "70"  !CDS_PN = "70";
"CA4_B":   PN = "80"  !CDS_PN = "80";
"CA5_A":   PN = "215"  !CDS_PN = "215";
"CA5_B":   PN = "225"  !CDS_PN = "225";
"CA6_A":   PN = "72"  !CDS_PN = "72";
"CA6_B":   PN = "82"  !CDS_PN = "82";
"CB0_A":   PN = "51"  !CDS_PN = "51";
"CB0_B":   PN = "96"  !CDS_PN = "96";
"CB1_A":   PN = "53"  !CDS_PN = "53";
"CB1_B":   PN = "98"  !CDS_PN = "98";
"CB2_A":   PN = "196"  !CDS_PN = "196";
"CB2_B":   PN = "241"  !CDS_PN = "241";
"CB3_A":   PN = "198"  !CDS_PN = "198";
"CB3_B":   PN = "243"  !CDS_PN = "243";
"CB4_A":   PN = "58"  !CDS_PN = "58";
"CB4_B":   PN = "89"  !CDS_PN = "89";
"CB5_A":   PN = "60"  !CDS_PN = "60";
"CB5_B":   PN = "91"  !CDS_PN = "91";
"CB6_A":   PN = "203"  !CDS_PN = "203";
"CB6_B":   PN = "234"  !CDS_PN = "234";
"CB7_A":   PN = "205"  !CDS_PN = "205";
"CB7_B":   PN = "236"  !CDS_PN = "236";
"CK_C":   PN = "218"  !CDS_PN = "218";
"CK_T":   PN = "217"  !CDS_PN = "217";
"CS0_A_N":   PN = "64"  !CDS_PN = "64";
"CS0_B_N":   PN = "84"  !CDS_PN = "84";
"CS1_A_N":   PN = "209"  !CDS_PN = "209";
"CS1_B_N":   PN = "229"  !CDS_PN = "229";
"DQ0_A":   PN = "7"  !CDS_PN = "7";
"DQ0_B":   PN = "100"  !CDS_PN = "100";
"DQ1_A":   PN = "9"  !CDS_PN = "9";
"DQ1_B":   PN = "102"  !CDS_PN = "102";
"DQ2_A":   PN = "152"  !CDS_PN = "152";
"DQ2_B":   PN = "245"  !CDS_PN = "245";
"DQ3_A":   PN = "154"  !CDS_PN = "154";
"DQ3_B":   PN = "247"  !CDS_PN = "247";
"DQ4_A":   PN = "14"  !CDS_PN = "14";
"DQ4_B":   PN = "107"  !CDS_PN = "107";
"DQ5_A":   PN = "16"  !CDS_PN = "16";
"DQ5_B":   PN = "109"  !CDS_PN = "109";
"DQ6_A":   PN = "159"  !CDS_PN = "159";
"DQ6_B":   PN = "252"  !CDS_PN = "252";
"DQ7_A":   PN = "161"  !CDS_PN = "161";
"DQ7_B":   PN = "254"  !CDS_PN = "254";
"DQ8_A":   PN = "18"  !CDS_PN = "18";
"DQ8_B":   PN = "111"  !CDS_PN = "111";
"DQ9_A":   PN = "20"  !CDS_PN = "20";
"DQ9_B":   PN = "113"  !CDS_PN = "113";
"DQ10_A":   PN = "163"  !CDS_PN = "163";
"DQ10_B":   PN = "256"  !CDS_PN = "256";
"DQ11_A":   PN = "165"  !CDS_PN = "165";
"DQ11_B":   PN = "258"  !CDS_PN = "258";
"DQ12_A":   PN = "25"  !CDS_PN = "25";
"DQ12_B":   PN = "118"  !CDS_PN = "118";
"DQ13_A":   PN = "27"  !CDS_PN = "27";
"DQ13_B":   PN = "120"  !CDS_PN = "120";
"DQ14_A":   PN = "170"  !CDS_PN = "170";
"DQ14_B":   PN = "263"  !CDS_PN = "263";
"DQ15_A":   PN = "172"  !CDS_PN = "172";
"DQ15_B":   PN = "265"  !CDS_PN = "265";
"DQ16_A":   PN = "29"  !CDS_PN = "29";
"DQ16_B":   PN = "122"  !CDS_PN = "122";
"DQ17_A":   PN = "31"  !CDS_PN = "31";
"DQ17_B":   PN = "124"  !CDS_PN = "124";
"DQ18_A":   PN = "174"  !CDS_PN = "174";
"DQ18_B":   PN = "267"  !CDS_PN = "267";
"DQ19_A":   PN = "176"  !CDS_PN = "176";
"DQ19_B":   PN = "269"  !CDS_PN = "269";
"DQ20_A":   PN = "36"  !CDS_PN = "36";
"DQ20_B":   PN = "129"  !CDS_PN = "129";
"DQ21_A":   PN = "38"  !CDS_PN = "38";
"DQ21_B":   PN = "131"  !CDS_PN = "131";
"DQ22_A":   PN = "181"  !CDS_PN = "181";
"DQ22_B":   PN = "274"  !CDS_PN = "274";
"DQ23_A":   PN = "183"  !CDS_PN = "183";
"DQ23_B":   PN = "276"  !CDS_PN = "276";
"DQ24_A":   PN = "40"  !CDS_PN = "40";
"DQ24_B":   PN = "133"  !CDS_PN = "133";
"DQ25_A":   PN = "42"  !CDS_PN = "42";
"DQ25_B":   PN = "135"  !CDS_PN = "135";
"DQ26_A":   PN = "185"  !CDS_PN = "185";
"DQ26_B":   PN = "278"  !CDS_PN = "278";
"DQ27_A":   PN = "187"  !CDS_PN = "187";
"DQ27_B":   PN = "280"  !CDS_PN = "280";
"DQ28_A":   PN = "47"  !CDS_PN = "47";
"DQ28_B":   PN = "140"  !CDS_PN = "140";
"DQ29_A":   PN = "49"  !CDS_PN = "49";
"DQ29_B":   PN = "142"  !CDS_PN = "142";
"DQ30_A":   PN = "192"  !CDS_PN = "192";
"DQ30_B":   PN = "285"  !CDS_PN = "285";
"DQ31_A":   PN = "194"  !CDS_PN = "194";
"DQ31_B":   PN = "287"  !CDS_PN = "287";
"HAS":   PN = "148"  !CDS_PN = "148";
"HSCL":   PN = "4"  !CDS_PN = "4";
"HSDA":   PN = "5"  !CDS_PN = "5";
"LBD||RSP_A_N":   PN = "86"  !CDS_PN = "86";
"LBS||RSP_B_N":   PN = "87"  !CDS_PN = "87";
"PAR_A":   PN = "74"  !CDS_PN = "74";
"PAR_B":   PN = "227"  !CDS_PN = "227";
"PWR_GOOD||FAIL_N":   PN = "147"  !CDS_PN = "147";
"RESET_N":   PN = "207"  !CDS_PN = "207";
"RFU0":   PN = "2"  !CDS_PN = "2";
"RFU1":   PN = "144"  !CDS_PN = "144";
"RFU2":   PN = "149"  !CDS_PN = "149";
"RFU3":   PN = "150"  !CDS_PN = "150";
"RFU4":   PN = "220"  !CDS_PN = "220";
"RFU5":   PN = "231"  !CDS_PN = "231";
"RFU6":   PN = "232"  !CDS_PN = "232";
"VIN_MGMT":   PN = "3"  !CDS_PN = "3";
BODY = "Q_RES","I128": #LOCATION = "R766" !CDS_LOCATION = "R766" &SEC = "1" #&CDS_SEC = "1";
"A":   PN = "1"  !CDS_PN = "1";
"B":   PN = "2"  !CDS_PN = "2";
BODY = "SCONN288_DDR506112002KQ","I143": #LOCATION = "J18" !CDS_LOCATION = "J18" &SEC = "3" #&CDS_SEC = "3";
"G1":   PN = "G1"  !CDS_PN = "G1";
"G2":   PN = "G2"  !CDS_PN = "G2";
"G3":   PN = "G3"  !CDS_PN = "G3";
"VIN_BULK0":   PN = "1"  !CDS_PN = "1";
"VIN_BULK1":   PN = "145"  !CDS_PN = "145";
"VIN_BULK2":   PN = "146"  !CDS_PN = "146";
"VSS0":   PN = "6"  !CDS_PN = "6";
"VSS1":   PN = "8"  !CDS_PN = "8";
"VSS2":   PN = "10"  !CDS_PN = "10";
"VSS3":   PN = "13"  !CDS_PN = "13";
"VSS4":   PN = "15"  !CDS_PN = "15";
"VSS5":   PN = "17"  !CDS_PN = "17";
"VSS6":   PN = "19"  !CDS_PN = "19";
"VSS7":   PN = "21"  !CDS_PN = "21";
"VSS8":   PN = "24"  !CDS_PN = "24";
"VSS9":   PN = "26"  !CDS_PN = "26";
"VSS10":   PN = "28"  !CDS_PN = "28";
"VSS11":   PN = "30"  !CDS_PN = "30";
"VSS12":   PN = "32"  !CDS_PN = "32";
"VSS13":   PN = "35"  !CDS_PN = "35";
"VSS14":   PN = "37"  !CDS_PN = "37";
"VSS15":   PN = "39"  !CDS_PN = "39";
"VSS16":   PN = "41"  !CDS_PN = "41";
"VSS17":   PN = "43"  !CDS_PN = "43";
"VSS18":   PN = "46"  !CDS_PN = "46";
"VSS19":   PN = "48"  !CDS_PN = "48";
"VSS20":   PN = "50"  !CDS_PN = "50";
"VSS21":   PN = "52"  !CDS_PN = "52";
"VSS22":   PN = "54"  !CDS_PN = "54";
"VSS23":   PN = "57"  !CDS_PN = "57";
"VSS24":   PN = "59"  !CDS_PN = "59";
"VSS25":   PN = "61"  !CDS_PN = "61";
"VSS26":   PN = "63"  !CDS_PN = "63";
"VSS27":   PN = "65"  !CDS_PN = "65";
"VSS28":   PN = "67"  !CDS_PN = "67";
"VSS29":   PN = "69"  !CDS_PN = "69";
"VSS30":   PN = "71"  !CDS_PN = "71";
"VSS31":   PN = "73"  !CDS_PN = "73";
"VSS32":   PN = "75"  !CDS_PN = "75";
"VSS33":   PN = "77"  !CDS_PN = "77";
"VSS34":   PN = "79"  !CDS_PN = "79";
"VSS35":   PN = "81"  !CDS_PN = "81";
"VSS36":   PN = "83"  !CDS_PN = "83";
"VSS37":   PN = "85"  !CDS_PN = "85";
"VSS38":   PN = "88"  !CDS_PN = "88";
"VSS39":   PN = "90"  !CDS_PN = "90";
"VSS40":   PN = "92"  !CDS_PN = "92";
"VSS41":   PN = "95"  !CDS_PN = "95";
"VSS42":   PN = "97"  !CDS_PN = "97";
"VSS43":   PN = "99"  !CDS_PN = "99";
"VSS44":   PN = "101"  !CDS_PN = "101";
"VSS45":   PN = "103"  !CDS_PN = "103";
"VSS46":   PN = "106"  !CDS_PN = "106";
"VSS47":   PN = "108"  !CDS_PN = "108";
"VSS48":   PN = "110"  !CDS_PN = "110";
"VSS49":   PN = "112"  !CDS_PN = "112";
"VSS50":   PN = "114"  !CDS_PN = "114";
"VSS51":   PN = "117"  !CDS_PN = "117";
"VSS52":   PN = "119"  !CDS_PN = "119";
"VSS53":   PN = "121"  !CDS_PN = "121";
"VSS54":   PN = "123"  !CDS_PN = "123";
"VSS55":   PN = "125"  !CDS_PN = "125";
"VSS56":   PN = "128"  !CDS_PN = "128";
"VSS57":   PN = "130"  !CDS_PN = "130";
"VSS58":   PN = "132"  !CDS_PN = "132";
"VSS59":   PN = "134"  !CDS_PN = "134";
"VSS60":   PN = "136"  !CDS_PN = "136";
"VSS61":   PN = "139"  !CDS_PN = "139";
"VSS62":   PN = "141"  !CDS_PN = "141";
"VSS63":   PN = "143"  !CDS_PN = "143";
"VSS64":   PN = "151"  !CDS_PN = "151";
"VSS65":   PN = "153"  !CDS_PN = "153";
"VSS66":   PN = "155"  !CDS_PN = "155";
"VSS67":   PN = "158"  !CDS_PN = "158";
"VSS68":   PN = "160"  !CDS_PN = "160";
"VSS69":   PN = "162"  !CDS_PN = "162";
"VSS70":   PN = "164"  !CDS_PN = "164";
"VSS71":   PN = "166"  !CDS_PN = "166";
"VSS72":   PN = "169"  !CDS_PN = "169";
"VSS73":   PN = "171"  !CDS_PN = "171";
"VSS74":   PN = "173"  !CDS_PN = "173";
"VSS75":   PN = "175"  !CDS_PN = "175";
"VSS76":   PN = "177"  !CDS_PN = "177";
"VSS77":   PN = "180"  !CDS_PN = "180";
"VSS78":   PN = "182"  !CDS_PN = "182";
"VSS79":   PN = "184"  !CDS_PN = "184";
"VSS80":   PN = "186"  !CDS_PN = "186";
"VSS81":   PN = "188"  !CDS_PN = "188";
"VSS82":   PN = "191"  !CDS_PN = "191";
"VSS83":   PN = "193"  !CDS_PN = "193";
"VSS84":   PN = "195"  !CDS_PN = "195";
"VSS85":   PN = "197"  !CDS_PN = "197";
"VSS86":   PN = "199"  !CDS_PN = "199";
"VSS87":   PN = "202"  !CDS_PN = "202";
"VSS88":   PN = "204"  !CDS_PN = "204";
"VSS89":   PN = "206"  !CDS_PN = "206";
"VSS90":   PN = "208"  !CDS_PN = "208";
"VSS91":   PN = "210"  !CDS_PN = "210";
"VSS92":   PN = "212"  !CDS_PN = "212";
"VSS93":   PN = "214"  !CDS_PN = "214";
"VSS94":   PN = "216"  !CDS_PN = "216";
"VSS95":   PN = "219"  !CDS_PN = "219";
"VSS96":   PN = "222"  !CDS_PN = "222";
"VSS97":   PN = "224"  !CDS_PN = "224";
"VSS98":   PN = "226"  !CDS_PN = "226";
"VSS99":   PN = "228"  !CDS_PN = "228";
"VSS100":   PN = "230"  !CDS_PN = "230";
"VSS101":   PN = "233"  !CDS_PN = "233";
"VSS102":   PN = "235"  !CDS_PN = "235";
"VSS103":   PN = "237"  !CDS_PN = "237";
"VSS104":   PN = "240"  !CDS_PN = "240";
"VSS105":   PN = "242"  !CDS_PN = "242";
"VSS106":   PN = "244"  !CDS_PN = "244";
"VSS107":   PN = "246"  !CDS_PN = "246";
"VSS108":   PN = "248"  !CDS_PN = "248";
"VSS109":   PN = "251"  !CDS_PN = "251";
"VSS110":   PN = "253"  !CDS_PN = "253";
"VSS111":   PN = "255"  !CDS_PN = "255";
"VSS112":   PN = "257"  !CDS_PN = "257";
"VSS113":   PN = "259"  !CDS_PN = "259";
"VSS114":   PN = "262"  !CDS_PN = "262";
"VSS115":   PN = "264"  !CDS_PN = "264";
"VSS116":   PN = "266"  !CDS_PN = "266";
"VSS117":   PN = "268"  !CDS_PN = "268";
"VSS118":   PN = "270"  !CDS_PN = "270";
"VSS119":   PN = "273"  !CDS_PN = "273";
"VSS120":   PN = "275"  !CDS_PN = "275";
"VSS121":   PN = "277"  !CDS_PN = "277";
"VSS122":   PN = "279"  !CDS_PN = "279";
"VSS123":   PN = "281"  !CDS_PN = "281";
"VSS124":   PN = "284"  !CDS_PN = "284";
"VSS125":   PN = "286"  !CDS_PN = "286";
"VSS126":   PN = "288"  !CDS_PN = "288";
BODY = "Q_CAP","I185": #LOCATION = "C120" !CDS_LOCATION = "C120" &SEC = "1" #&CDS_SEC = "1";
"A":   PN = "1"  !CDS_PN = "1";
"B":   PN = "2"  !CDS_PN = "2";
BODY = "Q_RES","I188": #LOCATION = "R299" !CDS_LOCATION = "R299" &SEC = "1" #&CDS_SEC = "1";
"A":   PN = "1"  !CDS_PN = "1";
"B":   PN = "2"  !CDS_PN = "2";
BODY = "Q_RES","I189": #LOCATION = "R98" !CDS_LOCATION = "R98" &SEC = "1" #&CDS_SEC = "1";
"A":   PN = "1"  !CDS_PN = "1";
"B":   PN = "2"  !CDS_PN = "2";
BODY = "SCONN288_DDR506112002KQ","I236": #LOCATION = "J18" !CDS_LOCATION = "J18" &SEC = "2" #&CDS_SEC = "2";
"DQS0_A_C":   PN = "12"  !CDS_PN = "12";
"DQS0_A_T":   PN = "11"  !CDS_PN = "11";
"DQS0_B_C":   PN = "105"  !CDS_PN = "105";
"DQS0_B_T":   PN = "104"  !CDS_PN = "104";
"DQS1_A_C":   PN = "23"  !CDS_PN = "23";
"DQS1_A_T":   PN = "22"  !CDS_PN = "22";
"DQS1_B_C":   PN = "116"  !CDS_PN = "116";
"DQS1_B_T":   PN = "115"  !CDS_PN = "115";
"DQS2_A_C":   PN = "34"  !CDS_PN = "34";
"DQS2_A_T":   PN = "33"  !CDS_PN = "33";
"DQS2_B_C":   PN = "127"  !CDS_PN = "127";
"DQS2_B_T":   PN = "126"  !CDS_PN = "126";
"DQS3_A_C":   PN = "45"  !CDS_PN = "45";
"DQS3_A_T":   PN = "44"  !CDS_PN = "44";
"DQS3_B_C":   PN = "138"  !CDS_PN = "138";
"DQS3_B_T":   PN = "137"  !CDS_PN = "137";
"DQS4_A_C":   PN = "56"  !CDS_PN = "56";
"DQS4_A_T":   PN = "55"  !CDS_PN = "55";
"DQS4_B_C":   PN = "238"  !CDS_PN = "238";
"DQS4_B_T":   PN = "239"  !CDS_PN = "239";
"DQS5_A_C||TDQS5_A_C||DQS5_A_T||TDQS5_A_T":   PN = "156"  !CDS_PN = "156";
"DQS5_A_T||TDQS5_A_T":   PN = "157"  !CDS_PN = "157";
"DQS5_B_C||TDQS5_B_C":   PN = "249"  !CDS_PN = "249";
"DQS5_B_T||TDQS5_B_T":   PN = "250"  !CDS_PN = "250";
"DQS6_A_C||TDQS6_A_C||DQS6_A_T||TDQS6_A_T":   PN = "167"  !CDS_PN = "167";
"DQS6_A_T||TDQS6_A_T":   PN = "168"  !CDS_PN = "168";
"DQS6_B_C||TDQS6_B_C":   PN = "260"  !CDS_PN = "260";
"DQS6_B_T||TDQS6_B_T":   PN = "261"  !CDS_PN = "261";
"DQS7_A_C||TDQS7_A_C":   PN = "178"  !CDS_PN = "178";
"DQS7_A_T||TDQS7_A_T":   PN = "179"  !CDS_PN = "179";
"DQS7_B_C||TDQS7_B_C":   PN = "271"  !CDS_PN = "271";
"DQS7_B_T||TDQS7_B_T":   PN = "272"  !CDS_PN = "272";
"DQS8_A_C||TDQS8_A_C":   PN = "189"  !CDS_PN = "189";
"DQS8_A_T||TDQS8_A_T":   PN = "190"  !CDS_PN = "190";
"DQS8_B_C||TDQS8_B_C":   PN = "282"  !CDS_PN = "282";
"DQS8_B_T||TDQS8_B_T":   PN = "283"  !CDS_PN = "283";
"DQS9_A_C||TDQS9_A_C":   PN = "200"  !CDS_PN = "200";
"DQS9_A_T||TDQS9_A_T":   PN = "201"  !CDS_PN = "201";
"DQS9_B_C||TDQS9_B_C":   PN = "94"  !CDS_PN = "94";
"DQS9_B_T||TDQS9_B_T||DBI4_B_N":   PN = "93"  !CDS_PN = "93";
BODY = "Q_CAP","I238": #LOCATION = "C162" !CDS_LOCATION = "C162" &SEC = "1" #&CDS_SEC = "1";
"A":   PN = "1"  !CDS_PN = "1";
"B":   PN = "2"  !CDS_PN = "2";
BODY = "Q_CAP","I239": #LOCATION = "C163" !CDS_LOCATION = "C163" &SEC = "1" #&CDS_SEC = "1";
"A":   PN = "1"  !CDS_PN = "1";
"B":   PN = "2"  !CDS_PN = "2";
BODY = "Q_RES","I242": #LOCATION = "R1576" !CDS_LOCATION = "R1576" &SEC = "1" #&CDS_SEC = "1";
"A":   PN = "1"  !CDS_PN = "1";
"B":   PN = "2"  !CDS_PN = "2";
BODY = "Q_RES","I243": #LOCATION = "R1683" !CDS_LOCATION = "R1683" &SEC = "1" #&CDS_SEC = "1";
"A":   PN = "1"  !CDS_PN = "1";
"B":   PN = "2"  !CDS_PN = "2";
DRAWING = "@t6g_mb_lib.t6g(sch_1):page94";
BODY = "SCONN288_DDR506112002KQ","I22": #LOCATION = "J68" !CDS_LOCATION = "J68" &SEC = "1" #&CDS_SEC = "1";
"ALERT_N":   PN = "62"  !CDS_PN = "62";
"CA0_A":   PN = "66"  !CDS_PN = "66";
"CA0_B":   PN = "76"  !CDS_PN = "76";
"CA1_A":   PN = "211"  !CDS_PN = "211";
"CA1_B":   PN = "221"  !CDS_PN = "221";
"CA2_A":   PN = "68"  !CDS_PN = "68";
"CA2_B":   PN = "78"  !CDS_PN = "78";
"CA3_A":   PN = "213"  !CDS_PN = "213";
"CA3_B":   PN = "223"  !CDS_PN = "223";
"CA4_A":   PN = "70"  !CDS_PN = "70";
"CA4_B":   PN = "80"  !CDS_PN = "80";
"CA5_A":   PN = "215"  !CDS_PN = "215";
"CA5_B":   PN = "225"  !CDS_PN = "225";
"CA6_A":   PN = "72"  !CDS_PN = "72";
"CA6_B":   PN = "82"  !CDS_PN = "82";
"CB0_A":   PN = "51"  !CDS_PN = "51";
"CB0_B":   PN = "96"  !CDS_PN = "96";
"CB1_A":   PN = "53"  !CDS_PN = "53";
"CB1_B":   PN = "98"  !CDS_PN = "98";
"CB2_A":   PN = "196"  !CDS_PN = "196";
"CB2_B":   PN = "241"  !CDS_PN = "241";
"CB3_A":   PN = "198"  !CDS_PN = "198";
"CB3_B":   PN = "243"  !CDS_PN = "243";
"CB4_A":   PN = "58"  !CDS_PN = "58";
"CB4_B":   PN = "89"  !CDS_PN = "89";
"CB5_A":   PN = "60"  !CDS_PN = "60";
"CB5_B":   PN = "91"  !CDS_PN = "91";
"CB6_A":   PN = "203"  !CDS_PN = "203";
"CB6_B":   PN = "234"  !CDS_PN = "234";
"CB7_A":   PN = "205"  !CDS_PN = "205";
"CB7_B":   PN = "236"  !CDS_PN = "236";
"CK_C":   PN = "218"  !CDS_PN = "218";
"CK_T":   PN = "217"  !CDS_PN = "217";
"CS0_A_N":   PN = "64"  !CDS_PN = "64";
"CS0_B_N":   PN = "84"  !CDS_PN = "84";
"CS1_A_N":   PN = "209"  !CDS_PN = "209";
"CS1_B_N":   PN = "229"  !CDS_PN = "229";
"DQ0_A":   PN = "7"  !CDS_PN = "7";
"DQ0_B":   PN = "100"  !CDS_PN = "100";
"DQ1_A":   PN = "9"  !CDS_PN = "9";
"DQ1_B":   PN = "102"  !CDS_PN = "102";
"DQ2_A":   PN = "152"  !CDS_PN = "152";
"DQ2_B":   PN = "245"  !CDS_PN = "245";
"DQ3_A":   PN = "154"  !CDS_PN = "154";
"DQ3_B":   PN = "247"  !CDS_PN = "247";
"DQ4_A":   PN = "14"  !CDS_PN = "14";
"DQ4_B":   PN = "107"  !CDS_PN = "107";
"DQ5_A":   PN = "16"  !CDS_PN = "16";
"DQ5_B":   PN = "109"  !CDS_PN = "109";
"DQ6_A":   PN = "159"  !CDS_PN = "159";
"DQ6_B":   PN = "252"  !CDS_PN = "252";
"DQ7_A":   PN = "161"  !CDS_PN = "161";
"DQ7_B":   PN = "254"  !CDS_PN = "254";
"DQ8_A":   PN = "18"  !CDS_PN = "18";
"DQ8_B":   PN = "111"  !CDS_PN = "111";
"DQ9_A":   PN = "20"  !CDS_PN = "20";
"DQ9_B":   PN = "113"  !CDS_PN = "113";
"DQ10_A":   PN = "163"  !CDS_PN = "163";
"DQ10_B":   PN = "256"  !CDS_PN = "256";
"DQ11_A":   PN = "165"  !CDS_PN = "165";
"DQ11_B":   PN = "258"  !CDS_PN = "258";
"DQ12_A":   PN = "25"  !CDS_PN = "25";
"DQ12_B":   PN = "118"  !CDS_PN = "118";
"DQ13_A":   PN = "27"  !CDS_PN = "27";
"DQ13_B":   PN = "120"  !CDS_PN = "120";
"DQ14_A":   PN = "170"  !CDS_PN = "170";
"DQ14_B":   PN = "263"  !CDS_PN = "263";
"DQ15_A":   PN = "172"  !CDS_PN = "172";
"DQ15_B":   PN = "265"  !CDS_PN = "265";
"DQ16_A":   PN = "29"  !CDS_PN = "29";
"DQ16_B":   PN = "122"  !CDS_PN = "122";
"DQ17_A":   PN = "31"  !CDS_PN = "31";
"DQ17_B":   PN = "124"  !CDS_PN = "124";
"DQ18_A":   PN = "174"  !CDS_PN = "174";
"DQ18_B":   PN = "267"  !CDS_PN = "267";
"DQ19_A":   PN = "176"  !CDS_PN = "176";
"DQ19_B":   PN = "269"  !CDS_PN = "269";
"DQ20_A":   PN = "36"  !CDS_PN = "36";
"DQ20_B":   PN = "129"  !CDS_PN = "129";
"DQ21_A":   PN = "38"  !CDS_PN = "38";
"DQ21_B":   PN = "131"  !CDS_PN = "131";
"DQ22_A":   PN = "181"  !CDS_PN = "181";
"DQ22_B":   PN = "274"  !CDS_PN = "274";
"DQ23_A":   PN = "183"  !CDS_PN = "183";
"DQ23_B":   PN = "276"  !CDS_PN = "276";
"DQ24_A":   PN = "40"  !CDS_PN = "40";
"DQ24_B":   PN = "133"  !CDS_PN = "133";
"DQ25_A":   PN = "42"  !CDS_PN = "42";
"DQ25_B":   PN = "135"  !CDS_PN = "135";
"DQ26_A":   PN = "185"  !CDS_PN = "185";
"DQ26_B":   PN = "278"  !CDS_PN = "278";
"DQ27_A":   PN = "187"  !CDS_PN = "187";
"DQ27_B":   PN = "280"  !CDS_PN = "280";
"DQ28_A":   PN = "47"  !CDS_PN = "47";
"DQ28_B":   PN = "140"  !CDS_PN = "140";
"DQ29_A":   PN = "49"  !CDS_PN = "49";
"DQ29_B":   PN = "142"  !CDS_PN = "142";
"DQ30_A":   PN = "192"  !CDS_PN = "192";
"DQ30_B":   PN = "285"  !CDS_PN = "285";
"DQ31_A":   PN = "194"  !CDS_PN = "194";
"DQ31_B":   PN = "287"  !CDS_PN = "287";
"HAS":   PN = "148"  !CDS_PN = "148";
"HSCL":   PN = "4"  !CDS_PN = "4";
"HSDA":   PN = "5"  !CDS_PN = "5";
"LBD||RSP_A_N":   PN = "86"  !CDS_PN = "86";
"LBS||RSP_B_N":   PN = "87"  !CDS_PN = "87";
"PAR_A":   PN = "74"  !CDS_PN = "74";
"PAR_B":   PN = "227"  !CDS_PN = "227";
"PWR_GOOD||FAIL_N":   PN = "147"  !CDS_PN = "147";
"RESET_N":   PN = "207"  !CDS_PN = "207";
"RFU0":   PN = "2"  !CDS_PN = "2";
"RFU1":   PN = "144"  !CDS_PN = "144";
"RFU2":   PN = "149"  !CDS_PN = "149";
"RFU3":   PN = "150"  !CDS_PN = "150";
"RFU4":   PN = "220"  !CDS_PN = "220";
"RFU5":   PN = "231"  !CDS_PN = "231";
"RFU6":   PN = "232"  !CDS_PN = "232";
"VIN_MGMT":   PN = "3"  !CDS_PN = "3";
BODY = "Q_RES","I129": #LOCATION = "R767" !CDS_LOCATION = "R767" &SEC = "1" #&CDS_SEC = "1";
"A":   PN = "1"  !CDS_PN = "1";
"B":   PN = "2"  !CDS_PN = "2";
BODY = "SCONN288_DDR506112002KQ","I177": #LOCATION = "J68" !CDS_LOCATION = "J68" &SEC = "3" #&CDS_SEC = "3";
"G1":   PN = "G1"  !CDS_PN = "G1";
"G2":   PN = "G2"  !CDS_PN = "G2";
"G3":   PN = "G3"  !CDS_PN = "G3";
"VIN_BULK0":   PN = "1"  !CDS_PN = "1";
"VIN_BULK1":   PN = "145"  !CDS_PN = "145";
"VIN_BULK2":   PN = "146"  !CDS_PN = "146";
"VSS0":   PN = "6"  !CDS_PN = "6";
"VSS1":   PN = "8"  !CDS_PN = "8";
"VSS2":   PN = "10"  !CDS_PN = "10";
"VSS3":   PN = "13"  !CDS_PN = "13";
"VSS4":   PN = "15"  !CDS_PN = "15";
"VSS5":   PN = "17"  !CDS_PN = "17";
"VSS6":   PN = "19"  !CDS_PN = "19";
"VSS7":   PN = "21"  !CDS_PN = "21";
"VSS8":   PN = "24"  !CDS_PN = "24";
"VSS9":   PN = "26"  !CDS_PN = "26";
"VSS10":   PN = "28"  !CDS_PN = "28";
"VSS11":   PN = "30"  !CDS_PN = "30";
"VSS12":   PN = "32"  !CDS_PN = "32";
"VSS13":   PN = "35"  !CDS_PN = "35";
"VSS14":   PN = "37"  !CDS_PN = "37";
"VSS15":   PN = "39"  !CDS_PN = "39";
"VSS16":   PN = "41"  !CDS_PN = "41";
"VSS17":   PN = "43"  !CDS_PN = "43";
"VSS18":   PN = "46"  !CDS_PN = "46";
"VSS19":   PN = "48"  !CDS_PN = "48";
"VSS20":   PN = "50"  !CDS_PN = "50";
"VSS21":   PN = "52"  !CDS_PN = "52";
"VSS22":   PN = "54"  !CDS_PN = "54";
"VSS23":   PN = "57"  !CDS_PN = "57";
"VSS24":   PN = "59"  !CDS_PN = "59";
"VSS25":   PN = "61"  !CDS_PN = "61";
"VSS26":   PN = "63"  !CDS_PN = "63";
"VSS27":   PN = "65"  !CDS_PN = "65";
"VSS28":   PN = "67"  !CDS_PN = "67";
"VSS29":   PN = "69"  !CDS_PN = "69";
"VSS30":   PN = "71"  !CDS_PN = "71";
"VSS31":   PN = "73"  !CDS_PN = "73";
"VSS32":   PN = "75"  !CDS_PN = "75";
"VSS33":   PN = "77"  !CDS_PN = "77";
"VSS34":   PN = "79"  !CDS_PN = "79";
"VSS35":   PN = "81"  !CDS_PN = "81";
"VSS36":   PN = "83"  !CDS_PN = "83";
"VSS37":   PN = "85"  !CDS_PN = "85";
"VSS38":   PN = "88"  !CDS_PN = "88";
"VSS39":   PN = "90"  !CDS_PN = "90";
"VSS40":   PN = "92"  !CDS_PN = "92";
"VSS41":   PN = "95"  !CDS_PN = "95";
"VSS42":   PN = "97"  !CDS_PN = "97";
"VSS43":   PN = "99"  !CDS_PN = "99";
"VSS44":   PN = "101"  !CDS_PN = "101";
"VSS45":   PN = "103"  !CDS_PN = "103";
"VSS46":   PN = "106"  !CDS_PN = "106";
"VSS47":   PN = "108"  !CDS_PN = "108";
"VSS48":   PN = "110"  !CDS_PN = "110";
"VSS49":   PN = "112"  !CDS_PN = "112";
"VSS50":   PN = "114"  !CDS_PN = "114";
"VSS51":   PN = "117"  !CDS_PN = "117";
"VSS52":   PN = "119"  !CDS_PN = "119";
"VSS53":   PN = "121"  !CDS_PN = "121";
"VSS54":   PN = "123"  !CDS_PN = "123";
"VSS55":   PN = "125"  !CDS_PN = "125";
"VSS56":   PN = "128"  !CDS_PN = "128";
"VSS57":   PN = "130"  !CDS_PN = "130";
"VSS58":   PN = "132"  !CDS_PN = "132";
"VSS59":   PN = "134"  !CDS_PN = "134";
"VSS60":   PN = "136"  !CDS_PN = "136";
"VSS61":   PN = "139"  !CDS_PN = "139";
"VSS62":   PN = "141"  !CDS_PN = "141";
"VSS63":   PN = "143"  !CDS_PN = "143";
"VSS64":   PN = "151"  !CDS_PN = "151";
"VSS65":   PN = "153"  !CDS_PN = "153";
"VSS66":   PN = "155"  !CDS_PN = "155";
"VSS67":   PN = "158"  !CDS_PN = "158";
"VSS68":   PN = "160"  !CDS_PN = "160";
"VSS69":   PN = "162"  !CDS_PN = "162";
"VSS70":   PN = "164"  !CDS_PN = "164";
"VSS71":   PN = "166"  !CDS_PN = "166";
"VSS72":   PN = "169"  !CDS_PN = "169";
"VSS73":   PN = "171"  !CDS_PN = "171";
"VSS74":   PN = "173"  !CDS_PN = "173";
"VSS75":   PN = "175"  !CDS_PN = "175";
"VSS76":   PN = "177"  !CDS_PN = "177";
"VSS77":   PN = "180"  !CDS_PN = "180";
"VSS78":   PN = "182"  !CDS_PN = "182";
"VSS79":   PN = "184"  !CDS_PN = "184";
"VSS80":   PN = "186"  !CDS_PN = "186";
"VSS81":   PN = "188"  !CDS_PN = "188";
"VSS82":   PN = "191"  !CDS_PN = "191";
"VSS83":   PN = "193"  !CDS_PN = "193";
"VSS84":   PN = "195"  !CDS_PN = "195";
"VSS85":   PN = "197"  !CDS_PN = "197";
"VSS86":   PN = "199"  !CDS_PN = "199";
"VSS87":   PN = "202"  !CDS_PN = "202";
"VSS88":   PN = "204"  !CDS_PN = "204";
"VSS89":   PN = "206"  !CDS_PN = "206";
"VSS90":   PN = "208"  !CDS_PN = "208";
"VSS91":   PN = "210"  !CDS_PN = "210";
"VSS92":   PN = "212"  !CDS_PN = "212";
"VSS93":   PN = "214"  !CDS_PN = "214";
"VSS94":   PN = "216"  !CDS_PN = "216";
"VSS95":   PN = "219"  !CDS_PN = "219";
"VSS96":   PN = "222"  !CDS_PN = "222";
"VSS97":   PN = "224"  !CDS_PN = "224";
"VSS98":   PN = "226"  !CDS_PN = "226";
"VSS99":   PN = "228"  !CDS_PN = "228";
"VSS100":   PN = "230"  !CDS_PN = "230";
"VSS101":   PN = "233"  !CDS_PN = "233";
"VSS102":   PN = "235"  !CDS_PN = "235";
"VSS103":   PN = "237"  !CDS_PN = "237";
"VSS104":   PN = "240"  !CDS_PN = "240";
"VSS105":   PN = "242"  !CDS_PN = "242";
"VSS106":   PN = "244"  !CDS_PN = "244";
"VSS107":   PN = "246"  !CDS_PN = "246";
"VSS108":   PN = "248"  !CDS_PN = "248";
"VSS109":   PN = "251"  !CDS_PN = "251";
"VSS110":   PN = "253"  !CDS_PN = "253";
"VSS111":   PN = "255"  !CDS_PN = "255";
"VSS112":   PN = "257"  !CDS_PN = "257";
"VSS113":   PN = "259"  !CDS_PN = "259";
"VSS114":   PN = "262"  !CDS_PN = "262";
"VSS115":   PN = "264"  !CDS_PN = "264";
"VSS116":   PN = "266"  !CDS_PN = "266";
"VSS117":   PN = "268"  !CDS_PN = "268";
"VSS118":   PN = "270"  !CDS_PN = "270";
"VSS119":   PN = "273"  !CDS_PN = "273";
"VSS120":   PN = "275"  !CDS_PN = "275";
"VSS121":   PN = "277"  !CDS_PN = "277";
"VSS122":   PN = "279"  !CDS_PN = "279";
"VSS123":   PN = "281"  !CDS_PN = "281";
"VSS124":   PN = "284"  !CDS_PN = "284";
"VSS125":   PN = "286"  !CDS_PN = "286";
"VSS126":   PN = "288"  !CDS_PN = "288";
BODY = "Q_CAP","I185": #LOCATION = "C124" !CDS_LOCATION = "C124" &SEC = "1" #&CDS_SEC = "1";
"A":   PN = "1"  !CDS_PN = "1";
"B":   PN = "2"  !CDS_PN = "2";
BODY = "Q_RES","I188": #LOCATION = "R300" !CDS_LOCATION = "R300" &SEC = "1" #&CDS_SEC = "1";
"A":   PN = "1"  !CDS_PN = "1";
"B":   PN = "2"  !CDS_PN = "2";
BODY = "Q_RES","I189": #LOCATION = "R99" !CDS_LOCATION = "R99" &SEC = "1" #&CDS_SEC = "1";
"A":   PN = "1"  !CDS_PN = "1";
"B":   PN = "2"  !CDS_PN = "2";
BODY = "SCONN288_DDR506112002KQ","I236": #LOCATION = "J68" !CDS_LOCATION = "J68" &SEC = "2" #&CDS_SEC = "2";
"DQS0_A_C":   PN = "12"  !CDS_PN = "12";
"DQS0_A_T":   PN = "11"  !CDS_PN = "11";
"DQS0_B_C":   PN = "105"  !CDS_PN = "105";
"DQS0_B_T":   PN = "104"  !CDS_PN = "104";
"DQS1_A_C":   PN = "23"  !CDS_PN = "23";
"DQS1_A_T":   PN = "22"  !CDS_PN = "22";
"DQS1_B_C":   PN = "116"  !CDS_PN = "116";
"DQS1_B_T":   PN = "115"  !CDS_PN = "115";
"DQS2_A_C":   PN = "34"  !CDS_PN = "34";
"DQS2_A_T":   PN = "33"  !CDS_PN = "33";
"DQS2_B_C":   PN = "127"  !CDS_PN = "127";
"DQS2_B_T":   PN = "126"  !CDS_PN = "126";
"DQS3_A_C":   PN = "45"  !CDS_PN = "45";
"DQS3_A_T":   PN = "44"  !CDS_PN = "44";
"DQS3_B_C":   PN = "138"  !CDS_PN = "138";
"DQS3_B_T":   PN = "137"  !CDS_PN = "137";
"DQS4_A_C":   PN = "56"  !CDS_PN = "56";
"DQS4_A_T":   PN = "55"  !CDS_PN = "55";
"DQS4_B_C":   PN = "238"  !CDS_PN = "238";
"DQS4_B_T":   PN = "239"  !CDS_PN = "239";
"DQS5_A_C||TDQS5_A_C||DQS5_A_T||TDQS5_A_T":   PN = "156"  !CDS_PN = "156";
"DQS5_A_T||TDQS5_A_T":   PN = "157"  !CDS_PN = "157";
"DQS5_B_C||TDQS5_B_C":   PN = "249"  !CDS_PN = "249";
"DQS5_B_T||TDQS5_B_T":   PN = "250"  !CDS_PN = "250";
"DQS6_A_C||TDQS6_A_C||DQS6_A_T||TDQS6_A_T":   PN = "167"  !CDS_PN = "167";
"DQS6_A_T||TDQS6_A_T":   PN = "168"  !CDS_PN = "168";
"DQS6_B_C||TDQS6_B_C":   PN = "260"  !CDS_PN = "260";
"DQS6_B_T||TDQS6_B_T":   PN = "261"  !CDS_PN = "261";
"DQS7_A_C||TDQS7_A_C":   PN = "178"  !CDS_PN = "178";
"DQS7_A_T||TDQS7_A_T":   PN = "179"  !CDS_PN = "179";
"DQS7_B_C||TDQS7_B_C":   PN = "271"  !CDS_PN = "271";
"DQS7_B_T||TDQS7_B_T":   PN = "272"  !CDS_PN = "272";
"DQS8_A_C||TDQS8_A_C":   PN = "189"  !CDS_PN = "189";
"DQS8_A_T||TDQS8_A_T":   PN = "190"  !CDS_PN = "190";
"DQS8_B_C||TDQS8_B_C":   PN = "282"  !CDS_PN = "282";
"DQS8_B_T||TDQS8_B_T":   PN = "283"  !CDS_PN = "283";
"DQS9_A_C||TDQS9_A_C":   PN = "200"  !CDS_PN = "200";
"DQS9_A_T||TDQS9_A_T":   PN = "201"  !CDS_PN = "201";
"DQS9_B_C||TDQS9_B_C":   PN = "94"  !CDS_PN = "94";
"DQS9_B_T||TDQS9_B_T||DBI4_B_N":   PN = "93"  !CDS_PN = "93";
BODY = "Q_CAP","I238": #LOCATION = "C165" !CDS_LOCATION = "C165" &SEC = "1" #&CDS_SEC = "1";
"A":   PN = "1"  !CDS_PN = "1";
"B":   PN = "2"  !CDS_PN = "2";
BODY = "Q_CAP","I239": #LOCATION = "C166" !CDS_LOCATION = "C166" &SEC = "1" #&CDS_SEC = "1";
"A":   PN = "1"  !CDS_PN = "1";
"B":   PN = "2"  !CDS_PN = "2";
BODY = "Q_RES","I242": #LOCATION = "R1577" !CDS_LOCATION = "R1577" &SEC = "1" #&CDS_SEC = "1";
"A":   PN = "1"  !CDS_PN = "1";
"B":   PN = "2"  !CDS_PN = "2";
BODY = "Q_RES","I243": #LOCATION = "R1684" !CDS_LOCATION = "R1684" &SEC = "1" #&CDS_SEC = "1";
"A":   PN = "1"  !CDS_PN = "1";
"B":   PN = "2"  !CDS_PN = "2";
DRAWING = "@t6g_mb_lib.t6g(sch_1):page95";
BODY = "SCONN288_DDR506112002KQ","I22": #LOCATION = "J20" !CDS_LOCATION = "J20" &SEC = "1" #&CDS_SEC = "1";
"ALERT_N":   PN = "62"  !CDS_PN = "62";
"CA0_A":   PN = "66"  !CDS_PN = "66";
"CA0_B":   PN = "76"  !CDS_PN = "76";
"CA1_A":   PN = "211"  !CDS_PN = "211";
"CA1_B":   PN = "221"  !CDS_PN = "221";
"CA2_A":   PN = "68"  !CDS_PN = "68";
"CA2_B":   PN = "78"  !CDS_PN = "78";
"CA3_A":   PN = "213"  !CDS_PN = "213";
"CA3_B":   PN = "223"  !CDS_PN = "223";
"CA4_A":   PN = "70"  !CDS_PN = "70";
"CA4_B":   PN = "80"  !CDS_PN = "80";
"CA5_A":   PN = "215"  !CDS_PN = "215";
"CA5_B":   PN = "225"  !CDS_PN = "225";
"CA6_A":   PN = "72"  !CDS_PN = "72";
"CA6_B":   PN = "82"  !CDS_PN = "82";
"CB0_A":   PN = "51"  !CDS_PN = "51";
"CB0_B":   PN = "96"  !CDS_PN = "96";
"CB1_A":   PN = "53"  !CDS_PN = "53";
"CB1_B":   PN = "98"  !CDS_PN = "98";
"CB2_A":   PN = "196"  !CDS_PN = "196";
"CB2_B":   PN = "241"  !CDS_PN = "241";
"CB3_A":   PN = "198"  !CDS_PN = "198";
"CB3_B":   PN = "243"  !CDS_PN = "243";
"CB4_A":   PN = "58"  !CDS_PN = "58";
"CB4_B":   PN = "89"  !CDS_PN = "89";
"CB5_A":   PN = "60"  !CDS_PN = "60";
"CB5_B":   PN = "91"  !CDS_PN = "91";
"CB6_A":   PN = "203"  !CDS_PN = "203";
"CB6_B":   PN = "234"  !CDS_PN = "234";
"CB7_A":   PN = "205"  !CDS_PN = "205";
"CB7_B":   PN = "236"  !CDS_PN = "236";
"CK_C":   PN = "218"  !CDS_PN = "218";
"CK_T":   PN = "217"  !CDS_PN = "217";
"CS0_A_N":   PN = "64"  !CDS_PN = "64";
"CS0_B_N":   PN = "84"  !CDS_PN = "84";
"CS1_A_N":   PN = "209"  !CDS_PN = "209";
"CS1_B_N":   PN = "229"  !CDS_PN = "229";
"DQ0_A":   PN = "7"  !CDS_PN = "7";
"DQ0_B":   PN = "100"  !CDS_PN = "100";
"DQ1_A":   PN = "9"  !CDS_PN = "9";
"DQ1_B":   PN = "102"  !CDS_PN = "102";
"DQ2_A":   PN = "152"  !CDS_PN = "152";
"DQ2_B":   PN = "245"  !CDS_PN = "245";
"DQ3_A":   PN = "154"  !CDS_PN = "154";
"DQ3_B":   PN = "247"  !CDS_PN = "247";
"DQ4_A":   PN = "14"  !CDS_PN = "14";
"DQ4_B":   PN = "107"  !CDS_PN = "107";
"DQ5_A":   PN = "16"  !CDS_PN = "16";
"DQ5_B":   PN = "109"  !CDS_PN = "109";
"DQ6_A":   PN = "159"  !CDS_PN = "159";
"DQ6_B":   PN = "252"  !CDS_PN = "252";
"DQ7_A":   PN = "161"  !CDS_PN = "161";
"DQ7_B":   PN = "254"  !CDS_PN = "254";
"DQ8_A":   PN = "18"  !CDS_PN = "18";
"DQ8_B":   PN = "111"  !CDS_PN = "111";
"DQ9_A":   PN = "20"  !CDS_PN = "20";
"DQ9_B":   PN = "113"  !CDS_PN = "113";
"DQ10_A":   PN = "163"  !CDS_PN = "163";
"DQ10_B":   PN = "256"  !CDS_PN = "256";
"DQ11_A":   PN = "165"  !CDS_PN = "165";
"DQ11_B":   PN = "258"  !CDS_PN = "258";
"DQ12_A":   PN = "25"  !CDS_PN = "25";
"DQ12_B":   PN = "118"  !CDS_PN = "118";
"DQ13_A":   PN = "27"  !CDS_PN = "27";
"DQ13_B":   PN = "120"  !CDS_PN = "120";
"DQ14_A":   PN = "170"  !CDS_PN = "170";
"DQ14_B":   PN = "263"  !CDS_PN = "263";
"DQ15_A":   PN = "172"  !CDS_PN = "172";
"DQ15_B":   PN = "265"  !CDS_PN = "265";
"DQ16_A":   PN = "29"  !CDS_PN = "29";
"DQ16_B":   PN = "122"  !CDS_PN = "122";
"DQ17_A":   PN = "31"  !CDS_PN = "31";
"DQ17_B":   PN = "124"  !CDS_PN = "124";
"DQ18_A":   PN = "174"  !CDS_PN = "174";
"DQ18_B":   PN = "267"  !CDS_PN = "267";
"DQ19_A":   PN = "176"  !CDS_PN = "176";
"DQ19_B":   PN = "269"  !CDS_PN = "269";
"DQ20_A":   PN = "36"  !CDS_PN = "36";
"DQ20_B":   PN = "129"  !CDS_PN = "129";
"DQ21_A":   PN = "38"  !CDS_PN = "38";
"DQ21_B":   PN = "131"  !CDS_PN = "131";
"DQ22_A":   PN = "181"  !CDS_PN = "181";
"DQ22_B":   PN = "274"  !CDS_PN = "274";
"DQ23_A":   PN = "183"  !CDS_PN = "183";
"DQ23_B":   PN = "276"  !CDS_PN = "276";
"DQ24_A":   PN = "40"  !CDS_PN = "40";
"DQ24_B":   PN = "133"  !CDS_PN = "133";
"DQ25_A":   PN = "42"  !CDS_PN = "42";
"DQ25_B":   PN = "135"  !CDS_PN = "135";
"DQ26_A":   PN = "185"  !CDS_PN = "185";
"DQ26_B":   PN = "278"  !CDS_PN = "278";
"DQ27_A":   PN = "187"  !CDS_PN = "187";
"DQ27_B":   PN = "280"  !CDS_PN = "280";
"DQ28_A":   PN = "47"  !CDS_PN = "47";
"DQ28_B":   PN = "140"  !CDS_PN = "140";
"DQ29_A":   PN = "49"  !CDS_PN = "49";
"DQ29_B":   PN = "142"  !CDS_PN = "142";
"DQ30_A":   PN = "192"  !CDS_PN = "192";
"DQ30_B":   PN = "285"  !CDS_PN = "285";
"DQ31_A":   PN = "194"  !CDS_PN = "194";
"DQ31_B":   PN = "287"  !CDS_PN = "287";
"HAS":   PN = "148"  !CDS_PN = "148";
"HSCL":   PN = "4"  !CDS_PN = "4";
"HSDA":   PN = "5"  !CDS_PN = "5";
"LBD||RSP_A_N":   PN = "86"  !CDS_PN = "86";
"LBS||RSP_B_N":   PN = "87"  !CDS_PN = "87";
"PAR_A":   PN = "74"  !CDS_PN = "74";
"PAR_B":   PN = "227"  !CDS_PN = "227";
"PWR_GOOD||FAIL_N":   PN = "147"  !CDS_PN = "147";
"RESET_N":   PN = "207"  !CDS_PN = "207";
"RFU0":   PN = "2"  !CDS_PN = "2";
"RFU1":   PN = "144"  !CDS_PN = "144";
"RFU2":   PN = "149"  !CDS_PN = "149";
"RFU3":   PN = "150"  !CDS_PN = "150";
"RFU4":   PN = "220"  !CDS_PN = "220";
"RFU5":   PN = "231"  !CDS_PN = "231";
"RFU6":   PN = "232"  !CDS_PN = "232";
"VIN_MGMT":   PN = "3"  !CDS_PN = "3";
BODY = "Q_RES","I129": #LOCATION = "R768" !CDS_LOCATION = "R768" &SEC = "1" #&CDS_SEC = "1";
"A":   PN = "1"  !CDS_PN = "1";
"B":   PN = "2"  !CDS_PN = "2";
BODY = "SCONN288_DDR506112002KQ","I177": #LOCATION = "J20" !CDS_LOCATION = "J20" &SEC = "3" #&CDS_SEC = "3";
"G1":   PN = "G1"  !CDS_PN = "G1";
"G2":   PN = "G2"  !CDS_PN = "G2";
"G3":   PN = "G3"  !CDS_PN = "G3";
"VIN_BULK0":   PN = "1"  !CDS_PN = "1";
"VIN_BULK1":   PN = "145"  !CDS_PN = "145";
"VIN_BULK2":   PN = "146"  !CDS_PN = "146";
"VSS0":   PN = "6"  !CDS_PN = "6";
"VSS1":   PN = "8"  !CDS_PN = "8";
"VSS2":   PN = "10"  !CDS_PN = "10";
"VSS3":   PN = "13"  !CDS_PN = "13";
"VSS4":   PN = "15"  !CDS_PN = "15";
"VSS5":   PN = "17"  !CDS_PN = "17";
"VSS6":   PN = "19"  !CDS_PN = "19";
"VSS7":   PN = "21"  !CDS_PN = "21";
"VSS8":   PN = "24"  !CDS_PN = "24";
"VSS9":   PN = "26"  !CDS_PN = "26";
"VSS10":   PN = "28"  !CDS_PN = "28";
"VSS11":   PN = "30"  !CDS_PN = "30";
"VSS12":   PN = "32"  !CDS_PN = "32";
"VSS13":   PN = "35"  !CDS_PN = "35";
"VSS14":   PN = "37"  !CDS_PN = "37";
"VSS15":   PN = "39"  !CDS_PN = "39";
"VSS16":   PN = "41"  !CDS_PN = "41";
"VSS17":   PN = "43"  !CDS_PN = "43";
"VSS18":   PN = "46"  !CDS_PN = "46";
"VSS19":   PN = "48"  !CDS_PN = "48";
"VSS20":   PN = "50"  !CDS_PN = "50";
"VSS21":   PN = "52"  !CDS_PN = "52";
"VSS22":   PN = "54"  !CDS_PN = "54";
"VSS23":   PN = "57"  !CDS_PN = "57";
"VSS24":   PN = "59"  !CDS_PN = "59";
"VSS25":   PN = "61"  !CDS_PN = "61";
"VSS26":   PN = "63"  !CDS_PN = "63";
"VSS27":   PN = "65"  !CDS_PN = "65";
"VSS28":   PN = "67"  !CDS_PN = "67";
"VSS29":   PN = "69"  !CDS_PN = "69";
"VSS30":   PN = "71"  !CDS_PN = "71";
"VSS31":   PN = "73"  !CDS_PN = "73";
"VSS32":   PN = "75"  !CDS_PN = "75";
"VSS33":   PN = "77"  !CDS_PN = "77";
"VSS34":   PN = "79"  !CDS_PN = "79";
"VSS35":   PN = "81"  !CDS_PN = "81";
"VSS36":   PN = "83"  !CDS_PN = "83";
"VSS37":   PN = "85"  !CDS_PN = "85";
"VSS38":   PN = "88"  !CDS_PN = "88";
"VSS39":   PN = "90"  !CDS_PN = "90";
"VSS40":   PN = "92"  !CDS_PN = "92";
"VSS41":   PN = "95"  !CDS_PN = "95";
"VSS42":   PN = "97"  !CDS_PN = "97";
"VSS43":   PN = "99"  !CDS_PN = "99";
"VSS44":   PN = "101"  !CDS_PN = "101";
"VSS45":   PN = "103"  !CDS_PN = "103";
"VSS46":   PN = "106"  !CDS_PN = "106";
"VSS47":   PN = "108"  !CDS_PN = "108";
"VSS48":   PN = "110"  !CDS_PN = "110";
"VSS49":   PN = "112"  !CDS_PN = "112";
"VSS50":   PN = "114"  !CDS_PN = "114";
"VSS51":   PN = "117"  !CDS_PN = "117";
"VSS52":   PN = "119"  !CDS_PN = "119";
"VSS53":   PN = "121"  !CDS_PN = "121";
"VSS54":   PN = "123"  !CDS_PN = "123";
"VSS55":   PN = "125"  !CDS_PN = "125";
"VSS56":   PN = "128"  !CDS_PN = "128";
"VSS57":   PN = "130"  !CDS_PN = "130";
"VSS58":   PN = "132"  !CDS_PN = "132";
"VSS59":   PN = "134"  !CDS_PN = "134";
"VSS60":   PN = "136"  !CDS_PN = "136";
"VSS61":   PN = "139"  !CDS_PN = "139";
"VSS62":   PN = "141"  !CDS_PN = "141";
"VSS63":   PN = "143"  !CDS_PN = "143";
"VSS64":   PN = "151"  !CDS_PN = "151";
"VSS65":   PN = "153"  !CDS_PN = "153";
"VSS66":   PN = "155"  !CDS_PN = "155";
"VSS67":   PN = "158"  !CDS_PN = "158";
"VSS68":   PN = "160"  !CDS_PN = "160";
"VSS69":   PN = "162"  !CDS_PN = "162";
"VSS70":   PN = "164"  !CDS_PN = "164";
"VSS71":   PN = "166"  !CDS_PN = "166";
"VSS72":   PN = "169"  !CDS_PN = "169";
"VSS73":   PN = "171"  !CDS_PN = "171";
"VSS74":   PN = "173"  !CDS_PN = "173";
"VSS75":   PN = "175"  !CDS_PN = "175";
"VSS76":   PN = "177"  !CDS_PN = "177";
"VSS77":   PN = "180"  !CDS_PN = "180";
"VSS78":   PN = "182"  !CDS_PN = "182";
"VSS79":   PN = "184"  !CDS_PN = "184";
"VSS80":   PN = "186"  !CDS_PN = "186";
"VSS81":   PN = "188"  !CDS_PN = "188";
"VSS82":   PN = "191"  !CDS_PN = "191";
"VSS83":   PN = "193"  !CDS_PN = "193";
"VSS84":   PN = "195"  !CDS_PN = "195";
"VSS85":   PN = "197"  !CDS_PN = "197";
"VSS86":   PN = "199"  !CDS_PN = "199";
"VSS87":   PN = "202"  !CDS_PN = "202";
"VSS88":   PN = "204"  !CDS_PN = "204";
"VSS89":   PN = "206"  !CDS_PN = "206";
"VSS90":   PN = "208"  !CDS_PN = "208";
"VSS91":   PN = "210"  !CDS_PN = "210";
"VSS92":   PN = "212"  !CDS_PN = "212";
"VSS93":   PN = "214"  !CDS_PN = "214";
"VSS94":   PN = "216"  !CDS_PN = "216";
"VSS95":   PN = "219"  !CDS_PN = "219";
"VSS96":   PN = "222"  !CDS_PN = "222";
"VSS97":   PN = "224"  !CDS_PN = "224";
"VSS98":   PN = "226"  !CDS_PN = "226";
"VSS99":   PN = "228"  !CDS_PN = "228";
"VSS100":   PN = "230"  !CDS_PN = "230";
"VSS101":   PN = "233"  !CDS_PN = "233";
"VSS102":   PN = "235"  !CDS_PN = "235";
"VSS103":   PN = "237"  !CDS_PN = "237";
"VSS104":   PN = "240"  !CDS_PN = "240";
"VSS105":   PN = "242"  !CDS_PN = "242";
"VSS106":   PN = "244"  !CDS_PN = "244";
"VSS107":   PN = "246"  !CDS_PN = "246";
"VSS108":   PN = "248"  !CDS_PN = "248";
"VSS109":   PN = "251"  !CDS_PN = "251";
"VSS110":   PN = "253"  !CDS_PN = "253";
"VSS111":   PN = "255"  !CDS_PN = "255";
"VSS112":   PN = "257"  !CDS_PN = "257";
"VSS113":   PN = "259"  !CDS_PN = "259";
"VSS114":   PN = "262"  !CDS_PN = "262";
"VSS115":   PN = "264"  !CDS_PN = "264";
"VSS116":   PN = "266"  !CDS_PN = "266";
"VSS117":   PN = "268"  !CDS_PN = "268";
"VSS118":   PN = "270"  !CDS_PN = "270";
"VSS119":   PN = "273"  !CDS_PN = "273";
"VSS120":   PN = "275"  !CDS_PN = "275";
"VSS121":   PN = "277"  !CDS_PN = "277";
"VSS122":   PN = "279"  !CDS_PN = "279";
"VSS123":   PN = "281"  !CDS_PN = "281";
"VSS124":   PN = "284"  !CDS_PN = "284";
"VSS125":   PN = "286"  !CDS_PN = "286";
"VSS126":   PN = "288"  !CDS_PN = "288";
BODY = "Q_CAP","I185": #LOCATION = "C128" !CDS_LOCATION = "C128" &SEC = "1" #&CDS_SEC = "1";
"A":   PN = "1"  !CDS_PN = "1";
"B":   PN = "2"  !CDS_PN = "2";
BODY = "Q_RES","I188": #LOCATION = "R301" !CDS_LOCATION = "R301" &SEC = "1" #&CDS_SEC = "1";
"A":   PN = "1"  !CDS_PN = "1";
"B":   PN = "2"  !CDS_PN = "2";
BODY = "Q_RES","I189": #LOCATION = "R100" !CDS_LOCATION = "R100" &SEC = "1" #&CDS_SEC = "1";
"A":   PN = "1"  !CDS_PN = "1";
"B":   PN = "2"  !CDS_PN = "2";
BODY = "SCONN288_DDR506112002KQ","I236": #LOCATION = "J20" !CDS_LOCATION = "J20" &SEC = "2" #&CDS_SEC = "2";
"DQS0_A_C":   PN = "12"  !CDS_PN = "12";
"DQS0_A_T":   PN = "11"  !CDS_PN = "11";
"DQS0_B_C":   PN = "105"  !CDS_PN = "105";
"DQS0_B_T":   PN = "104"  !CDS_PN = "104";
"DQS1_A_C":   PN = "23"  !CDS_PN = "23";
"DQS1_A_T":   PN = "22"  !CDS_PN = "22";
"DQS1_B_C":   PN = "116"  !CDS_PN = "116";
"DQS1_B_T":   PN = "115"  !CDS_PN = "115";
"DQS2_A_C":   PN = "34"  !CDS_PN = "34";
"DQS2_A_T":   PN = "33"  !CDS_PN = "33";
"DQS2_B_C":   PN = "127"  !CDS_PN = "127";
"DQS2_B_T":   PN = "126"  !CDS_PN = "126";
"DQS3_A_C":   PN = "45"  !CDS_PN = "45";
"DQS3_A_T":   PN = "44"  !CDS_PN = "44";
"DQS3_B_C":   PN = "138"  !CDS_PN = "138";
"DQS3_B_T":   PN = "137"  !CDS_PN = "137";
"DQS4_A_C":   PN = "56"  !CDS_PN = "56";
"DQS4_A_T":   PN = "55"  !CDS_PN = "55";
"DQS4_B_C":   PN = "238"  !CDS_PN = "238";
"DQS4_B_T":   PN = "239"  !CDS_PN = "239";
"DQS5_A_C||TDQS5_A_C||DQS5_A_T||TDQS5_A_T":   PN = "156"  !CDS_PN = "156";
"DQS5_A_T||TDQS5_A_T":   PN = "157"  !CDS_PN = "157";
"DQS5_B_C||TDQS5_B_C":   PN = "249"  !CDS_PN = "249";
"DQS5_B_T||TDQS5_B_T":   PN = "250"  !CDS_PN = "250";
"DQS6_A_C||TDQS6_A_C||DQS6_A_T||TDQS6_A_T":   PN = "167"  !CDS_PN = "167";
"DQS6_A_T||TDQS6_A_T":   PN = "168"  !CDS_PN = "168";
"DQS6_B_C||TDQS6_B_C":   PN = "260"  !CDS_PN = "260";
"DQS6_B_T||TDQS6_B_T":   PN = "261"  !CDS_PN = "261";
"DQS7_A_C||TDQS7_A_C":   PN = "178"  !CDS_PN = "178";
"DQS7_A_T||TDQS7_A_T":   PN = "179"  !CDS_PN = "179";
"DQS7_B_C||TDQS7_B_C":   PN = "271"  !CDS_PN = "271";
"DQS7_B_T||TDQS7_B_T":   PN = "272"  !CDS_PN = "272";
"DQS8_A_C||TDQS8_A_C":   PN = "189"  !CDS_PN = "189";
"DQS8_A_T||TDQS8_A_T":   PN = "190"  !CDS_PN = "190";
"DQS8_B_C||TDQS8_B_C":   PN = "282"  !CDS_PN = "282";
"DQS8_B_T||TDQS8_B_T":   PN = "283"  !CDS_PN = "283";
"DQS9_A_C||TDQS9_A_C":   PN = "200"  !CDS_PN = "200";
"DQS9_A_T||TDQS9_A_T":   PN = "201"  !CDS_PN = "201";
"DQS9_B_C||TDQS9_B_C":   PN = "94"  !CDS_PN = "94";
"DQS9_B_T||TDQS9_B_T||DBI4_B_N":   PN = "93"  !CDS_PN = "93";
BODY = "Q_CAP","I238": #LOCATION = "C167" !CDS_LOCATION = "C167" &SEC = "1" #&CDS_SEC = "1";
"A":   PN = "1"  !CDS_PN = "1";
"B":   PN = "2"  !CDS_PN = "2";
BODY = "Q_CAP","I239": #LOCATION = "C169" !CDS_LOCATION = "C169" &SEC = "1" #&CDS_SEC = "1";
"A":   PN = "1"  !CDS_PN = "1";
"B":   PN = "2"  !CDS_PN = "2";
BODY = "Q_RES","I242": #LOCATION = "R1578" !CDS_LOCATION = "R1578" &SEC = "1" #&CDS_SEC = "1";
"A":   PN = "1"  !CDS_PN = "1";
"B":   PN = "2"  !CDS_PN = "2";
BODY = "Q_RES","I243": #LOCATION = "R1685" !CDS_LOCATION = "R1685" &SEC = "1" #&CDS_SEC = "1";
"A":   PN = "1"  !CDS_PN = "1";
"B":   PN = "2"  !CDS_PN = "2";
DRAWING = "@t6g_mb_lib.t6g(sch_1):page96";
BODY = "SCONN288_DDR506112002KQ","I22": #LOCATION = "J67" !CDS_LOCATION = "J67" &SEC = "1" #&CDS_SEC = "1";
"ALERT_N":   PN = "62"  !CDS_PN = "62";
"CA0_A":   PN = "66"  !CDS_PN = "66";
"CA0_B":   PN = "76"  !CDS_PN = "76";
"CA1_A":   PN = "211"  !CDS_PN = "211";
"CA1_B":   PN = "221"  !CDS_PN = "221";
"CA2_A":   PN = "68"  !CDS_PN = "68";
"CA2_B":   PN = "78"  !CDS_PN = "78";
"CA3_A":   PN = "213"  !CDS_PN = "213";
"CA3_B":   PN = "223"  !CDS_PN = "223";
"CA4_A":   PN = "70"  !CDS_PN = "70";
"CA4_B":   PN = "80"  !CDS_PN = "80";
"CA5_A":   PN = "215"  !CDS_PN = "215";
"CA5_B":   PN = "225"  !CDS_PN = "225";
"CA6_A":   PN = "72"  !CDS_PN = "72";
"CA6_B":   PN = "82"  !CDS_PN = "82";
"CB0_A":   PN = "51"  !CDS_PN = "51";
"CB0_B":   PN = "96"  !CDS_PN = "96";
"CB1_A":   PN = "53"  !CDS_PN = "53";
"CB1_B":   PN = "98"  !CDS_PN = "98";
"CB2_A":   PN = "196"  !CDS_PN = "196";
"CB2_B":   PN = "241"  !CDS_PN = "241";
"CB3_A":   PN = "198"  !CDS_PN = "198";
"CB3_B":   PN = "243"  !CDS_PN = "243";
"CB4_A":   PN = "58"  !CDS_PN = "58";
"CB4_B":   PN = "89"  !CDS_PN = "89";
"CB5_A":   PN = "60"  !CDS_PN = "60";
"CB5_B":   PN = "91"  !CDS_PN = "91";
"CB6_A":   PN = "203"  !CDS_PN = "203";
"CB6_B":   PN = "234"  !CDS_PN = "234";
"CB7_A":   PN = "205"  !CDS_PN = "205";
"CB7_B":   PN = "236"  !CDS_PN = "236";
"CK_C":   PN = "218"  !CDS_PN = "218";
"CK_T":   PN = "217"  !CDS_PN = "217";
"CS0_A_N":   PN = "64"  !CDS_PN = "64";
"CS0_B_N":   PN = "84"  !CDS_PN = "84";
"CS1_A_N":   PN = "209"  !CDS_PN = "209";
"CS1_B_N":   PN = "229"  !CDS_PN = "229";
"DQ0_A":   PN = "7"  !CDS_PN = "7";
"DQ0_B":   PN = "100"  !CDS_PN = "100";
"DQ1_A":   PN = "9"  !CDS_PN = "9";
"DQ1_B":   PN = "102"  !CDS_PN = "102";
"DQ2_A":   PN = "152"  !CDS_PN = "152";
"DQ2_B":   PN = "245"  !CDS_PN = "245";
"DQ3_A":   PN = "154"  !CDS_PN = "154";
"DQ3_B":   PN = "247"  !CDS_PN = "247";
"DQ4_A":   PN = "14"  !CDS_PN = "14";
"DQ4_B":   PN = "107"  !CDS_PN = "107";
"DQ5_A":   PN = "16"  !CDS_PN = "16";
"DQ5_B":   PN = "109"  !CDS_PN = "109";
"DQ6_A":   PN = "159"  !CDS_PN = "159";
"DQ6_B":   PN = "252"  !CDS_PN = "252";
"DQ7_A":   PN = "161"  !CDS_PN = "161";
"DQ7_B":   PN = "254"  !CDS_PN = "254";
"DQ8_A":   PN = "18"  !CDS_PN = "18";
"DQ8_B":   PN = "111"  !CDS_PN = "111";
"DQ9_A":   PN = "20"  !CDS_PN = "20";
"DQ9_B":   PN = "113"  !CDS_PN = "113";
"DQ10_A":   PN = "163"  !CDS_PN = "163";
"DQ10_B":   PN = "256"  !CDS_PN = "256";
"DQ11_A":   PN = "165"  !CDS_PN = "165";
"DQ11_B":   PN = "258"  !CDS_PN = "258";
"DQ12_A":   PN = "25"  !CDS_PN = "25";
"DQ12_B":   PN = "118"  !CDS_PN = "118";
"DQ13_A":   PN = "27"  !CDS_PN = "27";
"DQ13_B":   PN = "120"  !CDS_PN = "120";
"DQ14_A":   PN = "170"  !CDS_PN = "170";
"DQ14_B":   PN = "263"  !CDS_PN = "263";
"DQ15_A":   PN = "172"  !CDS_PN = "172";
"DQ15_B":   PN = "265"  !CDS_PN = "265";
"DQ16_A":   PN = "29"  !CDS_PN = "29";
"DQ16_B":   PN = "122"  !CDS_PN = "122";
"DQ17_A":   PN = "31"  !CDS_PN = "31";
"DQ17_B":   PN = "124"  !CDS_PN = "124";
"DQ18_A":   PN = "174"  !CDS_PN = "174";
"DQ18_B":   PN = "267"  !CDS_PN = "267";
"DQ19_A":   PN = "176"  !CDS_PN = "176";
"DQ19_B":   PN = "269"  !CDS_PN = "269";
"DQ20_A":   PN = "36"  !CDS_PN = "36";
"DQ20_B":   PN = "129"  !CDS_PN = "129";
"DQ21_A":   PN = "38"  !CDS_PN = "38";
"DQ21_B":   PN = "131"  !CDS_PN = "131";
"DQ22_A":   PN = "181"  !CDS_PN = "181";
"DQ22_B":   PN = "274"  !CDS_PN = "274";
"DQ23_A":   PN = "183"  !CDS_PN = "183";
"DQ23_B":   PN = "276"  !CDS_PN = "276";
"DQ24_A":   PN = "40"  !CDS_PN = "40";
"DQ24_B":   PN = "133"  !CDS_PN = "133";
"DQ25_A":   PN = "42"  !CDS_PN = "42";
"DQ25_B":   PN = "135"  !CDS_PN = "135";
"DQ26_A":   PN = "185"  !CDS_PN = "185";
"DQ26_B":   PN = "278"  !CDS_PN = "278";
"DQ27_A":   PN = "187"  !CDS_PN = "187";
"DQ27_B":   PN = "280"  !CDS_PN = "280";
"DQ28_A":   PN = "47"  !CDS_PN = "47";
"DQ28_B":   PN = "140"  !CDS_PN = "140";
"DQ29_A":   PN = "49"  !CDS_PN = "49";
"DQ29_B":   PN = "142"  !CDS_PN = "142";
"DQ30_A":   PN = "192"  !CDS_PN = "192";
"DQ30_B":   PN = "285"  !CDS_PN = "285";
"DQ31_A":   PN = "194"  !CDS_PN = "194";
"DQ31_B":   PN = "287"  !CDS_PN = "287";
"HAS":   PN = "148"  !CDS_PN = "148";
"HSCL":   PN = "4"  !CDS_PN = "4";
"HSDA":   PN = "5"  !CDS_PN = "5";
"LBD||RSP_A_N":   PN = "86"  !CDS_PN = "86";
"LBS||RSP_B_N":   PN = "87"  !CDS_PN = "87";
"PAR_A":   PN = "74"  !CDS_PN = "74";
"PAR_B":   PN = "227"  !CDS_PN = "227";
"PWR_GOOD||FAIL_N":   PN = "147"  !CDS_PN = "147";
"RESET_N":   PN = "207"  !CDS_PN = "207";
"RFU0":   PN = "2"  !CDS_PN = "2";
"RFU1":   PN = "144"  !CDS_PN = "144";
"RFU2":   PN = "149"  !CDS_PN = "149";
"RFU3":   PN = "150"  !CDS_PN = "150";
"RFU4":   PN = "220"  !CDS_PN = "220";
"RFU5":   PN = "231"  !CDS_PN = "231";
"RFU6":   PN = "232"  !CDS_PN = "232";
"VIN_MGMT":   PN = "3"  !CDS_PN = "3";
BODY = "Q_RES","I127": #LOCATION = "R769" !CDS_LOCATION = "R769" &SEC = "1" #&CDS_SEC = "1";
"A":   PN = "1"  !CDS_PN = "1";
"B":   PN = "2"  !CDS_PN = "2";
BODY = "SCONN288_DDR506112002KQ","I140": #LOCATION = "J67" !CDS_LOCATION = "J67" &SEC = "3" #&CDS_SEC = "3";
"G1":   PN = "G1"  !CDS_PN = "G1";
"G2":   PN = "G2"  !CDS_PN = "G2";
"G3":   PN = "G3"  !CDS_PN = "G3";
"VIN_BULK0":   PN = "1"  !CDS_PN = "1";
"VIN_BULK1":   PN = "145"  !CDS_PN = "145";
"VIN_BULK2":   PN = "146"  !CDS_PN = "146";
"VSS0":   PN = "6"  !CDS_PN = "6";
"VSS1":   PN = "8"  !CDS_PN = "8";
"VSS2":   PN = "10"  !CDS_PN = "10";
"VSS3":   PN = "13"  !CDS_PN = "13";
"VSS4":   PN = "15"  !CDS_PN = "15";
"VSS5":   PN = "17"  !CDS_PN = "17";
"VSS6":   PN = "19"  !CDS_PN = "19";
"VSS7":   PN = "21"  !CDS_PN = "21";
"VSS8":   PN = "24"  !CDS_PN = "24";
"VSS9":   PN = "26"  !CDS_PN = "26";
"VSS10":   PN = "28"  !CDS_PN = "28";
"VSS11":   PN = "30"  !CDS_PN = "30";
"VSS12":   PN = "32"  !CDS_PN = "32";
"VSS13":   PN = "35"  !CDS_PN = "35";
"VSS14":   PN = "37"  !CDS_PN = "37";
"VSS15":   PN = "39"  !CDS_PN = "39";
"VSS16":   PN = "41"  !CDS_PN = "41";
"VSS17":   PN = "43"  !CDS_PN = "43";
"VSS18":   PN = "46"  !CDS_PN = "46";
"VSS19":   PN = "48"  !CDS_PN = "48";
"VSS20":   PN = "50"  !CDS_PN = "50";
"VSS21":   PN = "52"  !CDS_PN = "52";
"VSS22":   PN = "54"  !CDS_PN = "54";
"VSS23":   PN = "57"  !CDS_PN = "57";
"VSS24":   PN = "59"  !CDS_PN = "59";
"VSS25":   PN = "61"  !CDS_PN = "61";
"VSS26":   PN = "63"  !CDS_PN = "63";
"VSS27":   PN = "65"  !CDS_PN = "65";
"VSS28":   PN = "67"  !CDS_PN = "67";
"VSS29":   PN = "69"  !CDS_PN = "69";
"VSS30":   PN = "71"  !CDS_PN = "71";
"VSS31":   PN = "73"  !CDS_PN = "73";
"VSS32":   PN = "75"  !CDS_PN = "75";
"VSS33":   PN = "77"  !CDS_PN = "77";
"VSS34":   PN = "79"  !CDS_PN = "79";
"VSS35":   PN = "81"  !CDS_PN = "81";
"VSS36":   PN = "83"  !CDS_PN = "83";
"VSS37":   PN = "85"  !CDS_PN = "85";
"VSS38":   PN = "88"  !CDS_PN = "88";
"VSS39":   PN = "90"  !CDS_PN = "90";
"VSS40":   PN = "92"  !CDS_PN = "92";
"VSS41":   PN = "95"  !CDS_PN = "95";
"VSS42":   PN = "97"  !CDS_PN = "97";
"VSS43":   PN = "99"  !CDS_PN = "99";
"VSS44":   PN = "101"  !CDS_PN = "101";
"VSS45":   PN = "103"  !CDS_PN = "103";
"VSS46":   PN = "106"  !CDS_PN = "106";
"VSS47":   PN = "108"  !CDS_PN = "108";
"VSS48":   PN = "110"  !CDS_PN = "110";
"VSS49":   PN = "112"  !CDS_PN = "112";
"VSS50":   PN = "114"  !CDS_PN = "114";
"VSS51":   PN = "117"  !CDS_PN = "117";
"VSS52":   PN = "119"  !CDS_PN = "119";
"VSS53":   PN = "121"  !CDS_PN = "121";
"VSS54":   PN = "123"  !CDS_PN = "123";
"VSS55":   PN = "125"  !CDS_PN = "125";
"VSS56":   PN = "128"  !CDS_PN = "128";
"VSS57":   PN = "130"  !CDS_PN = "130";
"VSS58":   PN = "132"  !CDS_PN = "132";
"VSS59":   PN = "134"  !CDS_PN = "134";
"VSS60":   PN = "136"  !CDS_PN = "136";
"VSS61":   PN = "139"  !CDS_PN = "139";
"VSS62":   PN = "141"  !CDS_PN = "141";
"VSS63":   PN = "143"  !CDS_PN = "143";
"VSS64":   PN = "151"  !CDS_PN = "151";
"VSS65":   PN = "153"  !CDS_PN = "153";
"VSS66":   PN = "155"  !CDS_PN = "155";
"VSS67":   PN = "158"  !CDS_PN = "158";
"VSS68":   PN = "160"  !CDS_PN = "160";
"VSS69":   PN = "162"  !CDS_PN = "162";
"VSS70":   PN = "164"  !CDS_PN = "164";
"VSS71":   PN = "166"  !CDS_PN = "166";
"VSS72":   PN = "169"  !CDS_PN = "169";
"VSS73":   PN = "171"  !CDS_PN = "171";
"VSS74":   PN = "173"  !CDS_PN = "173";
"VSS75":   PN = "175"  !CDS_PN = "175";
"VSS76":   PN = "177"  !CDS_PN = "177";
"VSS77":   PN = "180"  !CDS_PN = "180";
"VSS78":   PN = "182"  !CDS_PN = "182";
"VSS79":   PN = "184"  !CDS_PN = "184";
"VSS80":   PN = "186"  !CDS_PN = "186";
"VSS81":   PN = "188"  !CDS_PN = "188";
"VSS82":   PN = "191"  !CDS_PN = "191";
"VSS83":   PN = "193"  !CDS_PN = "193";
"VSS84":   PN = "195"  !CDS_PN = "195";
"VSS85":   PN = "197"  !CDS_PN = "197";
"VSS86":   PN = "199"  !CDS_PN = "199";
"VSS87":   PN = "202"  !CDS_PN = "202";
"VSS88":   PN = "204"  !CDS_PN = "204";
"VSS89":   PN = "206"  !CDS_PN = "206";
"VSS90":   PN = "208"  !CDS_PN = "208";
"VSS91":   PN = "210"  !CDS_PN = "210";
"VSS92":   PN = "212"  !CDS_PN = "212";
"VSS93":   PN = "214"  !CDS_PN = "214";
"VSS94":   PN = "216"  !CDS_PN = "216";
"VSS95":   PN = "219"  !CDS_PN = "219";
"VSS96":   PN = "222"  !CDS_PN = "222";
"VSS97":   PN = "224"  !CDS_PN = "224";
"VSS98":   PN = "226"  !CDS_PN = "226";
"VSS99":   PN = "228"  !CDS_PN = "228";
"VSS100":   PN = "230"  !CDS_PN = "230";
"VSS101":   PN = "233"  !CDS_PN = "233";
"VSS102":   PN = "235"  !CDS_PN = "235";
"VSS103":   PN = "237"  !CDS_PN = "237";
"VSS104":   PN = "240"  !CDS_PN = "240";
"VSS105":   PN = "242"  !CDS_PN = "242";
"VSS106":   PN = "244"  !CDS_PN = "244";
"VSS107":   PN = "246"  !CDS_PN = "246";
"VSS108":   PN = "248"  !CDS_PN = "248";
"VSS109":   PN = "251"  !CDS_PN = "251";
"VSS110":   PN = "253"  !CDS_PN = "253";
"VSS111":   PN = "255"  !CDS_PN = "255";
"VSS112":   PN = "257"  !CDS_PN = "257";
"VSS113":   PN = "259"  !CDS_PN = "259";
"VSS114":   PN = "262"  !CDS_PN = "262";
"VSS115":   PN = "264"  !CDS_PN = "264";
"VSS116":   PN = "266"  !CDS_PN = "266";
"VSS117":   PN = "268"  !CDS_PN = "268";
"VSS118":   PN = "270"  !CDS_PN = "270";
"VSS119":   PN = "273"  !CDS_PN = "273";
"VSS120":   PN = "275"  !CDS_PN = "275";
"VSS121":   PN = "277"  !CDS_PN = "277";
"VSS122":   PN = "279"  !CDS_PN = "279";
"VSS123":   PN = "281"  !CDS_PN = "281";
"VSS124":   PN = "284"  !CDS_PN = "284";
"VSS125":   PN = "286"  !CDS_PN = "286";
"VSS126":   PN = "288"  !CDS_PN = "288";
BODY = "Q_CAP","I185": #LOCATION = "C132" !CDS_LOCATION = "C132" &SEC = "1" #&CDS_SEC = "1";
"A":   PN = "1"  !CDS_PN = "1";
"B":   PN = "2"  !CDS_PN = "2";
BODY = "Q_RES","I188": #LOCATION = "R302" !CDS_LOCATION = "R302" &SEC = "1" #&CDS_SEC = "1";
"A":   PN = "1"  !CDS_PN = "1";
"B":   PN = "2"  !CDS_PN = "2";
BODY = "Q_RES","I189": #LOCATION = "R101" !CDS_LOCATION = "R101" &SEC = "1" #&CDS_SEC = "1";
"A":   PN = "1"  !CDS_PN = "1";
"B":   PN = "2"  !CDS_PN = "2";
BODY = "SCONN288_DDR506112002KQ","I236": #LOCATION = "J67" !CDS_LOCATION = "J67" &SEC = "2" #&CDS_SEC = "2";
"DQS0_A_C":   PN = "12"  !CDS_PN = "12";
"DQS0_A_T":   PN = "11"  !CDS_PN = "11";
"DQS0_B_C":   PN = "105"  !CDS_PN = "105";
"DQS0_B_T":   PN = "104"  !CDS_PN = "104";
"DQS1_A_C":   PN = "23"  !CDS_PN = "23";
"DQS1_A_T":   PN = "22"  !CDS_PN = "22";
"DQS1_B_C":   PN = "116"  !CDS_PN = "116";
"DQS1_B_T":   PN = "115"  !CDS_PN = "115";
"DQS2_A_C":   PN = "34"  !CDS_PN = "34";
"DQS2_A_T":   PN = "33"  !CDS_PN = "33";
"DQS2_B_C":   PN = "127"  !CDS_PN = "127";
"DQS2_B_T":   PN = "126"  !CDS_PN = "126";
"DQS3_A_C":   PN = "45"  !CDS_PN = "45";
"DQS3_A_T":   PN = "44"  !CDS_PN = "44";
"DQS3_B_C":   PN = "138"  !CDS_PN = "138";
"DQS3_B_T":   PN = "137"  !CDS_PN = "137";
"DQS4_A_C":   PN = "56"  !CDS_PN = "56";
"DQS4_A_T":   PN = "55"  !CDS_PN = "55";
"DQS4_B_C":   PN = "238"  !CDS_PN = "238";
"DQS4_B_T":   PN = "239"  !CDS_PN = "239";
"DQS5_A_C||TDQS5_A_C||DQS5_A_T||TDQS5_A_T":   PN = "156"  !CDS_PN = "156";
"DQS5_A_T||TDQS5_A_T":   PN = "157"  !CDS_PN = "157";
"DQS5_B_C||TDQS5_B_C":   PN = "249"  !CDS_PN = "249";
"DQS5_B_T||TDQS5_B_T":   PN = "250"  !CDS_PN = "250";
"DQS6_A_C||TDQS6_A_C||DQS6_A_T||TDQS6_A_T":   PN = "167"  !CDS_PN = "167";
"DQS6_A_T||TDQS6_A_T":   PN = "168"  !CDS_PN = "168";
"DQS6_B_C||TDQS6_B_C":   PN = "260"  !CDS_PN = "260";
"DQS6_B_T||TDQS6_B_T":   PN = "261"  !CDS_PN = "261";
"DQS7_A_C||TDQS7_A_C":   PN = "178"  !CDS_PN = "178";
"DQS7_A_T||TDQS7_A_T":   PN = "179"  !CDS_PN = "179";
"DQS7_B_C||TDQS7_B_C":   PN = "271"  !CDS_PN = "271";
"DQS7_B_T||TDQS7_B_T":   PN = "272"  !CDS_PN = "272";
"DQS8_A_C||TDQS8_A_C":   PN = "189"  !CDS_PN = "189";
"DQS8_A_T||TDQS8_A_T":   PN = "190"  !CDS_PN = "190";
"DQS8_B_C||TDQS8_B_C":   PN = "282"  !CDS_PN = "282";
"DQS8_B_T||TDQS8_B_T":   PN = "283"  !CDS_PN = "283";
"DQS9_A_C||TDQS9_A_C":   PN = "200"  !CDS_PN = "200";
"DQS9_A_T||TDQS9_A_T":   PN = "201"  !CDS_PN = "201";
"DQS9_B_C||TDQS9_B_C":   PN = "94"  !CDS_PN = "94";
"DQS9_B_T||TDQS9_B_T||DBI4_B_N":   PN = "93"  !CDS_PN = "93";
BODY = "Q_CAP","I238": #LOCATION = "C170" !CDS_LOCATION = "C170" &SEC = "1" #&CDS_SEC = "1";
"A":   PN = "1"  !CDS_PN = "1";
"B":   PN = "2"  !CDS_PN = "2";
BODY = "Q_CAP","I239": #LOCATION = "C171" !CDS_LOCATION = "C171" &SEC = "1" #&CDS_SEC = "1";
"A":   PN = "1"  !CDS_PN = "1";
"B":   PN = "2"  !CDS_PN = "2";
BODY = "Q_RES","I242": #LOCATION = "R1579" !CDS_LOCATION = "R1579" &SEC = "1" #&CDS_SEC = "1";
"A":   PN = "1"  !CDS_PN = "1";
"B":   PN = "2"  !CDS_PN = "2";
BODY = "Q_RES","I243": #LOCATION = "R1686" !CDS_LOCATION = "R1686" &SEC = "1" #&CDS_SEC = "1";
"A":   PN = "1"  !CDS_PN = "1";
"B":   PN = "2"  !CDS_PN = "2";
DRAWING = "@t6g_mb_lib.t6g(sch_1):page97";
BODY = "SCONN288_DDR506112002KQ","I22": #LOCATION = "J24" !CDS_LOCATION = "J24" &SEC = "1" #&CDS_SEC = "1";
"ALERT_N":   PN = "62"  !CDS_PN = "62";
"CA0_A":   PN = "66"  !CDS_PN = "66";
"CA0_B":   PN = "76"  !CDS_PN = "76";
"CA1_A":   PN = "211"  !CDS_PN = "211";
"CA1_B":   PN = "221"  !CDS_PN = "221";
"CA2_A":   PN = "68"  !CDS_PN = "68";
"CA2_B":   PN = "78"  !CDS_PN = "78";
"CA3_A":   PN = "213"  !CDS_PN = "213";
"CA3_B":   PN = "223"  !CDS_PN = "223";
"CA4_A":   PN = "70"  !CDS_PN = "70";
"CA4_B":   PN = "80"  !CDS_PN = "80";
"CA5_A":   PN = "215"  !CDS_PN = "215";
"CA5_B":   PN = "225"  !CDS_PN = "225";
"CA6_A":   PN = "72"  !CDS_PN = "72";
"CA6_B":   PN = "82"  !CDS_PN = "82";
"CB0_A":   PN = "51"  !CDS_PN = "51";
"CB0_B":   PN = "96"  !CDS_PN = "96";
"CB1_A":   PN = "53"  !CDS_PN = "53";
"CB1_B":   PN = "98"  !CDS_PN = "98";
"CB2_A":   PN = "196"  !CDS_PN = "196";
"CB2_B":   PN = "241"  !CDS_PN = "241";
"CB3_A":   PN = "198"  !CDS_PN = "198";
"CB3_B":   PN = "243"  !CDS_PN = "243";
"CB4_A":   PN = "58"  !CDS_PN = "58";
"CB4_B":   PN = "89"  !CDS_PN = "89";
"CB5_A":   PN = "60"  !CDS_PN = "60";
"CB5_B":   PN = "91"  !CDS_PN = "91";
"CB6_A":   PN = "203"  !CDS_PN = "203";
"CB6_B":   PN = "234"  !CDS_PN = "234";
"CB7_A":   PN = "205"  !CDS_PN = "205";
"CB7_B":   PN = "236"  !CDS_PN = "236";
"CK_C":   PN = "218"  !CDS_PN = "218";
"CK_T":   PN = "217"  !CDS_PN = "217";
"CS0_A_N":   PN = "64"  !CDS_PN = "64";
"CS0_B_N":   PN = "84"  !CDS_PN = "84";
"CS1_A_N":   PN = "209"  !CDS_PN = "209";
"CS1_B_N":   PN = "229"  !CDS_PN = "229";
"DQ0_A":   PN = "7"  !CDS_PN = "7";
"DQ0_B":   PN = "100"  !CDS_PN = "100";
"DQ1_A":   PN = "9"  !CDS_PN = "9";
"DQ1_B":   PN = "102"  !CDS_PN = "102";
"DQ2_A":   PN = "152"  !CDS_PN = "152";
"DQ2_B":   PN = "245"  !CDS_PN = "245";
"DQ3_A":   PN = "154"  !CDS_PN = "154";
"DQ3_B":   PN = "247"  !CDS_PN = "247";
"DQ4_A":   PN = "14"  !CDS_PN = "14";
"DQ4_B":   PN = "107"  !CDS_PN = "107";
"DQ5_A":   PN = "16"  !CDS_PN = "16";
"DQ5_B":   PN = "109"  !CDS_PN = "109";
"DQ6_A":   PN = "159"  !CDS_PN = "159";
"DQ6_B":   PN = "252"  !CDS_PN = "252";
"DQ7_A":   PN = "161"  !CDS_PN = "161";
"DQ7_B":   PN = "254"  !CDS_PN = "254";
"DQ8_A":   PN = "18"  !CDS_PN = "18";
"DQ8_B":   PN = "111"  !CDS_PN = "111";
"DQ9_A":   PN = "20"  !CDS_PN = "20";
"DQ9_B":   PN = "113"  !CDS_PN = "113";
"DQ10_A":   PN = "163"  !CDS_PN = "163";
"DQ10_B":   PN = "256"  !CDS_PN = "256";
"DQ11_A":   PN = "165"  !CDS_PN = "165";
"DQ11_B":   PN = "258"  !CDS_PN = "258";
"DQ12_A":   PN = "25"  !CDS_PN = "25";
"DQ12_B":   PN = "118"  !CDS_PN = "118";
"DQ13_A":   PN = "27"  !CDS_PN = "27";
"DQ13_B":   PN = "120"  !CDS_PN = "120";
"DQ14_A":   PN = "170"  !CDS_PN = "170";
"DQ14_B":   PN = "263"  !CDS_PN = "263";
"DQ15_A":   PN = "172"  !CDS_PN = "172";
"DQ15_B":   PN = "265"  !CDS_PN = "265";
"DQ16_A":   PN = "29"  !CDS_PN = "29";
"DQ16_B":   PN = "122"  !CDS_PN = "122";
"DQ17_A":   PN = "31"  !CDS_PN = "31";
"DQ17_B":   PN = "124"  !CDS_PN = "124";
"DQ18_A":   PN = "174"  !CDS_PN = "174";
"DQ18_B":   PN = "267"  !CDS_PN = "267";
"DQ19_A":   PN = "176"  !CDS_PN = "176";
"DQ19_B":   PN = "269"  !CDS_PN = "269";
"DQ20_A":   PN = "36"  !CDS_PN = "36";
"DQ20_B":   PN = "129"  !CDS_PN = "129";
"DQ21_A":   PN = "38"  !CDS_PN = "38";
"DQ21_B":   PN = "131"  !CDS_PN = "131";
"DQ22_A":   PN = "181"  !CDS_PN = "181";
"DQ22_B":   PN = "274"  !CDS_PN = "274";
"DQ23_A":   PN = "183"  !CDS_PN = "183";
"DQ23_B":   PN = "276"  !CDS_PN = "276";
"DQ24_A":   PN = "40"  !CDS_PN = "40";
"DQ24_B":   PN = "133"  !CDS_PN = "133";
"DQ25_A":   PN = "42"  !CDS_PN = "42";
"DQ25_B":   PN = "135"  !CDS_PN = "135";
"DQ26_A":   PN = "185"  !CDS_PN = "185";
"DQ26_B":   PN = "278"  !CDS_PN = "278";
"DQ27_A":   PN = "187"  !CDS_PN = "187";
"DQ27_B":   PN = "280"  !CDS_PN = "280";
"DQ28_A":   PN = "47"  !CDS_PN = "47";
"DQ28_B":   PN = "140"  !CDS_PN = "140";
"DQ29_A":   PN = "49"  !CDS_PN = "49";
"DQ29_B":   PN = "142"  !CDS_PN = "142";
"DQ30_A":   PN = "192"  !CDS_PN = "192";
"DQ30_B":   PN = "285"  !CDS_PN = "285";
"DQ31_A":   PN = "194"  !CDS_PN = "194";
"DQ31_B":   PN = "287"  !CDS_PN = "287";
"HAS":   PN = "148"  !CDS_PN = "148";
"HSCL":   PN = "4"  !CDS_PN = "4";
"HSDA":   PN = "5"  !CDS_PN = "5";
"LBD||RSP_A_N":   PN = "86"  !CDS_PN = "86";
"LBS||RSP_B_N":   PN = "87"  !CDS_PN = "87";
"PAR_A":   PN = "74"  !CDS_PN = "74";
"PAR_B":   PN = "227"  !CDS_PN = "227";
"PWR_GOOD||FAIL_N":   PN = "147"  !CDS_PN = "147";
"RESET_N":   PN = "207"  !CDS_PN = "207";
"RFU0":   PN = "2"  !CDS_PN = "2";
"RFU1":   PN = "144"  !CDS_PN = "144";
"RFU2":   PN = "149"  !CDS_PN = "149";
"RFU3":   PN = "150"  !CDS_PN = "150";
"RFU4":   PN = "220"  !CDS_PN = "220";
"RFU5":   PN = "231"  !CDS_PN = "231";
"RFU6":   PN = "232"  !CDS_PN = "232";
"VIN_MGMT":   PN = "3"  !CDS_PN = "3";
BODY = "Q_RES","I129": #LOCATION = "R36" !CDS_LOCATION = "R36" #SEC = "1" !CDS_SEC = "1";
"A":   PN = "1"  !CDS_PN = "1";
"B":   PN = "2"  !CDS_PN = "2";
BODY = "SCONN288_DDR506112002KQ","I177": #LOCATION = "J24" !CDS_LOCATION = "J24" &SEC = "3" #&CDS_SEC = "3";
"G1":   PN = "G1"  !CDS_PN = "G1";
"G2":   PN = "G2"  !CDS_PN = "G2";
"G3":   PN = "G3"  !CDS_PN = "G3";
"VIN_BULK0":   PN = "1"  !CDS_PN = "1";
"VIN_BULK1":   PN = "145"  !CDS_PN = "145";
"VIN_BULK2":   PN = "146"  !CDS_PN = "146";
"VSS0":   PN = "6"  !CDS_PN = "6";
"VSS1":   PN = "8"  !CDS_PN = "8";
"VSS2":   PN = "10"  !CDS_PN = "10";
"VSS3":   PN = "13"  !CDS_PN = "13";
"VSS4":   PN = "15"  !CDS_PN = "15";
"VSS5":   PN = "17"  !CDS_PN = "17";
"VSS6":   PN = "19"  !CDS_PN = "19";
"VSS7":   PN = "21"  !CDS_PN = "21";
"VSS8":   PN = "24"  !CDS_PN = "24";
"VSS9":   PN = "26"  !CDS_PN = "26";
"VSS10":   PN = "28"  !CDS_PN = "28";
"VSS11":   PN = "30"  !CDS_PN = "30";
"VSS12":   PN = "32"  !CDS_PN = "32";
"VSS13":   PN = "35"  !CDS_PN = "35";
"VSS14":   PN = "37"  !CDS_PN = "37";
"VSS15":   PN = "39"  !CDS_PN = "39";
"VSS16":   PN = "41"  !CDS_PN = "41";
"VSS17":   PN = "43"  !CDS_PN = "43";
"VSS18":   PN = "46"  !CDS_PN = "46";
"VSS19":   PN = "48"  !CDS_PN = "48";
"VSS20":   PN = "50"  !CDS_PN = "50";
"VSS21":   PN = "52"  !CDS_PN = "52";
"VSS22":   PN = "54"  !CDS_PN = "54";
"VSS23":   PN = "57"  !CDS_PN = "57";
"VSS24":   PN = "59"  !CDS_PN = "59";
"VSS25":   PN = "61"  !CDS_PN = "61";
"VSS26":   PN = "63"  !CDS_PN = "63";
"VSS27":   PN = "65"  !CDS_PN = "65";
"VSS28":   PN = "67"  !CDS_PN = "67";
"VSS29":   PN = "69"  !CDS_PN = "69";
"VSS30":   PN = "71"  !CDS_PN = "71";
"VSS31":   PN = "73"  !CDS_PN = "73";
"VSS32":   PN = "75"  !CDS_PN = "75";
"VSS33":   PN = "77"  !CDS_PN = "77";
"VSS34":   PN = "79"  !CDS_PN = "79";
"VSS35":   PN = "81"  !CDS_PN = "81";
"VSS36":   PN = "83"  !CDS_PN = "83";
"VSS37":   PN = "85"  !CDS_PN = "85";
"VSS38":   PN = "88"  !CDS_PN = "88";
"VSS39":   PN = "90"  !CDS_PN = "90";
"VSS40":   PN = "92"  !CDS_PN = "92";
"VSS41":   PN = "95"  !CDS_PN = "95";
"VSS42":   PN = "97"  !CDS_PN = "97";
"VSS43":   PN = "99"  !CDS_PN = "99";
"VSS44":   PN = "101"  !CDS_PN = "101";
"VSS45":   PN = "103"  !CDS_PN = "103";
"VSS46":   PN = "106"  !CDS_PN = "106";
"VSS47":   PN = "108"  !CDS_PN = "108";
"VSS48":   PN = "110"  !CDS_PN = "110";
"VSS49":   PN = "112"  !CDS_PN = "112";
"VSS50":   PN = "114"  !CDS_PN = "114";
"VSS51":   PN = "117"  !CDS_PN = "117";
"VSS52":   PN = "119"  !CDS_PN = "119";
"VSS53":   PN = "121"  !CDS_PN = "121";
"VSS54":   PN = "123"  !CDS_PN = "123";
"VSS55":   PN = "125"  !CDS_PN = "125";
"VSS56":   PN = "128"  !CDS_PN = "128";
"VSS57":   PN = "130"  !CDS_PN = "130";
"VSS58":   PN = "132"  !CDS_PN = "132";
"VSS59":   PN = "134"  !CDS_PN = "134";
"VSS60":   PN = "136"  !CDS_PN = "136";
"VSS61":   PN = "139"  !CDS_PN = "139";
"VSS62":   PN = "141"  !CDS_PN = "141";
"VSS63":   PN = "143"  !CDS_PN = "143";
"VSS64":   PN = "151"  !CDS_PN = "151";
"VSS65":   PN = "153"  !CDS_PN = "153";
"VSS66":   PN = "155"  !CDS_PN = "155";
"VSS67":   PN = "158"  !CDS_PN = "158";
"VSS68":   PN = "160"  !CDS_PN = "160";
"VSS69":   PN = "162"  !CDS_PN = "162";
"VSS70":   PN = "164"  !CDS_PN = "164";
"VSS71":   PN = "166"  !CDS_PN = "166";
"VSS72":   PN = "169"  !CDS_PN = "169";
"VSS73":   PN = "171"  !CDS_PN = "171";
"VSS74":   PN = "173"  !CDS_PN = "173";
"VSS75":   PN = "175"  !CDS_PN = "175";
"VSS76":   PN = "177"  !CDS_PN = "177";
"VSS77":   PN = "180"  !CDS_PN = "180";
"VSS78":   PN = "182"  !CDS_PN = "182";
"VSS79":   PN = "184"  !CDS_PN = "184";
"VSS80":   PN = "186"  !CDS_PN = "186";
"VSS81":   PN = "188"  !CDS_PN = "188";
"VSS82":   PN = "191"  !CDS_PN = "191";
"VSS83":   PN = "193"  !CDS_PN = "193";
"VSS84":   PN = "195"  !CDS_PN = "195";
"VSS85":   PN = "197"  !CDS_PN = "197";
"VSS86":   PN = "199"  !CDS_PN = "199";
"VSS87":   PN = "202"  !CDS_PN = "202";
"VSS88":   PN = "204"  !CDS_PN = "204";
"VSS89":   PN = "206"  !CDS_PN = "206";
"VSS90":   PN = "208"  !CDS_PN = "208";
"VSS91":   PN = "210"  !CDS_PN = "210";
"VSS92":   PN = "212"  !CDS_PN = "212";
"VSS93":   PN = "214"  !CDS_PN = "214";
"VSS94":   PN = "216"  !CDS_PN = "216";
"VSS95":   PN = "219"  !CDS_PN = "219";
"VSS96":   PN = "222"  !CDS_PN = "222";
"VSS97":   PN = "224"  !CDS_PN = "224";
"VSS98":   PN = "226"  !CDS_PN = "226";
"VSS99":   PN = "228"  !CDS_PN = "228";
"VSS100":   PN = "230"  !CDS_PN = "230";
"VSS101":   PN = "233"  !CDS_PN = "233";
"VSS102":   PN = "235"  !CDS_PN = "235";
"VSS103":   PN = "237"  !CDS_PN = "237";
"VSS104":   PN = "240"  !CDS_PN = "240";
"VSS105":   PN = "242"  !CDS_PN = "242";
"VSS106":   PN = "244"  !CDS_PN = "244";
"VSS107":   PN = "246"  !CDS_PN = "246";
"VSS108":   PN = "248"  !CDS_PN = "248";
"VSS109":   PN = "251"  !CDS_PN = "251";
"VSS110":   PN = "253"  !CDS_PN = "253";
"VSS111":   PN = "255"  !CDS_PN = "255";
"VSS112":   PN = "257"  !CDS_PN = "257";
"VSS113":   PN = "259"  !CDS_PN = "259";
"VSS114":   PN = "262"  !CDS_PN = "262";
"VSS115":   PN = "264"  !CDS_PN = "264";
"VSS116":   PN = "266"  !CDS_PN = "266";
"VSS117":   PN = "268"  !CDS_PN = "268";
"VSS118":   PN = "270"  !CDS_PN = "270";
"VSS119":   PN = "273"  !CDS_PN = "273";
"VSS120":   PN = "275"  !CDS_PN = "275";
"VSS121":   PN = "277"  !CDS_PN = "277";
"VSS122":   PN = "279"  !CDS_PN = "279";
"VSS123":   PN = "281"  !CDS_PN = "281";
"VSS124":   PN = "284"  !CDS_PN = "284";
"VSS125":   PN = "286"  !CDS_PN = "286";
"VSS126":   PN = "288"  !CDS_PN = "288";
BODY = "Q_CAP","I185": #LOCATION = "C136" !CDS_LOCATION = "C136" &SEC = "1" #&CDS_SEC = "1";
"A":   PN = "1"  !CDS_PN = "1";
"B":   PN = "2"  !CDS_PN = "2";
BODY = "Q_RES","I189": #LOCATION = "R102" !CDS_LOCATION = "R102" &SEC = "1" #&CDS_SEC = "1";
"A":   PN = "1"  !CDS_PN = "1";
"B":   PN = "2"  !CDS_PN = "2";
BODY = "Q_RES","I190": #LOCATION = "R303" !CDS_LOCATION = "R303" &SEC = "1" #&CDS_SEC = "1";
"A":   PN = "1"  !CDS_PN = "1";
"B":   PN = "2"  !CDS_PN = "2";
BODY = "Q_RES","I191": #LOCATION = "R103" !CDS_LOCATION = "R103" &SEC = "1" #&CDS_SEC = "1";
"A":   PN = "1"  !CDS_PN = "1";
"B":   PN = "2"  !CDS_PN = "2";
BODY = "SCONN288_DDR506112002KQ","I238": #LOCATION = "J24" !CDS_LOCATION = "J24" &SEC = "2" #&CDS_SEC = "2";
"DQS0_A_C":   PN = "12"  !CDS_PN = "12";
"DQS0_A_T":   PN = "11"  !CDS_PN = "11";
"DQS0_B_C":   PN = "105"  !CDS_PN = "105";
"DQS0_B_T":   PN = "104"  !CDS_PN = "104";
"DQS1_A_C":   PN = "23"  !CDS_PN = "23";
"DQS1_A_T":   PN = "22"  !CDS_PN = "22";
"DQS1_B_C":   PN = "116"  !CDS_PN = "116";
"DQS1_B_T":   PN = "115"  !CDS_PN = "115";
"DQS2_A_C":   PN = "34"  !CDS_PN = "34";
"DQS2_A_T":   PN = "33"  !CDS_PN = "33";
"DQS2_B_C":   PN = "127"  !CDS_PN = "127";
"DQS2_B_T":   PN = "126"  !CDS_PN = "126";
"DQS3_A_C":   PN = "45"  !CDS_PN = "45";
"DQS3_A_T":   PN = "44"  !CDS_PN = "44";
"DQS3_B_C":   PN = "138"  !CDS_PN = "138";
"DQS3_B_T":   PN = "137"  !CDS_PN = "137";
"DQS4_A_C":   PN = "56"  !CDS_PN = "56";
"DQS4_A_T":   PN = "55"  !CDS_PN = "55";
"DQS4_B_C":   PN = "238"  !CDS_PN = "238";
"DQS4_B_T":   PN = "239"  !CDS_PN = "239";
"DQS5_A_C||TDQS5_A_C||DQS5_A_T||TDQS5_A_T":   PN = "156"  !CDS_PN = "156";
"DQS5_A_T||TDQS5_A_T":   PN = "157"  !CDS_PN = "157";
"DQS5_B_C||TDQS5_B_C":   PN = "249"  !CDS_PN = "249";
"DQS5_B_T||TDQS5_B_T":   PN = "250"  !CDS_PN = "250";
"DQS6_A_C||TDQS6_A_C||DQS6_A_T||TDQS6_A_T":   PN = "167"  !CDS_PN = "167";
"DQS6_A_T||TDQS6_A_T":   PN = "168"  !CDS_PN = "168";
"DQS6_B_C||TDQS6_B_C":   PN = "260"  !CDS_PN = "260";
"DQS6_B_T||TDQS6_B_T":   PN = "261"  !CDS_PN = "261";
"DQS7_A_C||TDQS7_A_C":   PN = "178"  !CDS_PN = "178";
"DQS7_A_T||TDQS7_A_T":   PN = "179"  !CDS_PN = "179";
"DQS7_B_C||TDQS7_B_C":   PN = "271"  !CDS_PN = "271";
"DQS7_B_T||TDQS7_B_T":   PN = "272"  !CDS_PN = "272";
"DQS8_A_C||TDQS8_A_C":   PN = "189"  !CDS_PN = "189";
"DQS8_A_T||TDQS8_A_T":   PN = "190"  !CDS_PN = "190";
"DQS8_B_C||TDQS8_B_C":   PN = "282"  !CDS_PN = "282";
"DQS8_B_T||TDQS8_B_T":   PN = "283"  !CDS_PN = "283";
"DQS9_A_C||TDQS9_A_C":   PN = "200"  !CDS_PN = "200";
"DQS9_A_T||TDQS9_A_T":   PN = "201"  !CDS_PN = "201";
"DQS9_B_C||TDQS9_B_C":   PN = "94"  !CDS_PN = "94";
"DQS9_B_T||TDQS9_B_T||DBI4_B_N":   PN = "93"  !CDS_PN = "93";
BODY = "Q_CAP","I240": #LOCATION = "C173" !CDS_LOCATION = "C173" &SEC = "1" #&CDS_SEC = "1";
"A":   PN = "1"  !CDS_PN = "1";
"B":   PN = "2"  !CDS_PN = "2";
BODY = "Q_CAP","I241": #LOCATION = "C174" !CDS_LOCATION = "C174" &SEC = "1" #&CDS_SEC = "1";
"A":   PN = "1"  !CDS_PN = "1";
"B":   PN = "2"  !CDS_PN = "2";
BODY = "Q_RES","I244": #LOCATION = "R1580" !CDS_LOCATION = "R1580" &SEC = "1" #&CDS_SEC = "1";
"A":   PN = "1"  !CDS_PN = "1";
"B":   PN = "2"  !CDS_PN = "2";
BODY = "Q_RES","I245": #LOCATION = "R8039" !CDS_LOCATION = "R8039" &SEC = "1" #&CDS_SEC = "1";
"A":   PN = "1"  !CDS_PN = "1";
"B":   PN = "2"  !CDS_PN = "2";
BODY = "Q_RES","I250": #LOCATION = "R8086" !CDS_LOCATION = "R8086" &SEC = "1" #&CDS_SEC = "1";
"A":   PN = "1"  !CDS_PN = "1";
"B":   PN = "2"  !CDS_PN = "2";
BODY = "Q_RES","I251": #LOCATION = "R8088" !CDS_LOCATION = "R8088" &SEC = "1" #&CDS_SEC = "1";
"A":   PN = "1"  !CDS_PN = "1";
"B":   PN = "2"  !CDS_PN = "2";
BODY = "Q_RES","I252": #LOCATION = "R8087" !CDS_LOCATION = "R8087" &SEC = "1" #&CDS_SEC = "1";
"A":   PN = "1"  !CDS_PN = "1";
"B":   PN = "2"  !CDS_PN = "2";
BODY = "SCHOTTKY_12","I253": #LOCATION = "D8005" !CDS_LOCATION = "D8005" &SEC = "1" #&CDS_SEC = "1";
"A":   PN = "1"  !CDS_PN = "1";
"C":   PN = "2"  !CDS_PN = "2";
BODY = "Q_RES","I256": #LOCATION = "R1687" !CDS_LOCATION = "R1687" &SEC = "1" #&CDS_SEC = "1";
"A":   PN = "1"  !CDS_PN = "1";
"B":   PN = "2"  !CDS_PN = "2";
DRAWING = "@t6g_mb_lib.t6g(sch_1):page98";
BODY = "SCONN288_DDR506112002KQ","I22": #LOCATION = "J26" !CDS_LOCATION = "J26" &SEC = "1" #&CDS_SEC = "1";
"ALERT_N":   PN = "62"  !CDS_PN = "62";
"CA0_A":   PN = "66"  !CDS_PN = "66";
"CA0_B":   PN = "76"  !CDS_PN = "76";
"CA1_A":   PN = "211"  !CDS_PN = "211";
"CA1_B":   PN = "221"  !CDS_PN = "221";
"CA2_A":   PN = "68"  !CDS_PN = "68";
"CA2_B":   PN = "78"  !CDS_PN = "78";
"CA3_A":   PN = "213"  !CDS_PN = "213";
"CA3_B":   PN = "223"  !CDS_PN = "223";
"CA4_A":   PN = "70"  !CDS_PN = "70";
"CA4_B":   PN = "80"  !CDS_PN = "80";
"CA5_A":   PN = "215"  !CDS_PN = "215";
"CA5_B":   PN = "225"  !CDS_PN = "225";
"CA6_A":   PN = "72"  !CDS_PN = "72";
"CA6_B":   PN = "82"  !CDS_PN = "82";
"CB0_A":   PN = "51"  !CDS_PN = "51";
"CB0_B":   PN = "96"  !CDS_PN = "96";
"CB1_A":   PN = "53"  !CDS_PN = "53";
"CB1_B":   PN = "98"  !CDS_PN = "98";
"CB2_A":   PN = "196"  !CDS_PN = "196";
"CB2_B":   PN = "241"  !CDS_PN = "241";
"CB3_A":   PN = "198"  !CDS_PN = "198";
"CB3_B":   PN = "243"  !CDS_PN = "243";
"CB4_A":   PN = "58"  !CDS_PN = "58";
"CB4_B":   PN = "89"  !CDS_PN = "89";
"CB5_A":   PN = "60"  !CDS_PN = "60";
"CB5_B":   PN = "91"  !CDS_PN = "91";
"CB6_A":   PN = "203"  !CDS_PN = "203";
"CB6_B":   PN = "234"  !CDS_PN = "234";
"CB7_A":   PN = "205"  !CDS_PN = "205";
"CB7_B":   PN = "236"  !CDS_PN = "236";
"CK_C":   PN = "218"  !CDS_PN = "218";
"CK_T":   PN = "217"  !CDS_PN = "217";
"CS0_A_N":   PN = "64"  !CDS_PN = "64";
"CS0_B_N":   PN = "84"  !CDS_PN = "84";
"CS1_A_N":   PN = "209"  !CDS_PN = "209";
"CS1_B_N":   PN = "229"  !CDS_PN = "229";
"DQ0_A":   PN = "7"  !CDS_PN = "7";
"DQ0_B":   PN = "100"  !CDS_PN = "100";
"DQ1_A":   PN = "9"  !CDS_PN = "9";
"DQ1_B":   PN = "102"  !CDS_PN = "102";
"DQ2_A":   PN = "152"  !CDS_PN = "152";
"DQ2_B":   PN = "245"  !CDS_PN = "245";
"DQ3_A":   PN = "154"  !CDS_PN = "154";
"DQ3_B":   PN = "247"  !CDS_PN = "247";
"DQ4_A":   PN = "14"  !CDS_PN = "14";
"DQ4_B":   PN = "107"  !CDS_PN = "107";
"DQ5_A":   PN = "16"  !CDS_PN = "16";
"DQ5_B":   PN = "109"  !CDS_PN = "109";
"DQ6_A":   PN = "159"  !CDS_PN = "159";
"DQ6_B":   PN = "252"  !CDS_PN = "252";
"DQ7_A":   PN = "161"  !CDS_PN = "161";
"DQ7_B":   PN = "254"  !CDS_PN = "254";
"DQ8_A":   PN = "18"  !CDS_PN = "18";
"DQ8_B":   PN = "111"  !CDS_PN = "111";
"DQ9_A":   PN = "20"  !CDS_PN = "20";
"DQ9_B":   PN = "113"  !CDS_PN = "113";
"DQ10_A":   PN = "163"  !CDS_PN = "163";
"DQ10_B":   PN = "256"  !CDS_PN = "256";
"DQ11_A":   PN = "165"  !CDS_PN = "165";
"DQ11_B":   PN = "258"  !CDS_PN = "258";
"DQ12_A":   PN = "25"  !CDS_PN = "25";
"DQ12_B":   PN = "118"  !CDS_PN = "118";
"DQ13_A":   PN = "27"  !CDS_PN = "27";
"DQ13_B":   PN = "120"  !CDS_PN = "120";
"DQ14_A":   PN = "170"  !CDS_PN = "170";
"DQ14_B":   PN = "263"  !CDS_PN = "263";
"DQ15_A":   PN = "172"  !CDS_PN = "172";
"DQ15_B":   PN = "265"  !CDS_PN = "265";
"DQ16_A":   PN = "29"  !CDS_PN = "29";
"DQ16_B":   PN = "122"  !CDS_PN = "122";
"DQ17_A":   PN = "31"  !CDS_PN = "31";
"DQ17_B":   PN = "124"  !CDS_PN = "124";
"DQ18_A":   PN = "174"  !CDS_PN = "174";
"DQ18_B":   PN = "267"  !CDS_PN = "267";
"DQ19_A":   PN = "176"  !CDS_PN = "176";
"DQ19_B":   PN = "269"  !CDS_PN = "269";
"DQ20_A":   PN = "36"  !CDS_PN = "36";
"DQ20_B":   PN = "129"  !CDS_PN = "129";
"DQ21_A":   PN = "38"  !CDS_PN = "38";
"DQ21_B":   PN = "131"  !CDS_PN = "131";
"DQ22_A":   PN = "181"  !CDS_PN = "181";
"DQ22_B":   PN = "274"  !CDS_PN = "274";
"DQ23_A":   PN = "183"  !CDS_PN = "183";
"DQ23_B":   PN = "276"  !CDS_PN = "276";
"DQ24_A":   PN = "40"  !CDS_PN = "40";
"DQ24_B":   PN = "133"  !CDS_PN = "133";
"DQ25_A":   PN = "42"  !CDS_PN = "42";
"DQ25_B":   PN = "135"  !CDS_PN = "135";
"DQ26_A":   PN = "185"  !CDS_PN = "185";
"DQ26_B":   PN = "278"  !CDS_PN = "278";
"DQ27_A":   PN = "187"  !CDS_PN = "187";
"DQ27_B":   PN = "280"  !CDS_PN = "280";
"DQ28_A":   PN = "47"  !CDS_PN = "47";
"DQ28_B":   PN = "140"  !CDS_PN = "140";
"DQ29_A":   PN = "49"  !CDS_PN = "49";
"DQ29_B":   PN = "142"  !CDS_PN = "142";
"DQ30_A":   PN = "192"  !CDS_PN = "192";
"DQ30_B":   PN = "285"  !CDS_PN = "285";
"DQ31_A":   PN = "194"  !CDS_PN = "194";
"DQ31_B":   PN = "287"  !CDS_PN = "287";
"HAS":   PN = "148"  !CDS_PN = "148";
"HSCL":   PN = "4"  !CDS_PN = "4";
"HSDA":   PN = "5"  !CDS_PN = "5";
"LBD||RSP_A_N":   PN = "86"  !CDS_PN = "86";
"LBS||RSP_B_N":   PN = "87"  !CDS_PN = "87";
"PAR_A":   PN = "74"  !CDS_PN = "74";
"PAR_B":   PN = "227"  !CDS_PN = "227";
"PWR_GOOD||FAIL_N":   PN = "147"  !CDS_PN = "147";
"RESET_N":   PN = "207"  !CDS_PN = "207";
"RFU0":   PN = "2"  !CDS_PN = "2";
"RFU1":   PN = "144"  !CDS_PN = "144";
"RFU2":   PN = "149"  !CDS_PN = "149";
"RFU3":   PN = "150"  !CDS_PN = "150";
"RFU4":   PN = "220"  !CDS_PN = "220";
"RFU5":   PN = "231"  !CDS_PN = "231";
"RFU6":   PN = "232"  !CDS_PN = "232";
"VIN_MGMT":   PN = "3"  !CDS_PN = "3";
BODY = "Q_RES","I127": #LOCATION = "R770" !CDS_LOCATION = "R770" &SEC = "1" #&CDS_SEC = "1";
"A":   PN = "1"  !CDS_PN = "1";
"B":   PN = "2"  !CDS_PN = "2";
BODY = "SCONN288_DDR506112002KQ","I160": #LOCATION = "J26" !CDS_LOCATION = "J26" &SEC = "3" #&CDS_SEC = "3";
"G1":   PN = "G1"  !CDS_PN = "G1";
"G2":   PN = "G2"  !CDS_PN = "G2";
"G3":   PN = "G3"  !CDS_PN = "G3";
"VIN_BULK0":   PN = "1"  !CDS_PN = "1";
"VIN_BULK1":   PN = "145"  !CDS_PN = "145";
"VIN_BULK2":   PN = "146"  !CDS_PN = "146";
"VSS0":   PN = "6"  !CDS_PN = "6";
"VSS1":   PN = "8"  !CDS_PN = "8";
"VSS2":   PN = "10"  !CDS_PN = "10";
"VSS3":   PN = "13"  !CDS_PN = "13";
"VSS4":   PN = "15"  !CDS_PN = "15";
"VSS5":   PN = "17"  !CDS_PN = "17";
"VSS6":   PN = "19"  !CDS_PN = "19";
"VSS7":   PN = "21"  !CDS_PN = "21";
"VSS8":   PN = "24"  !CDS_PN = "24";
"VSS9":   PN = "26"  !CDS_PN = "26";
"VSS10":   PN = "28"  !CDS_PN = "28";
"VSS11":   PN = "30"  !CDS_PN = "30";
"VSS12":   PN = "32"  !CDS_PN = "32";
"VSS13":   PN = "35"  !CDS_PN = "35";
"VSS14":   PN = "37"  !CDS_PN = "37";
"VSS15":   PN = "39"  !CDS_PN = "39";
"VSS16":   PN = "41"  !CDS_PN = "41";
"VSS17":   PN = "43"  !CDS_PN = "43";
"VSS18":   PN = "46"  !CDS_PN = "46";
"VSS19":   PN = "48"  !CDS_PN = "48";
"VSS20":   PN = "50"  !CDS_PN = "50";
"VSS21":   PN = "52"  !CDS_PN = "52";
"VSS22":   PN = "54"  !CDS_PN = "54";
"VSS23":   PN = "57"  !CDS_PN = "57";
"VSS24":   PN = "59"  !CDS_PN = "59";
"VSS25":   PN = "61"  !CDS_PN = "61";
"VSS26":   PN = "63"  !CDS_PN = "63";
"VSS27":   PN = "65"  !CDS_PN = "65";
"VSS28":   PN = "67"  !CDS_PN = "67";
"VSS29":   PN = "69"  !CDS_PN = "69";
"VSS30":   PN = "71"  !CDS_PN = "71";
"VSS31":   PN = "73"  !CDS_PN = "73";
"VSS32":   PN = "75"  !CDS_PN = "75";
"VSS33":   PN = "77"  !CDS_PN = "77";
"VSS34":   PN = "79"  !CDS_PN = "79";
"VSS35":   PN = "81"  !CDS_PN = "81";
"VSS36":   PN = "83"  !CDS_PN = "83";
"VSS37":   PN = "85"  !CDS_PN = "85";
"VSS38":   PN = "88"  !CDS_PN = "88";
"VSS39":   PN = "90"  !CDS_PN = "90";
"VSS40":   PN = "92"  !CDS_PN = "92";
"VSS41":   PN = "95"  !CDS_PN = "95";
"VSS42":   PN = "97"  !CDS_PN = "97";
"VSS43":   PN = "99"  !CDS_PN = "99";
"VSS44":   PN = "101"  !CDS_PN = "101";
"VSS45":   PN = "103"  !CDS_PN = "103";
"VSS46":   PN = "106"  !CDS_PN = "106";
"VSS47":   PN = "108"  !CDS_PN = "108";
"VSS48":   PN = "110"  !CDS_PN = "110";
"VSS49":   PN = "112"  !CDS_PN = "112";
"VSS50":   PN = "114"  !CDS_PN = "114";
"VSS51":   PN = "117"  !CDS_PN = "117";
"VSS52":   PN = "119"  !CDS_PN = "119";
"VSS53":   PN = "121"  !CDS_PN = "121";
"VSS54":   PN = "123"  !CDS_PN = "123";
"VSS55":   PN = "125"  !CDS_PN = "125";
"VSS56":   PN = "128"  !CDS_PN = "128";
"VSS57":   PN = "130"  !CDS_PN = "130";
"VSS58":   PN = "132"  !CDS_PN = "132";
"VSS59":   PN = "134"  !CDS_PN = "134";
"VSS60":   PN = "136"  !CDS_PN = "136";
"VSS61":   PN = "139"  !CDS_PN = "139";
"VSS62":   PN = "141"  !CDS_PN = "141";
"VSS63":   PN = "143"  !CDS_PN = "143";
"VSS64":   PN = "151"  !CDS_PN = "151";
"VSS65":   PN = "153"  !CDS_PN = "153";
"VSS66":   PN = "155"  !CDS_PN = "155";
"VSS67":   PN = "158"  !CDS_PN = "158";
"VSS68":   PN = "160"  !CDS_PN = "160";
"VSS69":   PN = "162"  !CDS_PN = "162";
"VSS70":   PN = "164"  !CDS_PN = "164";
"VSS71":   PN = "166"  !CDS_PN = "166";
"VSS72":   PN = "169"  !CDS_PN = "169";
"VSS73":   PN = "171"  !CDS_PN = "171";
"VSS74":   PN = "173"  !CDS_PN = "173";
"VSS75":   PN = "175"  !CDS_PN = "175";
"VSS76":   PN = "177"  !CDS_PN = "177";
"VSS77":   PN = "180"  !CDS_PN = "180";
"VSS78":   PN = "182"  !CDS_PN = "182";
"VSS79":   PN = "184"  !CDS_PN = "184";
"VSS80":   PN = "186"  !CDS_PN = "186";
"VSS81":   PN = "188"  !CDS_PN = "188";
"VSS82":   PN = "191"  !CDS_PN = "191";
"VSS83":   PN = "193"  !CDS_PN = "193";
"VSS84":   PN = "195"  !CDS_PN = "195";
"VSS85":   PN = "197"  !CDS_PN = "197";
"VSS86":   PN = "199"  !CDS_PN = "199";
"VSS87":   PN = "202"  !CDS_PN = "202";
"VSS88":   PN = "204"  !CDS_PN = "204";
"VSS89":   PN = "206"  !CDS_PN = "206";
"VSS90":   PN = "208"  !CDS_PN = "208";
"VSS91":   PN = "210"  !CDS_PN = "210";
"VSS92":   PN = "212"  !CDS_PN = "212";
"VSS93":   PN = "214"  !CDS_PN = "214";
"VSS94":   PN = "216"  !CDS_PN = "216";
"VSS95":   PN = "219"  !CDS_PN = "219";
"VSS96":   PN = "222"  !CDS_PN = "222";
"VSS97":   PN = "224"  !CDS_PN = "224";
"VSS98":   PN = "226"  !CDS_PN = "226";
"VSS99":   PN = "228"  !CDS_PN = "228";
"VSS100":   PN = "230"  !CDS_PN = "230";
"VSS101":   PN = "233"  !CDS_PN = "233";
"VSS102":   PN = "235"  !CDS_PN = "235";
"VSS103":   PN = "237"  !CDS_PN = "237";
"VSS104":   PN = "240"  !CDS_PN = "240";
"VSS105":   PN = "242"  !CDS_PN = "242";
"VSS106":   PN = "244"  !CDS_PN = "244";
"VSS107":   PN = "246"  !CDS_PN = "246";
"VSS108":   PN = "248"  !CDS_PN = "248";
"VSS109":   PN = "251"  !CDS_PN = "251";
"VSS110":   PN = "253"  !CDS_PN = "253";
"VSS111":   PN = "255"  !CDS_PN = "255";
"VSS112":   PN = "257"  !CDS_PN = "257";
"VSS113":   PN = "259"  !CDS_PN = "259";
"VSS114":   PN = "262"  !CDS_PN = "262";
"VSS115":   PN = "264"  !CDS_PN = "264";
"VSS116":   PN = "266"  !CDS_PN = "266";
"VSS117":   PN = "268"  !CDS_PN = "268";
"VSS118":   PN = "270"  !CDS_PN = "270";
"VSS119":   PN = "273"  !CDS_PN = "273";
"VSS120":   PN = "275"  !CDS_PN = "275";
"VSS121":   PN = "277"  !CDS_PN = "277";
"VSS122":   PN = "279"  !CDS_PN = "279";
"VSS123":   PN = "281"  !CDS_PN = "281";
"VSS124":   PN = "284"  !CDS_PN = "284";
"VSS125":   PN = "286"  !CDS_PN = "286";
"VSS126":   PN = "288"  !CDS_PN = "288";
BODY = "Q_CAP","I185": #LOCATION = "C140" !CDS_LOCATION = "C140" &SEC = "1" #&CDS_SEC = "1";
"A":   PN = "1"  !CDS_PN = "1";
"B":   PN = "2"  !CDS_PN = "2";
BODY = "Q_RES","I188": #LOCATION = "R304" !CDS_LOCATION = "R304" &SEC = "1" #&CDS_SEC = "1";
"A":   PN = "1"  !CDS_PN = "1";
"B":   PN = "2"  !CDS_PN = "2";
BODY = "Q_RES","I190": #LOCATION = "R104" !CDS_LOCATION = "R104" &SEC = "1" #&CDS_SEC = "1";
"A":   PN = "1"  !CDS_PN = "1";
"B":   PN = "2"  !CDS_PN = "2";
BODY = "SCONN288_DDR506112002KQ","I236": #LOCATION = "J26" !CDS_LOCATION = "J26" &SEC = "2" #&CDS_SEC = "2";
"DQS0_A_C":   PN = "12"  !CDS_PN = "12";
"DQS0_A_T":   PN = "11"  !CDS_PN = "11";
"DQS0_B_C":   PN = "105"  !CDS_PN = "105";
"DQS0_B_T":   PN = "104"  !CDS_PN = "104";
"DQS1_A_C":   PN = "23"  !CDS_PN = "23";
"DQS1_A_T":   PN = "22"  !CDS_PN = "22";
"DQS1_B_C":   PN = "116"  !CDS_PN = "116";
"DQS1_B_T":   PN = "115"  !CDS_PN = "115";
"DQS2_A_C":   PN = "34"  !CDS_PN = "34";
"DQS2_A_T":   PN = "33"  !CDS_PN = "33";
"DQS2_B_C":   PN = "127"  !CDS_PN = "127";
"DQS2_B_T":   PN = "126"  !CDS_PN = "126";
"DQS3_A_C":   PN = "45"  !CDS_PN = "45";
"DQS3_A_T":   PN = "44"  !CDS_PN = "44";
"DQS3_B_C":   PN = "138"  !CDS_PN = "138";
"DQS3_B_T":   PN = "137"  !CDS_PN = "137";
"DQS4_A_C":   PN = "56"  !CDS_PN = "56";
"DQS4_A_T":   PN = "55"  !CDS_PN = "55";
"DQS4_B_C":   PN = "238"  !CDS_PN = "238";
"DQS4_B_T":   PN = "239"  !CDS_PN = "239";
"DQS5_A_C||TDQS5_A_C||DQS5_A_T||TDQS5_A_T":   PN = "156"  !CDS_PN = "156";
"DQS5_A_T||TDQS5_A_T":   PN = "157"  !CDS_PN = "157";
"DQS5_B_C||TDQS5_B_C":   PN = "249"  !CDS_PN = "249";
"DQS5_B_T||TDQS5_B_T":   PN = "250"  !CDS_PN = "250";
"DQS6_A_C||TDQS6_A_C||DQS6_A_T||TDQS6_A_T":   PN = "167"  !CDS_PN = "167";
"DQS6_A_T||TDQS6_A_T":   PN = "168"  !CDS_PN = "168";
"DQS6_B_C||TDQS6_B_C":   PN = "260"  !CDS_PN = "260";
"DQS6_B_T||TDQS6_B_T":   PN = "261"  !CDS_PN = "261";
"DQS7_A_C||TDQS7_A_C":   PN = "178"  !CDS_PN = "178";
"DQS7_A_T||TDQS7_A_T":   PN = "179"  !CDS_PN = "179";
"DQS7_B_C||TDQS7_B_C":   PN = "271"  !CDS_PN = "271";
"DQS7_B_T||TDQS7_B_T":   PN = "272"  !CDS_PN = "272";
"DQS8_A_C||TDQS8_A_C":   PN = "189"  !CDS_PN = "189";
"DQS8_A_T||TDQS8_A_T":   PN = "190"  !CDS_PN = "190";
"DQS8_B_C||TDQS8_B_C":   PN = "282"  !CDS_PN = "282";
"DQS8_B_T||TDQS8_B_T":   PN = "283"  !CDS_PN = "283";
"DQS9_A_C||TDQS9_A_C":   PN = "200"  !CDS_PN = "200";
"DQS9_A_T||TDQS9_A_T":   PN = "201"  !CDS_PN = "201";
"DQS9_B_C||TDQS9_B_C":   PN = "94"  !CDS_PN = "94";
"DQS9_B_T||TDQS9_B_T||DBI4_B_N":   PN = "93"  !CDS_PN = "93";
BODY = "Q_CAP","I238": #LOCATION = "C175" !CDS_LOCATION = "C175" &SEC = "1" #&CDS_SEC = "1";
"A":   PN = "1"  !CDS_PN = "1";
"B":   PN = "2"  !CDS_PN = "2";
BODY = "Q_CAP","I239": #LOCATION = "C177" !CDS_LOCATION = "C177" &SEC = "1" #&CDS_SEC = "1";
"A":   PN = "1"  !CDS_PN = "1";
"B":   PN = "2"  !CDS_PN = "2";
BODY = "Q_RES","I242": #LOCATION = "R1581" !CDS_LOCATION = "R1581" &SEC = "1" #&CDS_SEC = "1";
"A":   PN = "1"  !CDS_PN = "1";
"B":   PN = "2"  !CDS_PN = "2";
BODY = "Q_RES","I243": #LOCATION = "R1696" !CDS_LOCATION = "R1696" &SEC = "1" #&CDS_SEC = "1";
"A":   PN = "1"  !CDS_PN = "1";
"B":   PN = "2"  !CDS_PN = "2";
DRAWING = "@t6g_mb_lib.t6g(sch_1):page99";
BODY = "SCONN288_DDR506112002KQ","I22": #LOCATION = "J28" !CDS_LOCATION = "J28" &SEC = "1" #&CDS_SEC = "1";
"ALERT_N":   PN = "62"  !CDS_PN = "62";
"CA0_A":   PN = "66"  !CDS_PN = "66";
"CA0_B":   PN = "76"  !CDS_PN = "76";
"CA1_A":   PN = "211"  !CDS_PN = "211";
"CA1_B":   PN = "221"  !CDS_PN = "221";
"CA2_A":   PN = "68"  !CDS_PN = "68";
"CA2_B":   PN = "78"  !CDS_PN = "78";
"CA3_A":   PN = "213"  !CDS_PN = "213";
"CA3_B":   PN = "223"  !CDS_PN = "223";
"CA4_A":   PN = "70"  !CDS_PN = "70";
"CA4_B":   PN = "80"  !CDS_PN = "80";
"CA5_A":   PN = "215"  !CDS_PN = "215";
"CA5_B":   PN = "225"  !CDS_PN = "225";
"CA6_A":   PN = "72"  !CDS_PN = "72";
"CA6_B":   PN = "82"  !CDS_PN = "82";
"CB0_A":   PN = "51"  !CDS_PN = "51";
"CB0_B":   PN = "96"  !CDS_PN = "96";
"CB1_A":   PN = "53"  !CDS_PN = "53";
"CB1_B":   PN = "98"  !CDS_PN = "98";
"CB2_A":   PN = "196"  !CDS_PN = "196";
"CB2_B":   PN = "241"  !CDS_PN = "241";
"CB3_A":   PN = "198"  !CDS_PN = "198";
"CB3_B":   PN = "243"  !CDS_PN = "243";
"CB4_A":   PN = "58"  !CDS_PN = "58";
"CB4_B":   PN = "89"  !CDS_PN = "89";
"CB5_A":   PN = "60"  !CDS_PN = "60";
"CB5_B":   PN = "91"  !CDS_PN = "91";
"CB6_A":   PN = "203"  !CDS_PN = "203";
"CB6_B":   PN = "234"  !CDS_PN = "234";
"CB7_A":   PN = "205"  !CDS_PN = "205";
"CB7_B":   PN = "236"  !CDS_PN = "236";
"CK_C":   PN = "218"  !CDS_PN = "218";
"CK_T":   PN = "217"  !CDS_PN = "217";
"CS0_A_N":   PN = "64"  !CDS_PN = "64";
"CS0_B_N":   PN = "84"  !CDS_PN = "84";
"CS1_A_N":   PN = "209"  !CDS_PN = "209";
"CS1_B_N":   PN = "229"  !CDS_PN = "229";
"DQ0_A":   PN = "7"  !CDS_PN = "7";
"DQ0_B":   PN = "100"  !CDS_PN = "100";
"DQ1_A":   PN = "9"  !CDS_PN = "9";
"DQ1_B":   PN = "102"  !CDS_PN = "102";
"DQ2_A":   PN = "152"  !CDS_PN = "152";
"DQ2_B":   PN = "245"  !CDS_PN = "245";
"DQ3_A":   PN = "154"  !CDS_PN = "154";
"DQ3_B":   PN = "247"  !CDS_PN = "247";
"DQ4_A":   PN = "14"  !CDS_PN = "14";
"DQ4_B":   PN = "107"  !CDS_PN = "107";
"DQ5_A":   PN = "16"  !CDS_PN = "16";
"DQ5_B":   PN = "109"  !CDS_PN = "109";
"DQ6_A":   PN = "159"  !CDS_PN = "159";
"DQ6_B":   PN = "252"  !CDS_PN = "252";
"DQ7_A":   PN = "161"  !CDS_PN = "161";
"DQ7_B":   PN = "254"  !CDS_PN = "254";
"DQ8_A":   PN = "18"  !CDS_PN = "18";
"DQ8_B":   PN = "111"  !CDS_PN = "111";
"DQ9_A":   PN = "20"  !CDS_PN = "20";
"DQ9_B":   PN = "113"  !CDS_PN = "113";
"DQ10_A":   PN = "163"  !CDS_PN = "163";
"DQ10_B":   PN = "256"  !CDS_PN = "256";
"DQ11_A":   PN = "165"  !CDS_PN = "165";
"DQ11_B":   PN = "258"  !CDS_PN = "258";
"DQ12_A":   PN = "25"  !CDS_PN = "25";
"DQ12_B":   PN = "118"  !CDS_PN = "118";
"DQ13_A":   PN = "27"  !CDS_PN = "27";
"DQ13_B":   PN = "120"  !CDS_PN = "120";
"DQ14_A":   PN = "170"  !CDS_PN = "170";
"DQ14_B":   PN = "263"  !CDS_PN = "263";
"DQ15_A":   PN = "172"  !CDS_PN = "172";
"DQ15_B":   PN = "265"  !CDS_PN = "265";
"DQ16_A":   PN = "29"  !CDS_PN = "29";
"DQ16_B":   PN = "122"  !CDS_PN = "122";
"DQ17_A":   PN = "31"  !CDS_PN = "31";
"DQ17_B":   PN = "124"  !CDS_PN = "124";
"DQ18_A":   PN = "174"  !CDS_PN = "174";
"DQ18_B":   PN = "267"  !CDS_PN = "267";
"DQ19_A":   PN = "176"  !CDS_PN = "176";
"DQ19_B":   PN = "269"  !CDS_PN = "269";
"DQ20_A":   PN = "36"  !CDS_PN = "36";
"DQ20_B":   PN = "129"  !CDS_PN = "129";
"DQ21_A":   PN = "38"  !CDS_PN = "38";
"DQ21_B":   PN = "131"  !CDS_PN = "131";
"DQ22_A":   PN = "181"  !CDS_PN = "181";
"DQ22_B":   PN = "274"  !CDS_PN = "274";
"DQ23_A":   PN = "183"  !CDS_PN = "183";
"DQ23_B":   PN = "276"  !CDS_PN = "276";
"DQ24_A":   PN = "40"  !CDS_PN = "40";
"DQ24_B":   PN = "133"  !CDS_PN = "133";
"DQ25_A":   PN = "42"  !CDS_PN = "42";
"DQ25_B":   PN = "135"  !CDS_PN = "135";
"DQ26_A":   PN = "185"  !CDS_PN = "185";
"DQ26_B":   PN = "278"  !CDS_PN = "278";
"DQ27_A":   PN = "187"  !CDS_PN = "187";
"DQ27_B":   PN = "280"  !CDS_PN = "280";
"DQ28_A":   PN = "47"  !CDS_PN = "47";
"DQ28_B":   PN = "140"  !CDS_PN = "140";
"DQ29_A":   PN = "49"  !CDS_PN = "49";
"DQ29_B":   PN = "142"  !CDS_PN = "142";
"DQ30_A":   PN = "192"  !CDS_PN = "192";
"DQ30_B":   PN = "285"  !CDS_PN = "285";
"DQ31_A":   PN = "194"  !CDS_PN = "194";
"DQ31_B":   PN = "287"  !CDS_PN = "287";
"HAS":   PN = "148"  !CDS_PN = "148";
"HSCL":   PN = "4"  !CDS_PN = "4";
"HSDA":   PN = "5"  !CDS_PN = "5";
"LBD||RSP_A_N":   PN = "86"  !CDS_PN = "86";
"LBS||RSP_B_N":   PN = "87"  !CDS_PN = "87";
"PAR_A":   PN = "74"  !CDS_PN = "74";
"PAR_B":   PN = "227"  !CDS_PN = "227";
"PWR_GOOD||FAIL_N":   PN = "147"  !CDS_PN = "147";
"RESET_N":   PN = "207"  !CDS_PN = "207";
"RFU0":   PN = "2"  !CDS_PN = "2";
"RFU1":   PN = "144"  !CDS_PN = "144";
"RFU2":   PN = "149"  !CDS_PN = "149";
"RFU3":   PN = "150"  !CDS_PN = "150";
"RFU4":   PN = "220"  !CDS_PN = "220";
"RFU5":   PN = "231"  !CDS_PN = "231";
"RFU6":   PN = "232"  !CDS_PN = "232";
"VIN_MGMT":   PN = "3"  !CDS_PN = "3";
BODY = "Q_RES","I148": #LOCATION = "R771" !CDS_LOCATION = "R771" &SEC = "1" #&CDS_SEC = "1";
"A":   PN = "1"  !CDS_PN = "1";
"B":   PN = "2"  !CDS_PN = "2";
BODY = "SCONN288_DDR506112002KQ","I155": #LOCATION = "J28" !CDS_LOCATION = "J28" &SEC = "3" #&CDS_SEC = "3";
"G1":   PN = "G1"  !CDS_PN = "G1";
"G2":   PN = "G2"  !CDS_PN = "G2";
"G3":   PN = "G3"  !CDS_PN = "G3";
"VIN_BULK0":   PN = "1"  !CDS_PN = "1";
"VIN_BULK1":   PN = "145"  !CDS_PN = "145";
"VIN_BULK2":   PN = "146"  !CDS_PN = "146";
"VSS0":   PN = "6"  !CDS_PN = "6";
"VSS1":   PN = "8"  !CDS_PN = "8";
"VSS2":   PN = "10"  !CDS_PN = "10";
"VSS3":   PN = "13"  !CDS_PN = "13";
"VSS4":   PN = "15"  !CDS_PN = "15";
"VSS5":   PN = "17"  !CDS_PN = "17";
"VSS6":   PN = "19"  !CDS_PN = "19";
"VSS7":   PN = "21"  !CDS_PN = "21";
"VSS8":   PN = "24"  !CDS_PN = "24";
"VSS9":   PN = "26"  !CDS_PN = "26";
"VSS10":   PN = "28"  !CDS_PN = "28";
"VSS11":   PN = "30"  !CDS_PN = "30";
"VSS12":   PN = "32"  !CDS_PN = "32";
"VSS13":   PN = "35"  !CDS_PN = "35";
"VSS14":   PN = "37"  !CDS_PN = "37";
"VSS15":   PN = "39"  !CDS_PN = "39";
"VSS16":   PN = "41"  !CDS_PN = "41";
"VSS17":   PN = "43"  !CDS_PN = "43";
"VSS18":   PN = "46"  !CDS_PN = "46";
"VSS19":   PN = "48"  !CDS_PN = "48";
"VSS20":   PN = "50"  !CDS_PN = "50";
"VSS21":   PN = "52"  !CDS_PN = "52";
"VSS22":   PN = "54"  !CDS_PN = "54";
"VSS23":   PN = "57"  !CDS_PN = "57";
"VSS24":   PN = "59"  !CDS_PN = "59";
"VSS25":   PN = "61"  !CDS_PN = "61";
"VSS26":   PN = "63"  !CDS_PN = "63";
"VSS27":   PN = "65"  !CDS_PN = "65";
"VSS28":   PN = "67"  !CDS_PN = "67";
"VSS29":   PN = "69"  !CDS_PN = "69";
"VSS30":   PN = "71"  !CDS_PN = "71";
"VSS31":   PN = "73"  !CDS_PN = "73";
"VSS32":   PN = "75"  !CDS_PN = "75";
"VSS33":   PN = "77"  !CDS_PN = "77";
"VSS34":   PN = "79"  !CDS_PN = "79";
"VSS35":   PN = "81"  !CDS_PN = "81";
"VSS36":   PN = "83"  !CDS_PN = "83";
"VSS37":   PN = "85"  !CDS_PN = "85";
"VSS38":   PN = "88"  !CDS_PN = "88";
"VSS39":   PN = "90"  !CDS_PN = "90";
"VSS40":   PN = "92"  !CDS_PN = "92";
"VSS41":   PN = "95"  !CDS_PN = "95";
"VSS42":   PN = "97"  !CDS_PN = "97";
"VSS43":   PN = "99"  !CDS_PN = "99";
"VSS44":   PN = "101"  !CDS_PN = "101";
"VSS45":   PN = "103"  !CDS_PN = "103";
"VSS46":   PN = "106"  !CDS_PN = "106";
"VSS47":   PN = "108"  !CDS_PN = "108";
"VSS48":   PN = "110"  !CDS_PN = "110";
"VSS49":   PN = "112"  !CDS_PN = "112";
"VSS50":   PN = "114"  !CDS_PN = "114";
"VSS51":   PN = "117"  !CDS_PN = "117";
"VSS52":   PN = "119"  !CDS_PN = "119";
"VSS53":   PN = "121"  !CDS_PN = "121";
"VSS54":   PN = "123"  !CDS_PN = "123";
"VSS55":   PN = "125"  !CDS_PN = "125";
"VSS56":   PN = "128"  !CDS_PN = "128";
"VSS57":   PN = "130"  !CDS_PN = "130";
"VSS58":   PN = "132"  !CDS_PN = "132";
"VSS59":   PN = "134"  !CDS_PN = "134";
"VSS60":   PN = "136"  !CDS_PN = "136";
"VSS61":   PN = "139"  !CDS_PN = "139";
"VSS62":   PN = "141"  !CDS_PN = "141";
"VSS63":   PN = "143"  !CDS_PN = "143";
"VSS64":   PN = "151"  !CDS_PN = "151";
"VSS65":   PN = "153"  !CDS_PN = "153";
"VSS66":   PN = "155"  !CDS_PN = "155";
"VSS67":   PN = "158"  !CDS_PN = "158";
"VSS68":   PN = "160"  !CDS_PN = "160";
"VSS69":   PN = "162"  !CDS_PN = "162";
"VSS70":   PN = "164"  !CDS_PN = "164";
"VSS71":   PN = "166"  !CDS_PN = "166";
"VSS72":   PN = "169"  !CDS_PN = "169";
"VSS73":   PN = "171"  !CDS_PN = "171";
"VSS74":   PN = "173"  !CDS_PN = "173";
"VSS75":   PN = "175"  !CDS_PN = "175";
"VSS76":   PN = "177"  !CDS_PN = "177";
"VSS77":   PN = "180"  !CDS_PN = "180";
"VSS78":   PN = "182"  !CDS_PN = "182";
"VSS79":   PN = "184"  !CDS_PN = "184";
"VSS80":   PN = "186"  !CDS_PN = "186";
"VSS81":   PN = "188"  !CDS_PN = "188";
"VSS82":   PN = "191"  !CDS_PN = "191";
"VSS83":   PN = "193"  !CDS_PN = "193";
"VSS84":   PN = "195"  !CDS_PN = "195";
"VSS85":   PN = "197"  !CDS_PN = "197";
"VSS86":   PN = "199"  !CDS_PN = "199";
"VSS87":   PN = "202"  !CDS_PN = "202";
"VSS88":   PN = "204"  !CDS_PN = "204";
"VSS89":   PN = "206"  !CDS_PN = "206";
"VSS90":   PN = "208"  !CDS_PN = "208";
"VSS91":   PN = "210"  !CDS_PN = "210";
"VSS92":   PN = "212"  !CDS_PN = "212";
"VSS93":   PN = "214"  !CDS_PN = "214";
"VSS94":   PN = "216"  !CDS_PN = "216";
"VSS95":   PN = "219"  !CDS_PN = "219";
"VSS96":   PN = "222"  !CDS_PN = "222";
"VSS97":   PN = "224"  !CDS_PN = "224";
"VSS98":   PN = "226"  !CDS_PN = "226";
"VSS99":   PN = "228"  !CDS_PN = "228";
"VSS100":   PN = "230"  !CDS_PN = "230";
"VSS101":   PN = "233"  !CDS_PN = "233";
"VSS102":   PN = "235"  !CDS_PN = "235";
"VSS103":   PN = "237"  !CDS_PN = "237";
"VSS104":   PN = "240"  !CDS_PN = "240";
"VSS105":   PN = "242"  !CDS_PN = "242";
"VSS106":   PN = "244"  !CDS_PN = "244";
"VSS107":   PN = "246"  !CDS_PN = "246";
"VSS108":   PN = "248"  !CDS_PN = "248";
"VSS109":   PN = "251"  !CDS_PN = "251";
"VSS110":   PN = "253"  !CDS_PN = "253";
"VSS111":   PN = "255"  !CDS_PN = "255";
"VSS112":   PN = "257"  !CDS_PN = "257";
"VSS113":   PN = "259"  !CDS_PN = "259";
"VSS114":   PN = "262"  !CDS_PN = "262";
"VSS115":   PN = "264"  !CDS_PN = "264";
"VSS116":   PN = "266"  !CDS_PN = "266";
"VSS117":   PN = "268"  !CDS_PN = "268";
"VSS118":   PN = "270"  !CDS_PN = "270";
"VSS119":   PN = "273"  !CDS_PN = "273";
"VSS120":   PN = "275"  !CDS_PN = "275";
"VSS121":   PN = "277"  !CDS_PN = "277";
"VSS122":   PN = "279"  !CDS_PN = "279";
"VSS123":   PN = "281"  !CDS_PN = "281";
"VSS124":   PN = "284"  !CDS_PN = "284";
"VSS125":   PN = "286"  !CDS_PN = "286";
"VSS126":   PN = "288"  !CDS_PN = "288";
BODY = "Q_CAP","I185": #LOCATION = "C144" !CDS_LOCATION = "C144" &SEC = "1" #&CDS_SEC = "1";
"A":   PN = "1"  !CDS_PN = "1";
"B":   PN = "2"  !CDS_PN = "2";
BODY = "Q_RES","I188": #LOCATION = "R305" !CDS_LOCATION = "R305" &SEC = "1" #&CDS_SEC = "1";
"A":   PN = "1"  !CDS_PN = "1";
"B":   PN = "2"  !CDS_PN = "2";
BODY = "Q_RES","I190": #LOCATION = "R105" !CDS_LOCATION = "R105" &SEC = "1" #&CDS_SEC = "1";
"A":   PN = "1"  !CDS_PN = "1";
"B":   PN = "2"  !CDS_PN = "2";
BODY = "SCONN288_DDR506112002KQ","I236": #LOCATION = "J28" !CDS_LOCATION = "J28" &SEC = "2" #&CDS_SEC = "2";
"DQS0_A_C":   PN = "12"  !CDS_PN = "12";
"DQS0_A_T":   PN = "11"  !CDS_PN = "11";
"DQS0_B_C":   PN = "105"  !CDS_PN = "105";
"DQS0_B_T":   PN = "104"  !CDS_PN = "104";
"DQS1_A_C":   PN = "23"  !CDS_PN = "23";
"DQS1_A_T":   PN = "22"  !CDS_PN = "22";
"DQS1_B_C":   PN = "116"  !CDS_PN = "116";
"DQS1_B_T":   PN = "115"  !CDS_PN = "115";
"DQS2_A_C":   PN = "34"  !CDS_PN = "34";
"DQS2_A_T":   PN = "33"  !CDS_PN = "33";
"DQS2_B_C":   PN = "127"  !CDS_PN = "127";
"DQS2_B_T":   PN = "126"  !CDS_PN = "126";
"DQS3_A_C":   PN = "45"  !CDS_PN = "45";
"DQS3_A_T":   PN = "44"  !CDS_PN = "44";
"DQS3_B_C":   PN = "138"  !CDS_PN = "138";
"DQS3_B_T":   PN = "137"  !CDS_PN = "137";
"DQS4_A_C":   PN = "56"  !CDS_PN = "56";
"DQS4_A_T":   PN = "55"  !CDS_PN = "55";
"DQS4_B_C":   PN = "238"  !CDS_PN = "238";
"DQS4_B_T":   PN = "239"  !CDS_PN = "239";
"DQS5_A_C||TDQS5_A_C||DQS5_A_T||TDQS5_A_T":   PN = "156"  !CDS_PN = "156";
"DQS5_A_T||TDQS5_A_T":   PN = "157"  !CDS_PN = "157";
"DQS5_B_C||TDQS5_B_C":   PN = "249"  !CDS_PN = "249";
"DQS5_B_T||TDQS5_B_T":   PN = "250"  !CDS_PN = "250";
"DQS6_A_C||TDQS6_A_C||DQS6_A_T||TDQS6_A_T":   PN = "167"  !CDS_PN = "167";
"DQS6_A_T||TDQS6_A_T":   PN = "168"  !CDS_PN = "168";
"DQS6_B_C||TDQS6_B_C":   PN = "260"  !CDS_PN = "260";
"DQS6_B_T||TDQS6_B_T":   PN = "261"  !CDS_PN = "261";
"DQS7_A_C||TDQS7_A_C":   PN = "178"  !CDS_PN = "178";
"DQS7_A_T||TDQS7_A_T":   PN = "179"  !CDS_PN = "179";
"DQS7_B_C||TDQS7_B_C":   PN = "271"  !CDS_PN = "271";
"DQS7_B_T||TDQS7_B_T":   PN = "272"  !CDS_PN = "272";
"DQS8_A_C||TDQS8_A_C":   PN = "189"  !CDS_PN = "189";
"DQS8_A_T||TDQS8_A_T":   PN = "190"  !CDS_PN = "190";
"DQS8_B_C||TDQS8_B_C":   PN = "282"  !CDS_PN = "282";
"DQS8_B_T||TDQS8_B_T":   PN = "283"  !CDS_PN = "283";
"DQS9_A_C||TDQS9_A_C":   PN = "200"  !CDS_PN = "200";
"DQS9_A_T||TDQS9_A_T":   PN = "201"  !CDS_PN = "201";
"DQS9_B_C||TDQS9_B_C":   PN = "94"  !CDS_PN = "94";
"DQS9_B_T||TDQS9_B_T||DBI4_B_N":   PN = "93"  !CDS_PN = "93";
BODY = "Q_CAP","I238": #LOCATION = "C178" !CDS_LOCATION = "C178" &SEC = "1" #&CDS_SEC = "1";
"A":   PN = "1"  !CDS_PN = "1";
"B":   PN = "2"  !CDS_PN = "2";
BODY = "Q_CAP","I239": #LOCATION = "C179" !CDS_LOCATION = "C179" &SEC = "1" #&CDS_SEC = "1";
"A":   PN = "1"  !CDS_PN = "1";
"B":   PN = "2"  !CDS_PN = "2";
BODY = "Q_RES","I242": #LOCATION = "R1582" !CDS_LOCATION = "R1582" &SEC = "1" #&CDS_SEC = "1";
"A":   PN = "1"  !CDS_PN = "1";
"B":   PN = "2"  !CDS_PN = "2";
BODY = "Q_RES","I243": #LOCATION = "R1697" !CDS_LOCATION = "R1697" &SEC = "1" #&CDS_SEC = "1";
"A":   PN = "1"  !CDS_PN = "1";
"B":   PN = "2"  !CDS_PN = "2";
DRAWING = "@t6g_mb_lib.t6g(sch_1):page100";
BODY = "SCONN288_DDR506112002KQ","I52": #LOCATION = "J30" !CDS_LOCATION = "J30" &SEC = "1" #&CDS_SEC = "1";
"ALERT_N":   PN = "62"  !CDS_PN = "62";
"CA0_A":   PN = "66"  !CDS_PN = "66";
"CA0_B":   PN = "76"  !CDS_PN = "76";
"CA1_A":   PN = "211"  !CDS_PN = "211";
"CA1_B":   PN = "221"  !CDS_PN = "221";
"CA2_A":   PN = "68"  !CDS_PN = "68";
"CA2_B":   PN = "78"  !CDS_PN = "78";
"CA3_A":   PN = "213"  !CDS_PN = "213";
"CA3_B":   PN = "223"  !CDS_PN = "223";
"CA4_A":   PN = "70"  !CDS_PN = "70";
"CA4_B":   PN = "80"  !CDS_PN = "80";
"CA5_A":   PN = "215"  !CDS_PN = "215";
"CA5_B":   PN = "225"  !CDS_PN = "225";
"CA6_A":   PN = "72"  !CDS_PN = "72";
"CA6_B":   PN = "82"  !CDS_PN = "82";
"CB0_A":   PN = "51"  !CDS_PN = "51";
"CB0_B":   PN = "96"  !CDS_PN = "96";
"CB1_A":   PN = "53"  !CDS_PN = "53";
"CB1_B":   PN = "98"  !CDS_PN = "98";
"CB2_A":   PN = "196"  !CDS_PN = "196";
"CB2_B":   PN = "241"  !CDS_PN = "241";
"CB3_A":   PN = "198"  !CDS_PN = "198";
"CB3_B":   PN = "243"  !CDS_PN = "243";
"CB4_A":   PN = "58"  !CDS_PN = "58";
"CB4_B":   PN = "89"  !CDS_PN = "89";
"CB5_A":   PN = "60"  !CDS_PN = "60";
"CB5_B":   PN = "91"  !CDS_PN = "91";
"CB6_A":   PN = "203"  !CDS_PN = "203";
"CB6_B":   PN = "234"  !CDS_PN = "234";
"CB7_A":   PN = "205"  !CDS_PN = "205";
"CB7_B":   PN = "236"  !CDS_PN = "236";
"CK_C":   PN = "218"  !CDS_PN = "218";
"CK_T":   PN = "217"  !CDS_PN = "217";
"CS0_A_N":   PN = "64"  !CDS_PN = "64";
"CS0_B_N":   PN = "84"  !CDS_PN = "84";
"CS1_A_N":   PN = "209"  !CDS_PN = "209";
"CS1_B_N":   PN = "229"  !CDS_PN = "229";
"DQ0_A":   PN = "7"  !CDS_PN = "7";
"DQ0_B":   PN = "100"  !CDS_PN = "100";
"DQ1_A":   PN = "9"  !CDS_PN = "9";
"DQ1_B":   PN = "102"  !CDS_PN = "102";
"DQ2_A":   PN = "152"  !CDS_PN = "152";
"DQ2_B":   PN = "245"  !CDS_PN = "245";
"DQ3_A":   PN = "154"  !CDS_PN = "154";
"DQ3_B":   PN = "247"  !CDS_PN = "247";
"DQ4_A":   PN = "14"  !CDS_PN = "14";
"DQ4_B":   PN = "107"  !CDS_PN = "107";
"DQ5_A":   PN = "16"  !CDS_PN = "16";
"DQ5_B":   PN = "109"  !CDS_PN = "109";
"DQ6_A":   PN = "159"  !CDS_PN = "159";
"DQ6_B":   PN = "252"  !CDS_PN = "252";
"DQ7_A":   PN = "161"  !CDS_PN = "161";
"DQ7_B":   PN = "254"  !CDS_PN = "254";
"DQ8_A":   PN = "18"  !CDS_PN = "18";
"DQ8_B":   PN = "111"  !CDS_PN = "111";
"DQ9_A":   PN = "20"  !CDS_PN = "20";
"DQ9_B":   PN = "113"  !CDS_PN = "113";
"DQ10_A":   PN = "163"  !CDS_PN = "163";
"DQ10_B":   PN = "256"  !CDS_PN = "256";
"DQ11_A":   PN = "165"  !CDS_PN = "165";
"DQ11_B":   PN = "258"  !CDS_PN = "258";
"DQ12_A":   PN = "25"  !CDS_PN = "25";
"DQ12_B":   PN = "118"  !CDS_PN = "118";
"DQ13_A":   PN = "27"  !CDS_PN = "27";
"DQ13_B":   PN = "120"  !CDS_PN = "120";
"DQ14_A":   PN = "170"  !CDS_PN = "170";
"DQ14_B":   PN = "263"  !CDS_PN = "263";
"DQ15_A":   PN = "172"  !CDS_PN = "172";
"DQ15_B":   PN = "265"  !CDS_PN = "265";
"DQ16_A":   PN = "29"  !CDS_PN = "29";
"DQ16_B":   PN = "122"  !CDS_PN = "122";
"DQ17_A":   PN = "31"  !CDS_PN = "31";
"DQ17_B":   PN = "124"  !CDS_PN = "124";
"DQ18_A":   PN = "174"  !CDS_PN = "174";
"DQ18_B":   PN = "267"  !CDS_PN = "267";
"DQ19_A":   PN = "176"  !CDS_PN = "176";
"DQ19_B":   PN = "269"  !CDS_PN = "269";
"DQ20_A":   PN = "36"  !CDS_PN = "36";
"DQ20_B":   PN = "129"  !CDS_PN = "129";
"DQ21_A":   PN = "38"  !CDS_PN = "38";
"DQ21_B":   PN = "131"  !CDS_PN = "131";
"DQ22_A":   PN = "181"  !CDS_PN = "181";
"DQ22_B":   PN = "274"  !CDS_PN = "274";
"DQ23_A":   PN = "183"  !CDS_PN = "183";
"DQ23_B":   PN = "276"  !CDS_PN = "276";
"DQ24_A":   PN = "40"  !CDS_PN = "40";
"DQ24_B":   PN = "133"  !CDS_PN = "133";
"DQ25_A":   PN = "42"  !CDS_PN = "42";
"DQ25_B":   PN = "135"  !CDS_PN = "135";
"DQ26_A":   PN = "185"  !CDS_PN = "185";
"DQ26_B":   PN = "278"  !CDS_PN = "278";
"DQ27_A":   PN = "187"  !CDS_PN = "187";
"DQ27_B":   PN = "280"  !CDS_PN = "280";
"DQ28_A":   PN = "47"  !CDS_PN = "47";
"DQ28_B":   PN = "140"  !CDS_PN = "140";
"DQ29_A":   PN = "49"  !CDS_PN = "49";
"DQ29_B":   PN = "142"  !CDS_PN = "142";
"DQ30_A":   PN = "192"  !CDS_PN = "192";
"DQ30_B":   PN = "285"  !CDS_PN = "285";
"DQ31_A":   PN = "194"  !CDS_PN = "194";
"DQ31_B":   PN = "287"  !CDS_PN = "287";
"HAS":   PN = "148"  !CDS_PN = "148";
"HSCL":   PN = "4"  !CDS_PN = "4";
"HSDA":   PN = "5"  !CDS_PN = "5";
"LBD||RSP_A_N":   PN = "86"  !CDS_PN = "86";
"LBS||RSP_B_N":   PN = "87"  !CDS_PN = "87";
"PAR_A":   PN = "74"  !CDS_PN = "74";
"PAR_B":   PN = "227"  !CDS_PN = "227";
"PWR_GOOD||FAIL_N":   PN = "147"  !CDS_PN = "147";
"RESET_N":   PN = "207"  !CDS_PN = "207";
"RFU0":   PN = "2"  !CDS_PN = "2";
"RFU1":   PN = "144"  !CDS_PN = "144";
"RFU2":   PN = "149"  !CDS_PN = "149";
"RFU3":   PN = "150"  !CDS_PN = "150";
"RFU4":   PN = "220"  !CDS_PN = "220";
"RFU5":   PN = "231"  !CDS_PN = "231";
"RFU6":   PN = "232"  !CDS_PN = "232";
"VIN_MGMT":   PN = "3"  !CDS_PN = "3";
BODY = "Q_RES","I146": #LOCATION = "R772" !CDS_LOCATION = "R772" &SEC = "1" #&CDS_SEC = "1";
"A":   PN = "1"  !CDS_PN = "1";
"B":   PN = "2"  !CDS_PN = "2";
BODY = "SCONN288_DDR506112002KQ","I161": #LOCATION = "J30" !CDS_LOCATION = "J30" &SEC = "3" #&CDS_SEC = "3";
"G1":   PN = "G1"  !CDS_PN = "G1";
"G2":   PN = "G2"  !CDS_PN = "G2";
"G3":   PN = "G3"  !CDS_PN = "G3";
"VIN_BULK0":   PN = "1"  !CDS_PN = "1";
"VIN_BULK1":   PN = "145"  !CDS_PN = "145";
"VIN_BULK2":   PN = "146"  !CDS_PN = "146";
"VSS0":   PN = "6"  !CDS_PN = "6";
"VSS1":   PN = "8"  !CDS_PN = "8";
"VSS2":   PN = "10"  !CDS_PN = "10";
"VSS3":   PN = "13"  !CDS_PN = "13";
"VSS4":   PN = "15"  !CDS_PN = "15";
"VSS5":   PN = "17"  !CDS_PN = "17";
"VSS6":   PN = "19"  !CDS_PN = "19";
"VSS7":   PN = "21"  !CDS_PN = "21";
"VSS8":   PN = "24"  !CDS_PN = "24";
"VSS9":   PN = "26"  !CDS_PN = "26";
"VSS10":   PN = "28"  !CDS_PN = "28";
"VSS11":   PN = "30"  !CDS_PN = "30";
"VSS12":   PN = "32"  !CDS_PN = "32";
"VSS13":   PN = "35"  !CDS_PN = "35";
"VSS14":   PN = "37"  !CDS_PN = "37";
"VSS15":   PN = "39"  !CDS_PN = "39";
"VSS16":   PN = "41"  !CDS_PN = "41";
"VSS17":   PN = "43"  !CDS_PN = "43";
"VSS18":   PN = "46"  !CDS_PN = "46";
"VSS19":   PN = "48"  !CDS_PN = "48";
"VSS20":   PN = "50"  !CDS_PN = "50";
"VSS21":   PN = "52"  !CDS_PN = "52";
"VSS22":   PN = "54"  !CDS_PN = "54";
"VSS23":   PN = "57"  !CDS_PN = "57";
"VSS24":   PN = "59"  !CDS_PN = "59";
"VSS25":   PN = "61"  !CDS_PN = "61";
"VSS26":   PN = "63"  !CDS_PN = "63";
"VSS27":   PN = "65"  !CDS_PN = "65";
"VSS28":   PN = "67"  !CDS_PN = "67";
"VSS29":   PN = "69"  !CDS_PN = "69";
"VSS30":   PN = "71"  !CDS_PN = "71";
"VSS31":   PN = "73"  !CDS_PN = "73";
"VSS32":   PN = "75"  !CDS_PN = "75";
"VSS33":   PN = "77"  !CDS_PN = "77";
"VSS34":   PN = "79"  !CDS_PN = "79";
"VSS35":   PN = "81"  !CDS_PN = "81";
"VSS36":   PN = "83"  !CDS_PN = "83";
"VSS37":   PN = "85"  !CDS_PN = "85";
"VSS38":   PN = "88"  !CDS_PN = "88";
"VSS39":   PN = "90"  !CDS_PN = "90";
"VSS40":   PN = "92"  !CDS_PN = "92";
"VSS41":   PN = "95"  !CDS_PN = "95";
"VSS42":   PN = "97"  !CDS_PN = "97";
"VSS43":   PN = "99"  !CDS_PN = "99";
"VSS44":   PN = "101"  !CDS_PN = "101";
"VSS45":   PN = "103"  !CDS_PN = "103";
"VSS46":   PN = "106"  !CDS_PN = "106";
"VSS47":   PN = "108"  !CDS_PN = "108";
"VSS48":   PN = "110"  !CDS_PN = "110";
"VSS49":   PN = "112"  !CDS_PN = "112";
"VSS50":   PN = "114"  !CDS_PN = "114";
"VSS51":   PN = "117"  !CDS_PN = "117";
"VSS52":   PN = "119"  !CDS_PN = "119";
"VSS53":   PN = "121"  !CDS_PN = "121";
"VSS54":   PN = "123"  !CDS_PN = "123";
"VSS55":   PN = "125"  !CDS_PN = "125";
"VSS56":   PN = "128"  !CDS_PN = "128";
"VSS57":   PN = "130"  !CDS_PN = "130";
"VSS58":   PN = "132"  !CDS_PN = "132";
"VSS59":   PN = "134"  !CDS_PN = "134";
"VSS60":   PN = "136"  !CDS_PN = "136";
"VSS61":   PN = "139"  !CDS_PN = "139";
"VSS62":   PN = "141"  !CDS_PN = "141";
"VSS63":   PN = "143"  !CDS_PN = "143";
"VSS64":   PN = "151"  !CDS_PN = "151";
"VSS65":   PN = "153"  !CDS_PN = "153";
"VSS66":   PN = "155"  !CDS_PN = "155";
"VSS67":   PN = "158"  !CDS_PN = "158";
"VSS68":   PN = "160"  !CDS_PN = "160";
"VSS69":   PN = "162"  !CDS_PN = "162";
"VSS70":   PN = "164"  !CDS_PN = "164";
"VSS71":   PN = "166"  !CDS_PN = "166";
"VSS72":   PN = "169"  !CDS_PN = "169";
"VSS73":   PN = "171"  !CDS_PN = "171";
"VSS74":   PN = "173"  !CDS_PN = "173";
"VSS75":   PN = "175"  !CDS_PN = "175";
"VSS76":   PN = "177"  !CDS_PN = "177";
"VSS77":   PN = "180"  !CDS_PN = "180";
"VSS78":   PN = "182"  !CDS_PN = "182";
"VSS79":   PN = "184"  !CDS_PN = "184";
"VSS80":   PN = "186"  !CDS_PN = "186";
"VSS81":   PN = "188"  !CDS_PN = "188";
"VSS82":   PN = "191"  !CDS_PN = "191";
"VSS83":   PN = "193"  !CDS_PN = "193";
"VSS84":   PN = "195"  !CDS_PN = "195";
"VSS85":   PN = "197"  !CDS_PN = "197";
"VSS86":   PN = "199"  !CDS_PN = "199";
"VSS87":   PN = "202"  !CDS_PN = "202";
"VSS88":   PN = "204"  !CDS_PN = "204";
"VSS89":   PN = "206"  !CDS_PN = "206";
"VSS90":   PN = "208"  !CDS_PN = "208";
"VSS91":   PN = "210"  !CDS_PN = "210";
"VSS92":   PN = "212"  !CDS_PN = "212";
"VSS93":   PN = "214"  !CDS_PN = "214";
"VSS94":   PN = "216"  !CDS_PN = "216";
"VSS95":   PN = "219"  !CDS_PN = "219";
"VSS96":   PN = "222"  !CDS_PN = "222";
"VSS97":   PN = "224"  !CDS_PN = "224";
"VSS98":   PN = "226"  !CDS_PN = "226";
"VSS99":   PN = "228"  !CDS_PN = "228";
"VSS100":   PN = "230"  !CDS_PN = "230";
"VSS101":   PN = "233"  !CDS_PN = "233";
"VSS102":   PN = "235"  !CDS_PN = "235";
"VSS103":   PN = "237"  !CDS_PN = "237";
"VSS104":   PN = "240"  !CDS_PN = "240";
"VSS105":   PN = "242"  !CDS_PN = "242";
"VSS106":   PN = "244"  !CDS_PN = "244";
"VSS107":   PN = "246"  !CDS_PN = "246";
"VSS108":   PN = "248"  !CDS_PN = "248";
"VSS109":   PN = "251"  !CDS_PN = "251";
"VSS110":   PN = "253"  !CDS_PN = "253";
"VSS111":   PN = "255"  !CDS_PN = "255";
"VSS112":   PN = "257"  !CDS_PN = "257";
"VSS113":   PN = "259"  !CDS_PN = "259";
"VSS114":   PN = "262"  !CDS_PN = "262";
"VSS115":   PN = "264"  !CDS_PN = "264";
"VSS116":   PN = "266"  !CDS_PN = "266";
"VSS117":   PN = "268"  !CDS_PN = "268";
"VSS118":   PN = "270"  !CDS_PN = "270";
"VSS119":   PN = "273"  !CDS_PN = "273";
"VSS120":   PN = "275"  !CDS_PN = "275";
"VSS121":   PN = "277"  !CDS_PN = "277";
"VSS122":   PN = "279"  !CDS_PN = "279";
"VSS123":   PN = "281"  !CDS_PN = "281";
"VSS124":   PN = "284"  !CDS_PN = "284";
"VSS125":   PN = "286"  !CDS_PN = "286";
"VSS126":   PN = "288"  !CDS_PN = "288";
BODY = "Q_CAP","I185": #LOCATION = "C148" !CDS_LOCATION = "C148" &SEC = "1" #&CDS_SEC = "1";
"A":   PN = "1"  !CDS_PN = "1";
"B":   PN = "2"  !CDS_PN = "2";
BODY = "Q_RES","I188": #LOCATION = "R306" !CDS_LOCATION = "R306" &SEC = "1" #&CDS_SEC = "1";
"A":   PN = "1"  !CDS_PN = "1";
"B":   PN = "2"  !CDS_PN = "2";
BODY = "Q_RES","I190": #LOCATION = "R106" !CDS_LOCATION = "R106" &SEC = "1" #&CDS_SEC = "1";
"A":   PN = "1"  !CDS_PN = "1";
"B":   PN = "2"  !CDS_PN = "2";
BODY = "SCONN288_DDR506112002KQ","I236": #LOCATION = "J30" !CDS_LOCATION = "J30" &SEC = "2" #&CDS_SEC = "2";
"DQS0_A_C":   PN = "12"  !CDS_PN = "12";
"DQS0_A_T":   PN = "11"  !CDS_PN = "11";
"DQS0_B_C":   PN = "105"  !CDS_PN = "105";
"DQS0_B_T":   PN = "104"  !CDS_PN = "104";
"DQS1_A_C":   PN = "23"  !CDS_PN = "23";
"DQS1_A_T":   PN = "22"  !CDS_PN = "22";
"DQS1_B_C":   PN = "116"  !CDS_PN = "116";
"DQS1_B_T":   PN = "115"  !CDS_PN = "115";
"DQS2_A_C":   PN = "34"  !CDS_PN = "34";
"DQS2_A_T":   PN = "33"  !CDS_PN = "33";
"DQS2_B_C":   PN = "127"  !CDS_PN = "127";
"DQS2_B_T":   PN = "126"  !CDS_PN = "126";
"DQS3_A_C":   PN = "45"  !CDS_PN = "45";
"DQS3_A_T":   PN = "44"  !CDS_PN = "44";
"DQS3_B_C":   PN = "138"  !CDS_PN = "138";
"DQS3_B_T":   PN = "137"  !CDS_PN = "137";
"DQS4_A_C":   PN = "56"  !CDS_PN = "56";
"DQS4_A_T":   PN = "55"  !CDS_PN = "55";
"DQS4_B_C":   PN = "238"  !CDS_PN = "238";
"DQS4_B_T":   PN = "239"  !CDS_PN = "239";
"DQS5_A_C||TDQS5_A_C||DQS5_A_T||TDQS5_A_T":   PN = "156"  !CDS_PN = "156";
"DQS5_A_T||TDQS5_A_T":   PN = "157"  !CDS_PN = "157";
"DQS5_B_C||TDQS5_B_C":   PN = "249"  !CDS_PN = "249";
"DQS5_B_T||TDQS5_B_T":   PN = "250"  !CDS_PN = "250";
"DQS6_A_C||TDQS6_A_C||DQS6_A_T||TDQS6_A_T":   PN = "167"  !CDS_PN = "167";
"DQS6_A_T||TDQS6_A_T":   PN = "168"  !CDS_PN = "168";
"DQS6_B_C||TDQS6_B_C":   PN = "260"  !CDS_PN = "260";
"DQS6_B_T||TDQS6_B_T":   PN = "261"  !CDS_PN = "261";
"DQS7_A_C||TDQS7_A_C":   PN = "178"  !CDS_PN = "178";
"DQS7_A_T||TDQS7_A_T":   PN = "179"  !CDS_PN = "179";
"DQS7_B_C||TDQS7_B_C":   PN = "271"  !CDS_PN = "271";
"DQS7_B_T||TDQS7_B_T":   PN = "272"  !CDS_PN = "272";
"DQS8_A_C||TDQS8_A_C":   PN = "189"  !CDS_PN = "189";
"DQS8_A_T||TDQS8_A_T":   PN = "190"  !CDS_PN = "190";
"DQS8_B_C||TDQS8_B_C":   PN = "282"  !CDS_PN = "282";
"DQS8_B_T||TDQS8_B_T":   PN = "283"  !CDS_PN = "283";
"DQS9_A_C||TDQS9_A_C":   PN = "200"  !CDS_PN = "200";
"DQS9_A_T||TDQS9_A_T":   PN = "201"  !CDS_PN = "201";
"DQS9_B_C||TDQS9_B_C":   PN = "94"  !CDS_PN = "94";
"DQS9_B_T||TDQS9_B_T||DBI4_B_N":   PN = "93"  !CDS_PN = "93";
BODY = "Q_CAP","I238": #LOCATION = "C181" !CDS_LOCATION = "C181" &SEC = "1" #&CDS_SEC = "1";
"A":   PN = "1"  !CDS_PN = "1";
"B":   PN = "2"  !CDS_PN = "2";
BODY = "Q_CAP","I239": #LOCATION = "C182" !CDS_LOCATION = "C182" &SEC = "1" #&CDS_SEC = "1";
"A":   PN = "1"  !CDS_PN = "1";
"B":   PN = "2"  !CDS_PN = "2";
BODY = "Q_RES","I242": #LOCATION = "R1583" !CDS_LOCATION = "R1583" &SEC = "1" #&CDS_SEC = "1";
"A":   PN = "1"  !CDS_PN = "1";
"B":   PN = "2"  !CDS_PN = "2";
BODY = "Q_RES","I243": #LOCATION = "R1699" !CDS_LOCATION = "R1699" &SEC = "1" #&CDS_SEC = "1";
"A":   PN = "1"  !CDS_PN = "1";
"B":   PN = "2"  !CDS_PN = "2";
DRAWING = "@t6g_mb_lib.t6g(sch_1):page101";
BODY = "SCONN288_DDR506112002KQ","I52": #LOCATION = "J32" !CDS_LOCATION = "J32" &SEC = "1" #&CDS_SEC = "1";
"ALERT_N":   PN = "62"  !CDS_PN = "62";
"CA0_A":   PN = "66"  !CDS_PN = "66";
"CA0_B":   PN = "76"  !CDS_PN = "76";
"CA1_A":   PN = "211"  !CDS_PN = "211";
"CA1_B":   PN = "221"  !CDS_PN = "221";
"CA2_A":   PN = "68"  !CDS_PN = "68";
"CA2_B":   PN = "78"  !CDS_PN = "78";
"CA3_A":   PN = "213"  !CDS_PN = "213";
"CA3_B":   PN = "223"  !CDS_PN = "223";
"CA4_A":   PN = "70"  !CDS_PN = "70";
"CA4_B":   PN = "80"  !CDS_PN = "80";
"CA5_A":   PN = "215"  !CDS_PN = "215";
"CA5_B":   PN = "225"  !CDS_PN = "225";
"CA6_A":   PN = "72"  !CDS_PN = "72";
"CA6_B":   PN = "82"  !CDS_PN = "82";
"CB0_A":   PN = "51"  !CDS_PN = "51";
"CB0_B":   PN = "96"  !CDS_PN = "96";
"CB1_A":   PN = "53"  !CDS_PN = "53";
"CB1_B":   PN = "98"  !CDS_PN = "98";
"CB2_A":   PN = "196"  !CDS_PN = "196";
"CB2_B":   PN = "241"  !CDS_PN = "241";
"CB3_A":   PN = "198"  !CDS_PN = "198";
"CB3_B":   PN = "243"  !CDS_PN = "243";
"CB4_A":   PN = "58"  !CDS_PN = "58";
"CB4_B":   PN = "89"  !CDS_PN = "89";
"CB5_A":   PN = "60"  !CDS_PN = "60";
"CB5_B":   PN = "91"  !CDS_PN = "91";
"CB6_A":   PN = "203"  !CDS_PN = "203";
"CB6_B":   PN = "234"  !CDS_PN = "234";
"CB7_A":   PN = "205"  !CDS_PN = "205";
"CB7_B":   PN = "236"  !CDS_PN = "236";
"CK_C":   PN = "218"  !CDS_PN = "218";
"CK_T":   PN = "217"  !CDS_PN = "217";
"CS0_A_N":   PN = "64"  !CDS_PN = "64";
"CS0_B_N":   PN = "84"  !CDS_PN = "84";
"CS1_A_N":   PN = "209"  !CDS_PN = "209";
"CS1_B_N":   PN = "229"  !CDS_PN = "229";
"DQ0_A":   PN = "7"  !CDS_PN = "7";
"DQ0_B":   PN = "100"  !CDS_PN = "100";
"DQ1_A":   PN = "9"  !CDS_PN = "9";
"DQ1_B":   PN = "102"  !CDS_PN = "102";
"DQ2_A":   PN = "152"  !CDS_PN = "152";
"DQ2_B":   PN = "245"  !CDS_PN = "245";
"DQ3_A":   PN = "154"  !CDS_PN = "154";
"DQ3_B":   PN = "247"  !CDS_PN = "247";
"DQ4_A":   PN = "14"  !CDS_PN = "14";
"DQ4_B":   PN = "107"  !CDS_PN = "107";
"DQ5_A":   PN = "16"  !CDS_PN = "16";
"DQ5_B":   PN = "109"  !CDS_PN = "109";
"DQ6_A":   PN = "159"  !CDS_PN = "159";
"DQ6_B":   PN = "252"  !CDS_PN = "252";
"DQ7_A":   PN = "161"  !CDS_PN = "161";
"DQ7_B":   PN = "254"  !CDS_PN = "254";
"DQ8_A":   PN = "18"  !CDS_PN = "18";
"DQ8_B":   PN = "111"  !CDS_PN = "111";
"DQ9_A":   PN = "20"  !CDS_PN = "20";
"DQ9_B":   PN = "113"  !CDS_PN = "113";
"DQ10_A":   PN = "163"  !CDS_PN = "163";
"DQ10_B":   PN = "256"  !CDS_PN = "256";
"DQ11_A":   PN = "165"  !CDS_PN = "165";
"DQ11_B":   PN = "258"  !CDS_PN = "258";
"DQ12_A":   PN = "25"  !CDS_PN = "25";
"DQ12_B":   PN = "118"  !CDS_PN = "118";
"DQ13_A":   PN = "27"  !CDS_PN = "27";
"DQ13_B":   PN = "120"  !CDS_PN = "120";
"DQ14_A":   PN = "170"  !CDS_PN = "170";
"DQ14_B":   PN = "263"  !CDS_PN = "263";
"DQ15_A":   PN = "172"  !CDS_PN = "172";
"DQ15_B":   PN = "265"  !CDS_PN = "265";
"DQ16_A":   PN = "29"  !CDS_PN = "29";
"DQ16_B":   PN = "122"  !CDS_PN = "122";
"DQ17_A":   PN = "31"  !CDS_PN = "31";
"DQ17_B":   PN = "124"  !CDS_PN = "124";
"DQ18_A":   PN = "174"  !CDS_PN = "174";
"DQ18_B":   PN = "267"  !CDS_PN = "267";
"DQ19_A":   PN = "176"  !CDS_PN = "176";
"DQ19_B":   PN = "269"  !CDS_PN = "269";
"DQ20_A":   PN = "36"  !CDS_PN = "36";
"DQ20_B":   PN = "129"  !CDS_PN = "129";
"DQ21_A":   PN = "38"  !CDS_PN = "38";
"DQ21_B":   PN = "131"  !CDS_PN = "131";
"DQ22_A":   PN = "181"  !CDS_PN = "181";
"DQ22_B":   PN = "274"  !CDS_PN = "274";
"DQ23_A":   PN = "183"  !CDS_PN = "183";
"DQ23_B":   PN = "276"  !CDS_PN = "276";
"DQ24_A":   PN = "40"  !CDS_PN = "40";
"DQ24_B":   PN = "133"  !CDS_PN = "133";
"DQ25_A":   PN = "42"  !CDS_PN = "42";
"DQ25_B":   PN = "135"  !CDS_PN = "135";
"DQ26_A":   PN = "185"  !CDS_PN = "185";
"DQ26_B":   PN = "278"  !CDS_PN = "278";
"DQ27_A":   PN = "187"  !CDS_PN = "187";
"DQ27_B":   PN = "280"  !CDS_PN = "280";
"DQ28_A":   PN = "47"  !CDS_PN = "47";
"DQ28_B":   PN = "140"  !CDS_PN = "140";
"DQ29_A":   PN = "49"  !CDS_PN = "49";
"DQ29_B":   PN = "142"  !CDS_PN = "142";
"DQ30_A":   PN = "192"  !CDS_PN = "192";
"DQ30_B":   PN = "285"  !CDS_PN = "285";
"DQ31_A":   PN = "194"  !CDS_PN = "194";
"DQ31_B":   PN = "287"  !CDS_PN = "287";
"HAS":   PN = "148"  !CDS_PN = "148";
"HSCL":   PN = "4"  !CDS_PN = "4";
"HSDA":   PN = "5"  !CDS_PN = "5";
"LBD||RSP_A_N":   PN = "86"  !CDS_PN = "86";
"LBS||RSP_B_N":   PN = "87"  !CDS_PN = "87";
"PAR_A":   PN = "74"  !CDS_PN = "74";
"PAR_B":   PN = "227"  !CDS_PN = "227";
"PWR_GOOD||FAIL_N":   PN = "147"  !CDS_PN = "147";
"RESET_N":   PN = "207"  !CDS_PN = "207";
"RFU0":   PN = "2"  !CDS_PN = "2";
"RFU1":   PN = "144"  !CDS_PN = "144";
"RFU2":   PN = "149"  !CDS_PN = "149";
"RFU3":   PN = "150"  !CDS_PN = "150";
"RFU4":   PN = "220"  !CDS_PN = "220";
"RFU5":   PN = "231"  !CDS_PN = "231";
"RFU6":   PN = "232"  !CDS_PN = "232";
"VIN_MGMT":   PN = "3"  !CDS_PN = "3";
BODY = "Q_RES","I127": #LOCATION = "R6" !CDS_LOCATION = "R6" #SEC = "1" !CDS_SEC = "1";
"A":   PN = "1"  !CDS_PN = "1";
"B":   PN = "2"  !CDS_PN = "2";
BODY = "SCONN288_DDR506112002KQ","I175": #LOCATION = "J32" !CDS_LOCATION = "J32" &SEC = "3" #&CDS_SEC = "3";
"G1":   PN = "G1"  !CDS_PN = "G1";
"G2":   PN = "G2"  !CDS_PN = "G2";
"G3":   PN = "G3"  !CDS_PN = "G3";
"VIN_BULK0":   PN = "1"  !CDS_PN = "1";
"VIN_BULK1":   PN = "145"  !CDS_PN = "145";
"VIN_BULK2":   PN = "146"  !CDS_PN = "146";
"VSS0":   PN = "6"  !CDS_PN = "6";
"VSS1":   PN = "8"  !CDS_PN = "8";
"VSS2":   PN = "10"  !CDS_PN = "10";
"VSS3":   PN = "13"  !CDS_PN = "13";
"VSS4":   PN = "15"  !CDS_PN = "15";
"VSS5":   PN = "17"  !CDS_PN = "17";
"VSS6":   PN = "19"  !CDS_PN = "19";
"VSS7":   PN = "21"  !CDS_PN = "21";
"VSS8":   PN = "24"  !CDS_PN = "24";
"VSS9":   PN = "26"  !CDS_PN = "26";
"VSS10":   PN = "28"  !CDS_PN = "28";
"VSS11":   PN = "30"  !CDS_PN = "30";
"VSS12":   PN = "32"  !CDS_PN = "32";
"VSS13":   PN = "35"  !CDS_PN = "35";
"VSS14":   PN = "37"  !CDS_PN = "37";
"VSS15":   PN = "39"  !CDS_PN = "39";
"VSS16":   PN = "41"  !CDS_PN = "41";
"VSS17":   PN = "43"  !CDS_PN = "43";
"VSS18":   PN = "46"  !CDS_PN = "46";
"VSS19":   PN = "48"  !CDS_PN = "48";
"VSS20":   PN = "50"  !CDS_PN = "50";
"VSS21":   PN = "52"  !CDS_PN = "52";
"VSS22":   PN = "54"  !CDS_PN = "54";
"VSS23":   PN = "57"  !CDS_PN = "57";
"VSS24":   PN = "59"  !CDS_PN = "59";
"VSS25":   PN = "61"  !CDS_PN = "61";
"VSS26":   PN = "63"  !CDS_PN = "63";
"VSS27":   PN = "65"  !CDS_PN = "65";
"VSS28":   PN = "67"  !CDS_PN = "67";
"VSS29":   PN = "69"  !CDS_PN = "69";
"VSS30":   PN = "71"  !CDS_PN = "71";
"VSS31":   PN = "73"  !CDS_PN = "73";
"VSS32":   PN = "75"  !CDS_PN = "75";
"VSS33":   PN = "77"  !CDS_PN = "77";
"VSS34":   PN = "79"  !CDS_PN = "79";
"VSS35":   PN = "81"  !CDS_PN = "81";
"VSS36":   PN = "83"  !CDS_PN = "83";
"VSS37":   PN = "85"  !CDS_PN = "85";
"VSS38":   PN = "88"  !CDS_PN = "88";
"VSS39":   PN = "90"  !CDS_PN = "90";
"VSS40":   PN = "92"  !CDS_PN = "92";
"VSS41":   PN = "95"  !CDS_PN = "95";
"VSS42":   PN = "97"  !CDS_PN = "97";
"VSS43":   PN = "99"  !CDS_PN = "99";
"VSS44":   PN = "101"  !CDS_PN = "101";
"VSS45":   PN = "103"  !CDS_PN = "103";
"VSS46":   PN = "106"  !CDS_PN = "106";
"VSS47":   PN = "108"  !CDS_PN = "108";
"VSS48":   PN = "110"  !CDS_PN = "110";
"VSS49":   PN = "112"  !CDS_PN = "112";
"VSS50":   PN = "114"  !CDS_PN = "114";
"VSS51":   PN = "117"  !CDS_PN = "117";
"VSS52":   PN = "119"  !CDS_PN = "119";
"VSS53":   PN = "121"  !CDS_PN = "121";
"VSS54":   PN = "123"  !CDS_PN = "123";
"VSS55":   PN = "125"  !CDS_PN = "125";
"VSS56":   PN = "128"  !CDS_PN = "128";
"VSS57":   PN = "130"  !CDS_PN = "130";
"VSS58":   PN = "132"  !CDS_PN = "132";
"VSS59":   PN = "134"  !CDS_PN = "134";
"VSS60":   PN = "136"  !CDS_PN = "136";
"VSS61":   PN = "139"  !CDS_PN = "139";
"VSS62":   PN = "141"  !CDS_PN = "141";
"VSS63":   PN = "143"  !CDS_PN = "143";
"VSS64":   PN = "151"  !CDS_PN = "151";
"VSS65":   PN = "153"  !CDS_PN = "153";
"VSS66":   PN = "155"  !CDS_PN = "155";
"VSS67":   PN = "158"  !CDS_PN = "158";
"VSS68":   PN = "160"  !CDS_PN = "160";
"VSS69":   PN = "162"  !CDS_PN = "162";
"VSS70":   PN = "164"  !CDS_PN = "164";
"VSS71":   PN = "166"  !CDS_PN = "166";
"VSS72":   PN = "169"  !CDS_PN = "169";
"VSS73":   PN = "171"  !CDS_PN = "171";
"VSS74":   PN = "173"  !CDS_PN = "173";
"VSS75":   PN = "175"  !CDS_PN = "175";
"VSS76":   PN = "177"  !CDS_PN = "177";
"VSS77":   PN = "180"  !CDS_PN = "180";
"VSS78":   PN = "182"  !CDS_PN = "182";
"VSS79":   PN = "184"  !CDS_PN = "184";
"VSS80":   PN = "186"  !CDS_PN = "186";
"VSS81":   PN = "188"  !CDS_PN = "188";
"VSS82":   PN = "191"  !CDS_PN = "191";
"VSS83":   PN = "193"  !CDS_PN = "193";
"VSS84":   PN = "195"  !CDS_PN = "195";
"VSS85":   PN = "197"  !CDS_PN = "197";
"VSS86":   PN = "199"  !CDS_PN = "199";
"VSS87":   PN = "202"  !CDS_PN = "202";
"VSS88":   PN = "204"  !CDS_PN = "204";
"VSS89":   PN = "206"  !CDS_PN = "206";
"VSS90":   PN = "208"  !CDS_PN = "208";
"VSS91":   PN = "210"  !CDS_PN = "210";
"VSS92":   PN = "212"  !CDS_PN = "212";
"VSS93":   PN = "214"  !CDS_PN = "214";
"VSS94":   PN = "216"  !CDS_PN = "216";
"VSS95":   PN = "219"  !CDS_PN = "219";
"VSS96":   PN = "222"  !CDS_PN = "222";
"VSS97":   PN = "224"  !CDS_PN = "224";
"VSS98":   PN = "226"  !CDS_PN = "226";
"VSS99":   PN = "228"  !CDS_PN = "228";
"VSS100":   PN = "230"  !CDS_PN = "230";
"VSS101":   PN = "233"  !CDS_PN = "233";
"VSS102":   PN = "235"  !CDS_PN = "235";
"VSS103":   PN = "237"  !CDS_PN = "237";
"VSS104":   PN = "240"  !CDS_PN = "240";
"VSS105":   PN = "242"  !CDS_PN = "242";
"VSS106":   PN = "244"  !CDS_PN = "244";
"VSS107":   PN = "246"  !CDS_PN = "246";
"VSS108":   PN = "248"  !CDS_PN = "248";
"VSS109":   PN = "251"  !CDS_PN = "251";
"VSS110":   PN = "253"  !CDS_PN = "253";
"VSS111":   PN = "255"  !CDS_PN = "255";
"VSS112":   PN = "257"  !CDS_PN = "257";
"VSS113":   PN = "259"  !CDS_PN = "259";
"VSS114":   PN = "262"  !CDS_PN = "262";
"VSS115":   PN = "264"  !CDS_PN = "264";
"VSS116":   PN = "266"  !CDS_PN = "266";
"VSS117":   PN = "268"  !CDS_PN = "268";
"VSS118":   PN = "270"  !CDS_PN = "270";
"VSS119":   PN = "273"  !CDS_PN = "273";
"VSS120":   PN = "275"  !CDS_PN = "275";
"VSS121":   PN = "277"  !CDS_PN = "277";
"VSS122":   PN = "279"  !CDS_PN = "279";
"VSS123":   PN = "281"  !CDS_PN = "281";
"VSS124":   PN = "284"  !CDS_PN = "284";
"VSS125":   PN = "286"  !CDS_PN = "286";
"VSS126":   PN = "288"  !CDS_PN = "288";
BODY = "Q_CAP","I185": #LOCATION = "C152" !CDS_LOCATION = "C152" &SEC = "1" #&CDS_SEC = "1";
"A":   PN = "1"  !CDS_PN = "1";
"B":   PN = "2"  !CDS_PN = "2";
BODY = "Q_RES","I188": #LOCATION = "R307" !CDS_LOCATION = "R307" &SEC = "1" #&CDS_SEC = "1";
"A":   PN = "1"  !CDS_PN = "1";
"B":   PN = "2"  !CDS_PN = "2";
BODY = "Q_RES","I190": #LOCATION = "R107" !CDS_LOCATION = "R107" &SEC = "1" #&CDS_SEC = "1";
"A":   PN = "1"  !CDS_PN = "1";
"B":   PN = "2"  !CDS_PN = "2";
BODY = "SCONN288_DDR506112002KQ","I236": #LOCATION = "J32" !CDS_LOCATION = "J32" &SEC = "2" #&CDS_SEC = "2";
"DQS0_A_C":   PN = "12"  !CDS_PN = "12";
"DQS0_A_T":   PN = "11"  !CDS_PN = "11";
"DQS0_B_C":   PN = "105"  !CDS_PN = "105";
"DQS0_B_T":   PN = "104"  !CDS_PN = "104";
"DQS1_A_C":   PN = "23"  !CDS_PN = "23";
"DQS1_A_T":   PN = "22"  !CDS_PN = "22";
"DQS1_B_C":   PN = "116"  !CDS_PN = "116";
"DQS1_B_T":   PN = "115"  !CDS_PN = "115";
"DQS2_A_C":   PN = "34"  !CDS_PN = "34";
"DQS2_A_T":   PN = "33"  !CDS_PN = "33";
"DQS2_B_C":   PN = "127"  !CDS_PN = "127";
"DQS2_B_T":   PN = "126"  !CDS_PN = "126";
"DQS3_A_C":   PN = "45"  !CDS_PN = "45";
"DQS3_A_T":   PN = "44"  !CDS_PN = "44";
"DQS3_B_C":   PN = "138"  !CDS_PN = "138";
"DQS3_B_T":   PN = "137"  !CDS_PN = "137";
"DQS4_A_C":   PN = "56"  !CDS_PN = "56";
"DQS4_A_T":   PN = "55"  !CDS_PN = "55";
"DQS4_B_C":   PN = "238"  !CDS_PN = "238";
"DQS4_B_T":   PN = "239"  !CDS_PN = "239";
"DQS5_A_C||TDQS5_A_C||DQS5_A_T||TDQS5_A_T":   PN = "156"  !CDS_PN = "156";
"DQS5_A_T||TDQS5_A_T":   PN = "157"  !CDS_PN = "157";
"DQS5_B_C||TDQS5_B_C":   PN = "249"  !CDS_PN = "249";
"DQS5_B_T||TDQS5_B_T":   PN = "250"  !CDS_PN = "250";
"DQS6_A_C||TDQS6_A_C||DQS6_A_T||TDQS6_A_T":   PN = "167"  !CDS_PN = "167";
"DQS6_A_T||TDQS6_A_T":   PN = "168"  !CDS_PN = "168";
"DQS6_B_C||TDQS6_B_C":   PN = "260"  !CDS_PN = "260";
"DQS6_B_T||TDQS6_B_T":   PN = "261"  !CDS_PN = "261";
"DQS7_A_C||TDQS7_A_C":   PN = "178"  !CDS_PN = "178";
"DQS7_A_T||TDQS7_A_T":   PN = "179"  !CDS_PN = "179";
"DQS7_B_C||TDQS7_B_C":   PN = "271"  !CDS_PN = "271";
"DQS7_B_T||TDQS7_B_T":   PN = "272"  !CDS_PN = "272";
"DQS8_A_C||TDQS8_A_C":   PN = "189"  !CDS_PN = "189";
"DQS8_A_T||TDQS8_A_T":   PN = "190"  !CDS_PN = "190";
"DQS8_B_C||TDQS8_B_C":   PN = "282"  !CDS_PN = "282";
"DQS8_B_T||TDQS8_B_T":   PN = "283"  !CDS_PN = "283";
"DQS9_A_C||TDQS9_A_C":   PN = "200"  !CDS_PN = "200";
"DQS9_A_T||TDQS9_A_T":   PN = "201"  !CDS_PN = "201";
"DQS9_B_C||TDQS9_B_C":   PN = "94"  !CDS_PN = "94";
"DQS9_B_T||TDQS9_B_T||DBI4_B_N":   PN = "93"  !CDS_PN = "93";
BODY = "Q_CAP","I238": #LOCATION = "C183" !CDS_LOCATION = "C183" &SEC = "1" #&CDS_SEC = "1";
"A":   PN = "1"  !CDS_PN = "1";
"B":   PN = "2"  !CDS_PN = "2";
BODY = "Q_CAP","I239": #LOCATION = "C509" !CDS_LOCATION = "C509" &SEC = "1" #&CDS_SEC = "1";
"A":   PN = "1"  !CDS_PN = "1";
"B":   PN = "2"  !CDS_PN = "2";
BODY = "Q_RES","I242": #LOCATION = "R1584" !CDS_LOCATION = "R1584" &SEC = "1" #&CDS_SEC = "1";
"A":   PN = "1"  !CDS_PN = "1";
"B":   PN = "2"  !CDS_PN = "2";
BODY = "Q_RES","I243": #LOCATION = "R1701" !CDS_LOCATION = "R1701" &SEC = "1" #&CDS_SEC = "1";
"A":   PN = "1"  !CDS_PN = "1";
"B":   PN = "2"  !CDS_PN = "2";
DRAWING = "@t6g_mb_lib.t6g(sch_1):page102";
BODY = "SCONN288_DDR506112002KQ","I22": #LOCATION = "J33" !CDS_LOCATION = "J33" &SEC = "1" #&CDS_SEC = "1";
"ALERT_N":   PN = "62"  !CDS_PN = "62";
"CA0_A":   PN = "66"  !CDS_PN = "66";
"CA0_B":   PN = "76"  !CDS_PN = "76";
"CA1_A":   PN = "211"  !CDS_PN = "211";
"CA1_B":   PN = "221"  !CDS_PN = "221";
"CA2_A":   PN = "68"  !CDS_PN = "68";
"CA2_B":   PN = "78"  !CDS_PN = "78";
"CA3_A":   PN = "213"  !CDS_PN = "213";
"CA3_B":   PN = "223"  !CDS_PN = "223";
"CA4_A":   PN = "70"  !CDS_PN = "70";
"CA4_B":   PN = "80"  !CDS_PN = "80";
"CA5_A":   PN = "215"  !CDS_PN = "215";
"CA5_B":   PN = "225"  !CDS_PN = "225";
"CA6_A":   PN = "72"  !CDS_PN = "72";
"CA6_B":   PN = "82"  !CDS_PN = "82";
"CB0_A":   PN = "51"  !CDS_PN = "51";
"CB0_B":   PN = "96"  !CDS_PN = "96";
"CB1_A":   PN = "53"  !CDS_PN = "53";
"CB1_B":   PN = "98"  !CDS_PN = "98";
"CB2_A":   PN = "196"  !CDS_PN = "196";
"CB2_B":   PN = "241"  !CDS_PN = "241";
"CB3_A":   PN = "198"  !CDS_PN = "198";
"CB3_B":   PN = "243"  !CDS_PN = "243";
"CB4_A":   PN = "58"  !CDS_PN = "58";
"CB4_B":   PN = "89"  !CDS_PN = "89";
"CB5_A":   PN = "60"  !CDS_PN = "60";
"CB5_B":   PN = "91"  !CDS_PN = "91";
"CB6_A":   PN = "203"  !CDS_PN = "203";
"CB6_B":   PN = "234"  !CDS_PN = "234";
"CB7_A":   PN = "205"  !CDS_PN = "205";
"CB7_B":   PN = "236"  !CDS_PN = "236";
"CK_C":   PN = "218"  !CDS_PN = "218";
"CK_T":   PN = "217"  !CDS_PN = "217";
"CS0_A_N":   PN = "64"  !CDS_PN = "64";
"CS0_B_N":   PN = "84"  !CDS_PN = "84";
"CS1_A_N":   PN = "209"  !CDS_PN = "209";
"CS1_B_N":   PN = "229"  !CDS_PN = "229";
"DQ0_A":   PN = "7"  !CDS_PN = "7";
"DQ0_B":   PN = "100"  !CDS_PN = "100";
"DQ1_A":   PN = "9"  !CDS_PN = "9";
"DQ1_B":   PN = "102"  !CDS_PN = "102";
"DQ2_A":   PN = "152"  !CDS_PN = "152";
"DQ2_B":   PN = "245"  !CDS_PN = "245";
"DQ3_A":   PN = "154"  !CDS_PN = "154";
"DQ3_B":   PN = "247"  !CDS_PN = "247";
"DQ4_A":   PN = "14"  !CDS_PN = "14";
"DQ4_B":   PN = "107"  !CDS_PN = "107";
"DQ5_A":   PN = "16"  !CDS_PN = "16";
"DQ5_B":   PN = "109"  !CDS_PN = "109";
"DQ6_A":   PN = "159"  !CDS_PN = "159";
"DQ6_B":   PN = "252"  !CDS_PN = "252";
"DQ7_A":   PN = "161"  !CDS_PN = "161";
"DQ7_B":   PN = "254"  !CDS_PN = "254";
"DQ8_A":   PN = "18"  !CDS_PN = "18";
"DQ8_B":   PN = "111"  !CDS_PN = "111";
"DQ9_A":   PN = "20"  !CDS_PN = "20";
"DQ9_B":   PN = "113"  !CDS_PN = "113";
"DQ10_A":   PN = "163"  !CDS_PN = "163";
"DQ10_B":   PN = "256"  !CDS_PN = "256";
"DQ11_A":   PN = "165"  !CDS_PN = "165";
"DQ11_B":   PN = "258"  !CDS_PN = "258";
"DQ12_A":   PN = "25"  !CDS_PN = "25";
"DQ12_B":   PN = "118"  !CDS_PN = "118";
"DQ13_A":   PN = "27"  !CDS_PN = "27";
"DQ13_B":   PN = "120"  !CDS_PN = "120";
"DQ14_A":   PN = "170"  !CDS_PN = "170";
"DQ14_B":   PN = "263"  !CDS_PN = "263";
"DQ15_A":   PN = "172"  !CDS_PN = "172";
"DQ15_B":   PN = "265"  !CDS_PN = "265";
"DQ16_A":   PN = "29"  !CDS_PN = "29";
"DQ16_B":   PN = "122"  !CDS_PN = "122";
"DQ17_A":   PN = "31"  !CDS_PN = "31";
"DQ17_B":   PN = "124"  !CDS_PN = "124";
"DQ18_A":   PN = "174"  !CDS_PN = "174";
"DQ18_B":   PN = "267"  !CDS_PN = "267";
"DQ19_A":   PN = "176"  !CDS_PN = "176";
"DQ19_B":   PN = "269"  !CDS_PN = "269";
"DQ20_A":   PN = "36"  !CDS_PN = "36";
"DQ20_B":   PN = "129"  !CDS_PN = "129";
"DQ21_A":   PN = "38"  !CDS_PN = "38";
"DQ21_B":   PN = "131"  !CDS_PN = "131";
"DQ22_A":   PN = "181"  !CDS_PN = "181";
"DQ22_B":   PN = "274"  !CDS_PN = "274";
"DQ23_A":   PN = "183"  !CDS_PN = "183";
"DQ23_B":   PN = "276"  !CDS_PN = "276";
"DQ24_A":   PN = "40"  !CDS_PN = "40";
"DQ24_B":   PN = "133"  !CDS_PN = "133";
"DQ25_A":   PN = "42"  !CDS_PN = "42";
"DQ25_B":   PN = "135"  !CDS_PN = "135";
"DQ26_A":   PN = "185"  !CDS_PN = "185";
"DQ26_B":   PN = "278"  !CDS_PN = "278";
"DQ27_A":   PN = "187"  !CDS_PN = "187";
"DQ27_B":   PN = "280"  !CDS_PN = "280";
"DQ28_A":   PN = "47"  !CDS_PN = "47";
"DQ28_B":   PN = "140"  !CDS_PN = "140";
"DQ29_A":   PN = "49"  !CDS_PN = "49";
"DQ29_B":   PN = "142"  !CDS_PN = "142";
"DQ30_A":   PN = "192"  !CDS_PN = "192";
"DQ30_B":   PN = "285"  !CDS_PN = "285";
"DQ31_A":   PN = "194"  !CDS_PN = "194";
"DQ31_B":   PN = "287"  !CDS_PN = "287";
"HAS":   PN = "148"  !CDS_PN = "148";
"HSCL":   PN = "4"  !CDS_PN = "4";
"HSDA":   PN = "5"  !CDS_PN = "5";
"LBD||RSP_A_N":   PN = "86"  !CDS_PN = "86";
"LBS||RSP_B_N":   PN = "87"  !CDS_PN = "87";
"PAR_A":   PN = "74"  !CDS_PN = "74";
"PAR_B":   PN = "227"  !CDS_PN = "227";
"PWR_GOOD||FAIL_N":   PN = "147"  !CDS_PN = "147";
"RESET_N":   PN = "207"  !CDS_PN = "207";
"RFU0":   PN = "2"  !CDS_PN = "2";
"RFU1":   PN = "144"  !CDS_PN = "144";
"RFU2":   PN = "149"  !CDS_PN = "149";
"RFU3":   PN = "150"  !CDS_PN = "150";
"RFU4":   PN = "220"  !CDS_PN = "220";
"RFU5":   PN = "231"  !CDS_PN = "231";
"RFU6":   PN = "232"  !CDS_PN = "232";
"VIN_MGMT":   PN = "3"  !CDS_PN = "3";
BODY = "Q_RES","I129": #LOCATION = "R773" !CDS_LOCATION = "R773" &SEC = "1" #&CDS_SEC = "1";
"A":   PN = "1"  !CDS_PN = "1";
"B":   PN = "2"  !CDS_PN = "2";
BODY = "SCONN288_DDR506112002KQ","I142": #LOCATION = "J33" !CDS_LOCATION = "J33" &SEC = "3" #&CDS_SEC = "3";
"G1":   PN = "G1"  !CDS_PN = "G1";
"G2":   PN = "G2"  !CDS_PN = "G2";
"G3":   PN = "G3"  !CDS_PN = "G3";
"VIN_BULK0":   PN = "1"  !CDS_PN = "1";
"VIN_BULK1":   PN = "145"  !CDS_PN = "145";
"VIN_BULK2":   PN = "146"  !CDS_PN = "146";
"VSS0":   PN = "6"  !CDS_PN = "6";
"VSS1":   PN = "8"  !CDS_PN = "8";
"VSS2":   PN = "10"  !CDS_PN = "10";
"VSS3":   PN = "13"  !CDS_PN = "13";
"VSS4":   PN = "15"  !CDS_PN = "15";
"VSS5":   PN = "17"  !CDS_PN = "17";
"VSS6":   PN = "19"  !CDS_PN = "19";
"VSS7":   PN = "21"  !CDS_PN = "21";
"VSS8":   PN = "24"  !CDS_PN = "24";
"VSS9":   PN = "26"  !CDS_PN = "26";
"VSS10":   PN = "28"  !CDS_PN = "28";
"VSS11":   PN = "30"  !CDS_PN = "30";
"VSS12":   PN = "32"  !CDS_PN = "32";
"VSS13":   PN = "35"  !CDS_PN = "35";
"VSS14":   PN = "37"  !CDS_PN = "37";
"VSS15":   PN = "39"  !CDS_PN = "39";
"VSS16":   PN = "41"  !CDS_PN = "41";
"VSS17":   PN = "43"  !CDS_PN = "43";
"VSS18":   PN = "46"  !CDS_PN = "46";
"VSS19":   PN = "48"  !CDS_PN = "48";
"VSS20":   PN = "50"  !CDS_PN = "50";
"VSS21":   PN = "52"  !CDS_PN = "52";
"VSS22":   PN = "54"  !CDS_PN = "54";
"VSS23":   PN = "57"  !CDS_PN = "57";
"VSS24":   PN = "59"  !CDS_PN = "59";
"VSS25":   PN = "61"  !CDS_PN = "61";
"VSS26":   PN = "63"  !CDS_PN = "63";
"VSS27":   PN = "65"  !CDS_PN = "65";
"VSS28":   PN = "67"  !CDS_PN = "67";
"VSS29":   PN = "69"  !CDS_PN = "69";
"VSS30":   PN = "71"  !CDS_PN = "71";
"VSS31":   PN = "73"  !CDS_PN = "73";
"VSS32":   PN = "75"  !CDS_PN = "75";
"VSS33":   PN = "77"  !CDS_PN = "77";
"VSS34":   PN = "79"  !CDS_PN = "79";
"VSS35":   PN = "81"  !CDS_PN = "81";
"VSS36":   PN = "83"  !CDS_PN = "83";
"VSS37":   PN = "85"  !CDS_PN = "85";
"VSS38":   PN = "88"  !CDS_PN = "88";
"VSS39":   PN = "90"  !CDS_PN = "90";
"VSS40":   PN = "92"  !CDS_PN = "92";
"VSS41":   PN = "95"  !CDS_PN = "95";
"VSS42":   PN = "97"  !CDS_PN = "97";
"VSS43":   PN = "99"  !CDS_PN = "99";
"VSS44":   PN = "101"  !CDS_PN = "101";
"VSS45":   PN = "103"  !CDS_PN = "103";
"VSS46":   PN = "106"  !CDS_PN = "106";
"VSS47":   PN = "108"  !CDS_PN = "108";
"VSS48":   PN = "110"  !CDS_PN = "110";
"VSS49":   PN = "112"  !CDS_PN = "112";
"VSS50":   PN = "114"  !CDS_PN = "114";
"VSS51":   PN = "117"  !CDS_PN = "117";
"VSS52":   PN = "119"  !CDS_PN = "119";
"VSS53":   PN = "121"  !CDS_PN = "121";
"VSS54":   PN = "123"  !CDS_PN = "123";
"VSS55":   PN = "125"  !CDS_PN = "125";
"VSS56":   PN = "128"  !CDS_PN = "128";
"VSS57":   PN = "130"  !CDS_PN = "130";
"VSS58":   PN = "132"  !CDS_PN = "132";
"VSS59":   PN = "134"  !CDS_PN = "134";
"VSS60":   PN = "136"  !CDS_PN = "136";
"VSS61":   PN = "139"  !CDS_PN = "139";
"VSS62":   PN = "141"  !CDS_PN = "141";
"VSS63":   PN = "143"  !CDS_PN = "143";
"VSS64":   PN = "151"  !CDS_PN = "151";
"VSS65":   PN = "153"  !CDS_PN = "153";
"VSS66":   PN = "155"  !CDS_PN = "155";
"VSS67":   PN = "158"  !CDS_PN = "158";
"VSS68":   PN = "160"  !CDS_PN = "160";
"VSS69":   PN = "162"  !CDS_PN = "162";
"VSS70":   PN = "164"  !CDS_PN = "164";
"VSS71":   PN = "166"  !CDS_PN = "166";
"VSS72":   PN = "169"  !CDS_PN = "169";
"VSS73":   PN = "171"  !CDS_PN = "171";
"VSS74":   PN = "173"  !CDS_PN = "173";
"VSS75":   PN = "175"  !CDS_PN = "175";
"VSS76":   PN = "177"  !CDS_PN = "177";
"VSS77":   PN = "180"  !CDS_PN = "180";
"VSS78":   PN = "182"  !CDS_PN = "182";
"VSS79":   PN = "184"  !CDS_PN = "184";
"VSS80":   PN = "186"  !CDS_PN = "186";
"VSS81":   PN = "188"  !CDS_PN = "188";
"VSS82":   PN = "191"  !CDS_PN = "191";
"VSS83":   PN = "193"  !CDS_PN = "193";
"VSS84":   PN = "195"  !CDS_PN = "195";
"VSS85":   PN = "197"  !CDS_PN = "197";
"VSS86":   PN = "199"  !CDS_PN = "199";
"VSS87":   PN = "202"  !CDS_PN = "202";
"VSS88":   PN = "204"  !CDS_PN = "204";
"VSS89":   PN = "206"  !CDS_PN = "206";
"VSS90":   PN = "208"  !CDS_PN = "208";
"VSS91":   PN = "210"  !CDS_PN = "210";
"VSS92":   PN = "212"  !CDS_PN = "212";
"VSS93":   PN = "214"  !CDS_PN = "214";
"VSS94":   PN = "216"  !CDS_PN = "216";
"VSS95":   PN = "219"  !CDS_PN = "219";
"VSS96":   PN = "222"  !CDS_PN = "222";
"VSS97":   PN = "224"  !CDS_PN = "224";
"VSS98":   PN = "226"  !CDS_PN = "226";
"VSS99":   PN = "228"  !CDS_PN = "228";
"VSS100":   PN = "230"  !CDS_PN = "230";
"VSS101":   PN = "233"  !CDS_PN = "233";
"VSS102":   PN = "235"  !CDS_PN = "235";
"VSS103":   PN = "237"  !CDS_PN = "237";
"VSS104":   PN = "240"  !CDS_PN = "240";
"VSS105":   PN = "242"  !CDS_PN = "242";
"VSS106":   PN = "244"  !CDS_PN = "244";
"VSS107":   PN = "246"  !CDS_PN = "246";
"VSS108":   PN = "248"  !CDS_PN = "248";
"VSS109":   PN = "251"  !CDS_PN = "251";
"VSS110":   PN = "253"  !CDS_PN = "253";
"VSS111":   PN = "255"  !CDS_PN = "255";
"VSS112":   PN = "257"  !CDS_PN = "257";
"VSS113":   PN = "259"  !CDS_PN = "259";
"VSS114":   PN = "262"  !CDS_PN = "262";
"VSS115":   PN = "264"  !CDS_PN = "264";
"VSS116":   PN = "266"  !CDS_PN = "266";
"VSS117":   PN = "268"  !CDS_PN = "268";
"VSS118":   PN = "270"  !CDS_PN = "270";
"VSS119":   PN = "273"  !CDS_PN = "273";
"VSS120":   PN = "275"  !CDS_PN = "275";
"VSS121":   PN = "277"  !CDS_PN = "277";
"VSS122":   PN = "279"  !CDS_PN = "279";
"VSS123":   PN = "281"  !CDS_PN = "281";
"VSS124":   PN = "284"  !CDS_PN = "284";
"VSS125":   PN = "286"  !CDS_PN = "286";
"VSS126":   PN = "288"  !CDS_PN = "288";
BODY = "Q_CAP","I185": #LOCATION = "C156" !CDS_LOCATION = "C156" &SEC = "1" #&CDS_SEC = "1";
"A":   PN = "1"  !CDS_PN = "1";
"B":   PN = "2"  !CDS_PN = "2";
BODY = "Q_RES","I188": #LOCATION = "R1183" !CDS_LOCATION = "R1183" &SEC = "1" #&CDS_SEC = "1";
"A":   PN = "1"  !CDS_PN = "1";
"B":   PN = "2"  !CDS_PN = "2";
BODY = "Q_RES","I190": #LOCATION = "R108" !CDS_LOCATION = "R108" &SEC = "1" #&CDS_SEC = "1";
"A":   PN = "1"  !CDS_PN = "1";
"B":   PN = "2"  !CDS_PN = "2";
BODY = "SCONN288_DDR506112002KQ","I236": #LOCATION = "J33" !CDS_LOCATION = "J33" &SEC = "2" #&CDS_SEC = "2";
"DQS0_A_C":   PN = "12"  !CDS_PN = "12";
"DQS0_A_T":   PN = "11"  !CDS_PN = "11";
"DQS0_B_C":   PN = "105"  !CDS_PN = "105";
"DQS0_B_T":   PN = "104"  !CDS_PN = "104";
"DQS1_A_C":   PN = "23"  !CDS_PN = "23";
"DQS1_A_T":   PN = "22"  !CDS_PN = "22";
"DQS1_B_C":   PN = "116"  !CDS_PN = "116";
"DQS1_B_T":   PN = "115"  !CDS_PN = "115";
"DQS2_A_C":   PN = "34"  !CDS_PN = "34";
"DQS2_A_T":   PN = "33"  !CDS_PN = "33";
"DQS2_B_C":   PN = "127"  !CDS_PN = "127";
"DQS2_B_T":   PN = "126"  !CDS_PN = "126";
"DQS3_A_C":   PN = "45"  !CDS_PN = "45";
"DQS3_A_T":   PN = "44"  !CDS_PN = "44";
"DQS3_B_C":   PN = "138"  !CDS_PN = "138";
"DQS3_B_T":   PN = "137"  !CDS_PN = "137";
"DQS4_A_C":   PN = "56"  !CDS_PN = "56";
"DQS4_A_T":   PN = "55"  !CDS_PN = "55";
"DQS4_B_C":   PN = "238"  !CDS_PN = "238";
"DQS4_B_T":   PN = "239"  !CDS_PN = "239";
"DQS5_A_C||TDQS5_A_C||DQS5_A_T||TDQS5_A_T":   PN = "156"  !CDS_PN = "156";
"DQS5_A_T||TDQS5_A_T":   PN = "157"  !CDS_PN = "157";
"DQS5_B_C||TDQS5_B_C":   PN = "249"  !CDS_PN = "249";
"DQS5_B_T||TDQS5_B_T":   PN = "250"  !CDS_PN = "250";
"DQS6_A_C||TDQS6_A_C||DQS6_A_T||TDQS6_A_T":   PN = "167"  !CDS_PN = "167";
"DQS6_A_T||TDQS6_A_T":   PN = "168"  !CDS_PN = "168";
"DQS6_B_C||TDQS6_B_C":   PN = "260"  !CDS_PN = "260";
"DQS6_B_T||TDQS6_B_T":   PN = "261"  !CDS_PN = "261";
"DQS7_A_C||TDQS7_A_C":   PN = "178"  !CDS_PN = "178";
"DQS7_A_T||TDQS7_A_T":   PN = "179"  !CDS_PN = "179";
"DQS7_B_C||TDQS7_B_C":   PN = "271"  !CDS_PN = "271";
"DQS7_B_T||TDQS7_B_T":   PN = "272"  !CDS_PN = "272";
"DQS8_A_C||TDQS8_A_C":   PN = "189"  !CDS_PN = "189";
"DQS8_A_T||TDQS8_A_T":   PN = "190"  !CDS_PN = "190";
"DQS8_B_C||TDQS8_B_C":   PN = "282"  !CDS_PN = "282";
"DQS8_B_T||TDQS8_B_T":   PN = "283"  !CDS_PN = "283";
"DQS9_A_C||TDQS9_A_C":   PN = "200"  !CDS_PN = "200";
"DQS9_A_T||TDQS9_A_T":   PN = "201"  !CDS_PN = "201";
"DQS9_B_C||TDQS9_B_C":   PN = "94"  !CDS_PN = "94";
"DQS9_B_T||TDQS9_B_T||DBI4_B_N":   PN = "93"  !CDS_PN = "93";
BODY = "Q_CAP","I238": #LOCATION = "C518" !CDS_LOCATION = "C518" &SEC = "1" #&CDS_SEC = "1";
"A":   PN = "1"  !CDS_PN = "1";
"B":   PN = "2"  !CDS_PN = "2";
BODY = "Q_CAP","I239": #LOCATION = "C527" !CDS_LOCATION = "C527" &SEC = "1" #&CDS_SEC = "1";
"A":   PN = "1"  !CDS_PN = "1";
"B":   PN = "2"  !CDS_PN = "2";
BODY = "Q_RES","I242": #LOCATION = "R1585" !CDS_LOCATION = "R1585" &SEC = "1" #&CDS_SEC = "1";
"A":   PN = "1"  !CDS_PN = "1";
"B":   PN = "2"  !CDS_PN = "2";
BODY = "Q_RES","I243": #LOCATION = "R1704" !CDS_LOCATION = "R1704" &SEC = "1" #&CDS_SEC = "1";
"A":   PN = "1"  !CDS_PN = "1";
"B":   PN = "2"  !CDS_PN = "2";
DRAWING = "@t6g_mb_lib.t6g(sch_1):page103";
BODY = "SCONN288_DDR506112002KQ","I22": #LOCATION = "J102" !CDS_LOCATION = "J102" &SEC = "1" #&CDS_SEC = "1";
"ALERT_N":   PN = "62"  !CDS_PN = "62";
"CA0_A":   PN = "66"  !CDS_PN = "66";
"CA0_B":   PN = "76"  !CDS_PN = "76";
"CA1_A":   PN = "211"  !CDS_PN = "211";
"CA1_B":   PN = "221"  !CDS_PN = "221";
"CA2_A":   PN = "68"  !CDS_PN = "68";
"CA2_B":   PN = "78"  !CDS_PN = "78";
"CA3_A":   PN = "213"  !CDS_PN = "213";
"CA3_B":   PN = "223"  !CDS_PN = "223";
"CA4_A":   PN = "70"  !CDS_PN = "70";
"CA4_B":   PN = "80"  !CDS_PN = "80";
"CA5_A":   PN = "215"  !CDS_PN = "215";
"CA5_B":   PN = "225"  !CDS_PN = "225";
"CA6_A":   PN = "72"  !CDS_PN = "72";
"CA6_B":   PN = "82"  !CDS_PN = "82";
"CB0_A":   PN = "51"  !CDS_PN = "51";
"CB0_B":   PN = "96"  !CDS_PN = "96";
"CB1_A":   PN = "53"  !CDS_PN = "53";
"CB1_B":   PN = "98"  !CDS_PN = "98";
"CB2_A":   PN = "196"  !CDS_PN = "196";
"CB2_B":   PN = "241"  !CDS_PN = "241";
"CB3_A":   PN = "198"  !CDS_PN = "198";
"CB3_B":   PN = "243"  !CDS_PN = "243";
"CB4_A":   PN = "58"  !CDS_PN = "58";
"CB4_B":   PN = "89"  !CDS_PN = "89";
"CB5_A":   PN = "60"  !CDS_PN = "60";
"CB5_B":   PN = "91"  !CDS_PN = "91";
"CB6_A":   PN = "203"  !CDS_PN = "203";
"CB6_B":   PN = "234"  !CDS_PN = "234";
"CB7_A":   PN = "205"  !CDS_PN = "205";
"CB7_B":   PN = "236"  !CDS_PN = "236";
"CK_C":   PN = "218"  !CDS_PN = "218";
"CK_T":   PN = "217"  !CDS_PN = "217";
"CS0_A_N":   PN = "64"  !CDS_PN = "64";
"CS0_B_N":   PN = "84"  !CDS_PN = "84";
"CS1_A_N":   PN = "209"  !CDS_PN = "209";
"CS1_B_N":   PN = "229"  !CDS_PN = "229";
"DQ0_A":   PN = "7"  !CDS_PN = "7";
"DQ0_B":   PN = "100"  !CDS_PN = "100";
"DQ1_A":   PN = "9"  !CDS_PN = "9";
"DQ1_B":   PN = "102"  !CDS_PN = "102";
"DQ2_A":   PN = "152"  !CDS_PN = "152";
"DQ2_B":   PN = "245"  !CDS_PN = "245";
"DQ3_A":   PN = "154"  !CDS_PN = "154";
"DQ3_B":   PN = "247"  !CDS_PN = "247";
"DQ4_A":   PN = "14"  !CDS_PN = "14";
"DQ4_B":   PN = "107"  !CDS_PN = "107";
"DQ5_A":   PN = "16"  !CDS_PN = "16";
"DQ5_B":   PN = "109"  !CDS_PN = "109";
"DQ6_A":   PN = "159"  !CDS_PN = "159";
"DQ6_B":   PN = "252"  !CDS_PN = "252";
"DQ7_A":   PN = "161"  !CDS_PN = "161";
"DQ7_B":   PN = "254"  !CDS_PN = "254";
"DQ8_A":   PN = "18"  !CDS_PN = "18";
"DQ8_B":   PN = "111"  !CDS_PN = "111";
"DQ9_A":   PN = "20"  !CDS_PN = "20";
"DQ9_B":   PN = "113"  !CDS_PN = "113";
"DQ10_A":   PN = "163"  !CDS_PN = "163";
"DQ10_B":   PN = "256"  !CDS_PN = "256";
"DQ11_A":   PN = "165"  !CDS_PN = "165";
"DQ11_B":   PN = "258"  !CDS_PN = "258";
"DQ12_A":   PN = "25"  !CDS_PN = "25";
"DQ12_B":   PN = "118"  !CDS_PN = "118";
"DQ13_A":   PN = "27"  !CDS_PN = "27";
"DQ13_B":   PN = "120"  !CDS_PN = "120";
"DQ14_A":   PN = "170"  !CDS_PN = "170";
"DQ14_B":   PN = "263"  !CDS_PN = "263";
"DQ15_A":   PN = "172"  !CDS_PN = "172";
"DQ15_B":   PN = "265"  !CDS_PN = "265";
"DQ16_A":   PN = "29"  !CDS_PN = "29";
"DQ16_B":   PN = "122"  !CDS_PN = "122";
"DQ17_A":   PN = "31"  !CDS_PN = "31";
"DQ17_B":   PN = "124"  !CDS_PN = "124";
"DQ18_A":   PN = "174"  !CDS_PN = "174";
"DQ18_B":   PN = "267"  !CDS_PN = "267";
"DQ19_A":   PN = "176"  !CDS_PN = "176";
"DQ19_B":   PN = "269"  !CDS_PN = "269";
"DQ20_A":   PN = "36"  !CDS_PN = "36";
"DQ20_B":   PN = "129"  !CDS_PN = "129";
"DQ21_A":   PN = "38"  !CDS_PN = "38";
"DQ21_B":   PN = "131"  !CDS_PN = "131";
"DQ22_A":   PN = "181"  !CDS_PN = "181";
"DQ22_B":   PN = "274"  !CDS_PN = "274";
"DQ23_A":   PN = "183"  !CDS_PN = "183";
"DQ23_B":   PN = "276"  !CDS_PN = "276";
"DQ24_A":   PN = "40"  !CDS_PN = "40";
"DQ24_B":   PN = "133"  !CDS_PN = "133";
"DQ25_A":   PN = "42"  !CDS_PN = "42";
"DQ25_B":   PN = "135"  !CDS_PN = "135";
"DQ26_A":   PN = "185"  !CDS_PN = "185";
"DQ26_B":   PN = "278"  !CDS_PN = "278";
"DQ27_A":   PN = "187"  !CDS_PN = "187";
"DQ27_B":   PN = "280"  !CDS_PN = "280";
"DQ28_A":   PN = "47"  !CDS_PN = "47";
"DQ28_B":   PN = "140"  !CDS_PN = "140";
"DQ29_A":   PN = "49"  !CDS_PN = "49";
"DQ29_B":   PN = "142"  !CDS_PN = "142";
"DQ30_A":   PN = "192"  !CDS_PN = "192";
"DQ30_B":   PN = "285"  !CDS_PN = "285";
"DQ31_A":   PN = "194"  !CDS_PN = "194";
"DQ31_B":   PN = "287"  !CDS_PN = "287";
"HAS":   PN = "148"  !CDS_PN = "148";
"HSCL":   PN = "4"  !CDS_PN = "4";
"HSDA":   PN = "5"  !CDS_PN = "5";
"LBD||RSP_A_N":   PN = "86"  !CDS_PN = "86";
"LBS||RSP_B_N":   PN = "87"  !CDS_PN = "87";
"PAR_A":   PN = "74"  !CDS_PN = "74";
"PAR_B":   PN = "227"  !CDS_PN = "227";
"PWR_GOOD||FAIL_N":   PN = "147"  !CDS_PN = "147";
"RESET_N":   PN = "207"  !CDS_PN = "207";
"RFU0":   PN = "2"  !CDS_PN = "2";
"RFU1":   PN = "144"  !CDS_PN = "144";
"RFU2":   PN = "149"  !CDS_PN = "149";
"RFU3":   PN = "150"  !CDS_PN = "150";
"RFU4":   PN = "220"  !CDS_PN = "220";
"RFU5":   PN = "231"  !CDS_PN = "231";
"RFU6":   PN = "232"  !CDS_PN = "232";
"VIN_MGMT":   PN = "3"  !CDS_PN = "3";
BODY = "Q_RES","I129": #LOCATION = "R37" !CDS_LOCATION = "R37" #SEC = "1" !CDS_SEC = "1";
"A":   PN = "1"  !CDS_PN = "1";
"B":   PN = "2"  !CDS_PN = "2";
BODY = "SCONN288_DDR506112002KQ","I142": #LOCATION = "J102" !CDS_LOCATION = "J102" &SEC = "3" #&CDS_SEC = "3";
"G1":   PN = "G1"  !CDS_PN = "G1";
"G2":   PN = "G2"  !CDS_PN = "G2";
"G3":   PN = "G3"  !CDS_PN = "G3";
"VIN_BULK0":   PN = "1"  !CDS_PN = "1";
"VIN_BULK1":   PN = "145"  !CDS_PN = "145";
"VIN_BULK2":   PN = "146"  !CDS_PN = "146";
"VSS0":   PN = "6"  !CDS_PN = "6";
"VSS1":   PN = "8"  !CDS_PN = "8";
"VSS2":   PN = "10"  !CDS_PN = "10";
"VSS3":   PN = "13"  !CDS_PN = "13";
"VSS4":   PN = "15"  !CDS_PN = "15";
"VSS5":   PN = "17"  !CDS_PN = "17";
"VSS6":   PN = "19"  !CDS_PN = "19";
"VSS7":   PN = "21"  !CDS_PN = "21";
"VSS8":   PN = "24"  !CDS_PN = "24";
"VSS9":   PN = "26"  !CDS_PN = "26";
"VSS10":   PN = "28"  !CDS_PN = "28";
"VSS11":   PN = "30"  !CDS_PN = "30";
"VSS12":   PN = "32"  !CDS_PN = "32";
"VSS13":   PN = "35"  !CDS_PN = "35";
"VSS14":   PN = "37"  !CDS_PN = "37";
"VSS15":   PN = "39"  !CDS_PN = "39";
"VSS16":   PN = "41"  !CDS_PN = "41";
"VSS17":   PN = "43"  !CDS_PN = "43";
"VSS18":   PN = "46"  !CDS_PN = "46";
"VSS19":   PN = "48"  !CDS_PN = "48";
"VSS20":   PN = "50"  !CDS_PN = "50";
"VSS21":   PN = "52"  !CDS_PN = "52";
"VSS22":   PN = "54"  !CDS_PN = "54";
"VSS23":   PN = "57"  !CDS_PN = "57";
"VSS24":   PN = "59"  !CDS_PN = "59";
"VSS25":   PN = "61"  !CDS_PN = "61";
"VSS26":   PN = "63"  !CDS_PN = "63";
"VSS27":   PN = "65"  !CDS_PN = "65";
"VSS28":   PN = "67"  !CDS_PN = "67";
"VSS29":   PN = "69"  !CDS_PN = "69";
"VSS30":   PN = "71"  !CDS_PN = "71";
"VSS31":   PN = "73"  !CDS_PN = "73";
"VSS32":   PN = "75"  !CDS_PN = "75";
"VSS33":   PN = "77"  !CDS_PN = "77";
"VSS34":   PN = "79"  !CDS_PN = "79";
"VSS35":   PN = "81"  !CDS_PN = "81";
"VSS36":   PN = "83"  !CDS_PN = "83";
"VSS37":   PN = "85"  !CDS_PN = "85";
"VSS38":   PN = "88"  !CDS_PN = "88";
"VSS39":   PN = "90"  !CDS_PN = "90";
"VSS40":   PN = "92"  !CDS_PN = "92";
"VSS41":   PN = "95"  !CDS_PN = "95";
"VSS42":   PN = "97"  !CDS_PN = "97";
"VSS43":   PN = "99"  !CDS_PN = "99";
"VSS44":   PN = "101"  !CDS_PN = "101";
"VSS45":   PN = "103"  !CDS_PN = "103";
"VSS46":   PN = "106"  !CDS_PN = "106";
"VSS47":   PN = "108"  !CDS_PN = "108";
"VSS48":   PN = "110"  !CDS_PN = "110";
"VSS49":   PN = "112"  !CDS_PN = "112";
"VSS50":   PN = "114"  !CDS_PN = "114";
"VSS51":   PN = "117"  !CDS_PN = "117";
"VSS52":   PN = "119"  !CDS_PN = "119";
"VSS53":   PN = "121"  !CDS_PN = "121";
"VSS54":   PN = "123"  !CDS_PN = "123";
"VSS55":   PN = "125"  !CDS_PN = "125";
"VSS56":   PN = "128"  !CDS_PN = "128";
"VSS57":   PN = "130"  !CDS_PN = "130";
"VSS58":   PN = "132"  !CDS_PN = "132";
"VSS59":   PN = "134"  !CDS_PN = "134";
"VSS60":   PN = "136"  !CDS_PN = "136";
"VSS61":   PN = "139"  !CDS_PN = "139";
"VSS62":   PN = "141"  !CDS_PN = "141";
"VSS63":   PN = "143"  !CDS_PN = "143";
"VSS64":   PN = "151"  !CDS_PN = "151";
"VSS65":   PN = "153"  !CDS_PN = "153";
"VSS66":   PN = "155"  !CDS_PN = "155";
"VSS67":   PN = "158"  !CDS_PN = "158";
"VSS68":   PN = "160"  !CDS_PN = "160";
"VSS69":   PN = "162"  !CDS_PN = "162";
"VSS70":   PN = "164"  !CDS_PN = "164";
"VSS71":   PN = "166"  !CDS_PN = "166";
"VSS72":   PN = "169"  !CDS_PN = "169";
"VSS73":   PN = "171"  !CDS_PN = "171";
"VSS74":   PN = "173"  !CDS_PN = "173";
"VSS75":   PN = "175"  !CDS_PN = "175";
"VSS76":   PN = "177"  !CDS_PN = "177";
"VSS77":   PN = "180"  !CDS_PN = "180";
"VSS78":   PN = "182"  !CDS_PN = "182";
"VSS79":   PN = "184"  !CDS_PN = "184";
"VSS80":   PN = "186"  !CDS_PN = "186";
"VSS81":   PN = "188"  !CDS_PN = "188";
"VSS82":   PN = "191"  !CDS_PN = "191";
"VSS83":   PN = "193"  !CDS_PN = "193";
"VSS84":   PN = "195"  !CDS_PN = "195";
"VSS85":   PN = "197"  !CDS_PN = "197";
"VSS86":   PN = "199"  !CDS_PN = "199";
"VSS87":   PN = "202"  !CDS_PN = "202";
"VSS88":   PN = "204"  !CDS_PN = "204";
"VSS89":   PN = "206"  !CDS_PN = "206";
"VSS90":   PN = "208"  !CDS_PN = "208";
"VSS91":   PN = "210"  !CDS_PN = "210";
"VSS92":   PN = "212"  !CDS_PN = "212";
"VSS93":   PN = "214"  !CDS_PN = "214";
"VSS94":   PN = "216"  !CDS_PN = "216";
"VSS95":   PN = "219"  !CDS_PN = "219";
"VSS96":   PN = "222"  !CDS_PN = "222";
"VSS97":   PN = "224"  !CDS_PN = "224";
"VSS98":   PN = "226"  !CDS_PN = "226";
"VSS99":   PN = "228"  !CDS_PN = "228";
"VSS100":   PN = "230"  !CDS_PN = "230";
"VSS101":   PN = "233"  !CDS_PN = "233";
"VSS102":   PN = "235"  !CDS_PN = "235";
"VSS103":   PN = "237"  !CDS_PN = "237";
"VSS104":   PN = "240"  !CDS_PN = "240";
"VSS105":   PN = "242"  !CDS_PN = "242";
"VSS106":   PN = "244"  !CDS_PN = "244";
"VSS107":   PN = "246"  !CDS_PN = "246";
"VSS108":   PN = "248"  !CDS_PN = "248";
"VSS109":   PN = "251"  !CDS_PN = "251";
"VSS110":   PN = "253"  !CDS_PN = "253";
"VSS111":   PN = "255"  !CDS_PN = "255";
"VSS112":   PN = "257"  !CDS_PN = "257";
"VSS113":   PN = "259"  !CDS_PN = "259";
"VSS114":   PN = "262"  !CDS_PN = "262";
"VSS115":   PN = "264"  !CDS_PN = "264";
"VSS116":   PN = "266"  !CDS_PN = "266";
"VSS117":   PN = "268"  !CDS_PN = "268";
"VSS118":   PN = "270"  !CDS_PN = "270";
"VSS119":   PN = "273"  !CDS_PN = "273";
"VSS120":   PN = "275"  !CDS_PN = "275";
"VSS121":   PN = "277"  !CDS_PN = "277";
"VSS122":   PN = "279"  !CDS_PN = "279";
"VSS123":   PN = "281"  !CDS_PN = "281";
"VSS124":   PN = "284"  !CDS_PN = "284";
"VSS125":   PN = "286"  !CDS_PN = "286";
"VSS126":   PN = "288"  !CDS_PN = "288";
BODY = "Q_CAP","I185": #LOCATION = "C160" !CDS_LOCATION = "C160" &SEC = "1" #&CDS_SEC = "1";
"A":   PN = "1"  !CDS_PN = "1";
"B":   PN = "2"  !CDS_PN = "2";
BODY = "Q_RES","I188": #LOCATION = "R1184" !CDS_LOCATION = "R1184" &SEC = "1" #&CDS_SEC = "1";
"A":   PN = "1"  !CDS_PN = "1";
"B":   PN = "2"  !CDS_PN = "2";
BODY = "Q_RES","I189": #LOCATION = "R109" !CDS_LOCATION = "R109" &SEC = "1" #&CDS_SEC = "1";
"A":   PN = "1"  !CDS_PN = "1";
"B":   PN = "2"  !CDS_PN = "2";
BODY = "Q_RES","I192": #LOCATION = "R110" !CDS_LOCATION = "R110" &SEC = "1" #&CDS_SEC = "1";
"A":   PN = "1"  !CDS_PN = "1";
"B":   PN = "2"  !CDS_PN = "2";
BODY = "SCONN288_DDR506112002KQ","I238": #LOCATION = "J102" !CDS_LOCATION = "J102" &SEC = "2" #&CDS_SEC = "2";
"DQS0_A_C":   PN = "12"  !CDS_PN = "12";
"DQS0_A_T":   PN = "11"  !CDS_PN = "11";
"DQS0_B_C":   PN = "105"  !CDS_PN = "105";
"DQS0_B_T":   PN = "104"  !CDS_PN = "104";
"DQS1_A_C":   PN = "23"  !CDS_PN = "23";
"DQS1_A_T":   PN = "22"  !CDS_PN = "22";
"DQS1_B_C":   PN = "116"  !CDS_PN = "116";
"DQS1_B_T":   PN = "115"  !CDS_PN = "115";
"DQS2_A_C":   PN = "34"  !CDS_PN = "34";
"DQS2_A_T":   PN = "33"  !CDS_PN = "33";
"DQS2_B_C":   PN = "127"  !CDS_PN = "127";
"DQS2_B_T":   PN = "126"  !CDS_PN = "126";
"DQS3_A_C":   PN = "45"  !CDS_PN = "45";
"DQS3_A_T":   PN = "44"  !CDS_PN = "44";
"DQS3_B_C":   PN = "138"  !CDS_PN = "138";
"DQS3_B_T":   PN = "137"  !CDS_PN = "137";
"DQS4_A_C":   PN = "56"  !CDS_PN = "56";
"DQS4_A_T":   PN = "55"  !CDS_PN = "55";
"DQS4_B_C":   PN = "238"  !CDS_PN = "238";
"DQS4_B_T":   PN = "239"  !CDS_PN = "239";
"DQS5_A_C||TDQS5_A_C||DQS5_A_T||TDQS5_A_T":   PN = "156"  !CDS_PN = "156";
"DQS5_A_T||TDQS5_A_T":   PN = "157"  !CDS_PN = "157";
"DQS5_B_C||TDQS5_B_C":   PN = "249"  !CDS_PN = "249";
"DQS5_B_T||TDQS5_B_T":   PN = "250"  !CDS_PN = "250";
"DQS6_A_C||TDQS6_A_C||DQS6_A_T||TDQS6_A_T":   PN = "167"  !CDS_PN = "167";
"DQS6_A_T||TDQS6_A_T":   PN = "168"  !CDS_PN = "168";
"DQS6_B_C||TDQS6_B_C":   PN = "260"  !CDS_PN = "260";
"DQS6_B_T||TDQS6_B_T":   PN = "261"  !CDS_PN = "261";
"DQS7_A_C||TDQS7_A_C":   PN = "178"  !CDS_PN = "178";
"DQS7_A_T||TDQS7_A_T":   PN = "179"  !CDS_PN = "179";
"DQS7_B_C||TDQS7_B_C":   PN = "271"  !CDS_PN = "271";
"DQS7_B_T||TDQS7_B_T":   PN = "272"  !CDS_PN = "272";
"DQS8_A_C||TDQS8_A_C":   PN = "189"  !CDS_PN = "189";
"DQS8_A_T||TDQS8_A_T":   PN = "190"  !CDS_PN = "190";
"DQS8_B_C||TDQS8_B_C":   PN = "282"  !CDS_PN = "282";
"DQS8_B_T||TDQS8_B_T":   PN = "283"  !CDS_PN = "283";
"DQS9_A_C||TDQS9_A_C":   PN = "200"  !CDS_PN = "200";
"DQS9_A_T||TDQS9_A_T":   PN = "201"  !CDS_PN = "201";
"DQS9_B_C||TDQS9_B_C":   PN = "94"  !CDS_PN = "94";
"DQS9_B_T||TDQS9_B_T||DBI4_B_N":   PN = "93"  !CDS_PN = "93";
BODY = "Q_CAP","I240": #LOCATION = "C530" !CDS_LOCATION = "C530" &SEC = "1" #&CDS_SEC = "1";
"A":   PN = "1"  !CDS_PN = "1";
"B":   PN = "2"  !CDS_PN = "2";
BODY = "Q_CAP","I241": #LOCATION = "C531" !CDS_LOCATION = "C531" &SEC = "1" #&CDS_SEC = "1";
"A":   PN = "1"  !CDS_PN = "1";
"B":   PN = "2"  !CDS_PN = "2";
BODY = "Q_RES","I244": #LOCATION = "R1586" !CDS_LOCATION = "R1586" &SEC = "1" #&CDS_SEC = "1";
"A":   PN = "1"  !CDS_PN = "1";
"B":   PN = "2"  !CDS_PN = "2";
BODY = "Q_RES","I245": #LOCATION = "R8040" !CDS_LOCATION = "R8040" &SEC = "1" #&CDS_SEC = "1";
"A":   PN = "1"  !CDS_PN = "1";
"B":   PN = "2"  !CDS_PN = "2";
BODY = "Q_RES","I249": #LOCATION = "R8089" !CDS_LOCATION = "R8089" &SEC = "1" #&CDS_SEC = "1";
"A":   PN = "1"  !CDS_PN = "1";
"B":   PN = "2"  !CDS_PN = "2";
BODY = "Q_RES","I251": #LOCATION = "R8091" !CDS_LOCATION = "R8091" &SEC = "1" #&CDS_SEC = "1";
"A":   PN = "1"  !CDS_PN = "1";
"B":   PN = "2"  !CDS_PN = "2";
BODY = "Q_RES","I252": #LOCATION = "R8090" !CDS_LOCATION = "R8090" &SEC = "1" #&CDS_SEC = "1";
"A":   PN = "1"  !CDS_PN = "1";
"B":   PN = "2"  !CDS_PN = "2";
BODY = "SCHOTTKY_12","I253": #LOCATION = "D8006" !CDS_LOCATION = "D8006" &SEC = "1" #&CDS_SEC = "1";
"A":   PN = "1"  !CDS_PN = "1";
"C":   PN = "2"  !CDS_PN = "2";
BODY = "Q_RES","I256": #LOCATION = "R1705" !CDS_LOCATION = "R1705" &SEC = "1" #&CDS_SEC = "1";
"A":   PN = "1"  !CDS_PN = "1";
"B":   PN = "2"  !CDS_PN = "2";
DRAWING = "@t6g_mb_lib.t6g(sch_1):page104";
BODY = "SCONN288_DDR506112002KQ","I22": #LOCATION = "J27" !CDS_LOCATION = "J27" &SEC = "1" #&CDS_SEC = "1";
"ALERT_N":   PN = "62"  !CDS_PN = "62";
"CA0_A":   PN = "66"  !CDS_PN = "66";
"CA0_B":   PN = "76"  !CDS_PN = "76";
"CA1_A":   PN = "211"  !CDS_PN = "211";
"CA1_B":   PN = "221"  !CDS_PN = "221";
"CA2_A":   PN = "68"  !CDS_PN = "68";
"CA2_B":   PN = "78"  !CDS_PN = "78";
"CA3_A":   PN = "213"  !CDS_PN = "213";
"CA3_B":   PN = "223"  !CDS_PN = "223";
"CA4_A":   PN = "70"  !CDS_PN = "70";
"CA4_B":   PN = "80"  !CDS_PN = "80";
"CA5_A":   PN = "215"  !CDS_PN = "215";
"CA5_B":   PN = "225"  !CDS_PN = "225";
"CA6_A":   PN = "72"  !CDS_PN = "72";
"CA6_B":   PN = "82"  !CDS_PN = "82";
"CB0_A":   PN = "51"  !CDS_PN = "51";
"CB0_B":   PN = "96"  !CDS_PN = "96";
"CB1_A":   PN = "53"  !CDS_PN = "53";
"CB1_B":   PN = "98"  !CDS_PN = "98";
"CB2_A":   PN = "196"  !CDS_PN = "196";
"CB2_B":   PN = "241"  !CDS_PN = "241";
"CB3_A":   PN = "198"  !CDS_PN = "198";
"CB3_B":   PN = "243"  !CDS_PN = "243";
"CB4_A":   PN = "58"  !CDS_PN = "58";
"CB4_B":   PN = "89"  !CDS_PN = "89";
"CB5_A":   PN = "60"  !CDS_PN = "60";
"CB5_B":   PN = "91"  !CDS_PN = "91";
"CB6_A":   PN = "203"  !CDS_PN = "203";
"CB6_B":   PN = "234"  !CDS_PN = "234";
"CB7_A":   PN = "205"  !CDS_PN = "205";
"CB7_B":   PN = "236"  !CDS_PN = "236";
"CK_C":   PN = "218"  !CDS_PN = "218";
"CK_T":   PN = "217"  !CDS_PN = "217";
"CS0_A_N":   PN = "64"  !CDS_PN = "64";
"CS0_B_N":   PN = "84"  !CDS_PN = "84";
"CS1_A_N":   PN = "209"  !CDS_PN = "209";
"CS1_B_N":   PN = "229"  !CDS_PN = "229";
"DQ0_A":   PN = "7"  !CDS_PN = "7";
"DQ0_B":   PN = "100"  !CDS_PN = "100";
"DQ1_A":   PN = "9"  !CDS_PN = "9";
"DQ1_B":   PN = "102"  !CDS_PN = "102";
"DQ2_A":   PN = "152"  !CDS_PN = "152";
"DQ2_B":   PN = "245"  !CDS_PN = "245";
"DQ3_A":   PN = "154"  !CDS_PN = "154";
"DQ3_B":   PN = "247"  !CDS_PN = "247";
"DQ4_A":   PN = "14"  !CDS_PN = "14";
"DQ4_B":   PN = "107"  !CDS_PN = "107";
"DQ5_A":   PN = "16"  !CDS_PN = "16";
"DQ5_B":   PN = "109"  !CDS_PN = "109";
"DQ6_A":   PN = "159"  !CDS_PN = "159";
"DQ6_B":   PN = "252"  !CDS_PN = "252";
"DQ7_A":   PN = "161"  !CDS_PN = "161";
"DQ7_B":   PN = "254"  !CDS_PN = "254";
"DQ8_A":   PN = "18"  !CDS_PN = "18";
"DQ8_B":   PN = "111"  !CDS_PN = "111";
"DQ9_A":   PN = "20"  !CDS_PN = "20";
"DQ9_B":   PN = "113"  !CDS_PN = "113";
"DQ10_A":   PN = "163"  !CDS_PN = "163";
"DQ10_B":   PN = "256"  !CDS_PN = "256";
"DQ11_A":   PN = "165"  !CDS_PN = "165";
"DQ11_B":   PN = "258"  !CDS_PN = "258";
"DQ12_A":   PN = "25"  !CDS_PN = "25";
"DQ12_B":   PN = "118"  !CDS_PN = "118";
"DQ13_A":   PN = "27"  !CDS_PN = "27";
"DQ13_B":   PN = "120"  !CDS_PN = "120";
"DQ14_A":   PN = "170"  !CDS_PN = "170";
"DQ14_B":   PN = "263"  !CDS_PN = "263";
"DQ15_A":   PN = "172"  !CDS_PN = "172";
"DQ15_B":   PN = "265"  !CDS_PN = "265";
"DQ16_A":   PN = "29"  !CDS_PN = "29";
"DQ16_B":   PN = "122"  !CDS_PN = "122";
"DQ17_A":   PN = "31"  !CDS_PN = "31";
"DQ17_B":   PN = "124"  !CDS_PN = "124";
"DQ18_A":   PN = "174"  !CDS_PN = "174";
"DQ18_B":   PN = "267"  !CDS_PN = "267";
"DQ19_A":   PN = "176"  !CDS_PN = "176";
"DQ19_B":   PN = "269"  !CDS_PN = "269";
"DQ20_A":   PN = "36"  !CDS_PN = "36";
"DQ20_B":   PN = "129"  !CDS_PN = "129";
"DQ21_A":   PN = "38"  !CDS_PN = "38";
"DQ21_B":   PN = "131"  !CDS_PN = "131";
"DQ22_A":   PN = "181"  !CDS_PN = "181";
"DQ22_B":   PN = "274"  !CDS_PN = "274";
"DQ23_A":   PN = "183"  !CDS_PN = "183";
"DQ23_B":   PN = "276"  !CDS_PN = "276";
"DQ24_A":   PN = "40"  !CDS_PN = "40";
"DQ24_B":   PN = "133"  !CDS_PN = "133";
"DQ25_A":   PN = "42"  !CDS_PN = "42";
"DQ25_B":   PN = "135"  !CDS_PN = "135";
"DQ26_A":   PN = "185"  !CDS_PN = "185";
"DQ26_B":   PN = "278"  !CDS_PN = "278";
"DQ27_A":   PN = "187"  !CDS_PN = "187";
"DQ27_B":   PN = "280"  !CDS_PN = "280";
"DQ28_A":   PN = "47"  !CDS_PN = "47";
"DQ28_B":   PN = "140"  !CDS_PN = "140";
"DQ29_A":   PN = "49"  !CDS_PN = "49";
"DQ29_B":   PN = "142"  !CDS_PN = "142";
"DQ30_A":   PN = "192"  !CDS_PN = "192";
"DQ30_B":   PN = "285"  !CDS_PN = "285";
"DQ31_A":   PN = "194"  !CDS_PN = "194";
"DQ31_B":   PN = "287"  !CDS_PN = "287";
"HAS":   PN = "148"  !CDS_PN = "148";
"HSCL":   PN = "4"  !CDS_PN = "4";
"HSDA":   PN = "5"  !CDS_PN = "5";
"LBD||RSP_A_N":   PN = "86"  !CDS_PN = "86";
"LBS||RSP_B_N":   PN = "87"  !CDS_PN = "87";
"PAR_A":   PN = "74"  !CDS_PN = "74";
"PAR_B":   PN = "227"  !CDS_PN = "227";
"PWR_GOOD||FAIL_N":   PN = "147"  !CDS_PN = "147";
"RESET_N":   PN = "207"  !CDS_PN = "207";
"RFU0":   PN = "2"  !CDS_PN = "2";
"RFU1":   PN = "144"  !CDS_PN = "144";
"RFU2":   PN = "149"  !CDS_PN = "149";
"RFU3":   PN = "150"  !CDS_PN = "150";
"RFU4":   PN = "220"  !CDS_PN = "220";
"RFU5":   PN = "231"  !CDS_PN = "231";
"RFU6":   PN = "232"  !CDS_PN = "232";
"VIN_MGMT":   PN = "3"  !CDS_PN = "3";
BODY = "Q_RES","I128": #LOCATION = "R774" !CDS_LOCATION = "R774" &SEC = "1" #&CDS_SEC = "1";
"A":   PN = "1"  !CDS_PN = "1";
"B":   PN = "2"  !CDS_PN = "2";
BODY = "SCONN288_DDR506112002KQ","I174": #LOCATION = "J27" !CDS_LOCATION = "J27" &SEC = "3" #&CDS_SEC = "3";
"G1":   PN = "G1"  !CDS_PN = "G1";
"G2":   PN = "G2"  !CDS_PN = "G2";
"G3":   PN = "G3"  !CDS_PN = "G3";
"VIN_BULK0":   PN = "1"  !CDS_PN = "1";
"VIN_BULK1":   PN = "145"  !CDS_PN = "145";
"VIN_BULK2":   PN = "146"  !CDS_PN = "146";
"VSS0":   PN = "6"  !CDS_PN = "6";
"VSS1":   PN = "8"  !CDS_PN = "8";
"VSS2":   PN = "10"  !CDS_PN = "10";
"VSS3":   PN = "13"  !CDS_PN = "13";
"VSS4":   PN = "15"  !CDS_PN = "15";
"VSS5":   PN = "17"  !CDS_PN = "17";
"VSS6":   PN = "19"  !CDS_PN = "19";
"VSS7":   PN = "21"  !CDS_PN = "21";
"VSS8":   PN = "24"  !CDS_PN = "24";
"VSS9":   PN = "26"  !CDS_PN = "26";
"VSS10":   PN = "28"  !CDS_PN = "28";
"VSS11":   PN = "30"  !CDS_PN = "30";
"VSS12":   PN = "32"  !CDS_PN = "32";
"VSS13":   PN = "35"  !CDS_PN = "35";
"VSS14":   PN = "37"  !CDS_PN = "37";
"VSS15":   PN = "39"  !CDS_PN = "39";
"VSS16":   PN = "41"  !CDS_PN = "41";
"VSS17":   PN = "43"  !CDS_PN = "43";
"VSS18":   PN = "46"  !CDS_PN = "46";
"VSS19":   PN = "48"  !CDS_PN = "48";
"VSS20":   PN = "50"  !CDS_PN = "50";
"VSS21":   PN = "52"  !CDS_PN = "52";
"VSS22":   PN = "54"  !CDS_PN = "54";
"VSS23":   PN = "57"  !CDS_PN = "57";
"VSS24":   PN = "59"  !CDS_PN = "59";
"VSS25":   PN = "61"  !CDS_PN = "61";
"VSS26":   PN = "63"  !CDS_PN = "63";
"VSS27":   PN = "65"  !CDS_PN = "65";
"VSS28":   PN = "67"  !CDS_PN = "67";
"VSS29":   PN = "69"  !CDS_PN = "69";
"VSS30":   PN = "71"  !CDS_PN = "71";
"VSS31":   PN = "73"  !CDS_PN = "73";
"VSS32":   PN = "75"  !CDS_PN = "75";
"VSS33":   PN = "77"  !CDS_PN = "77";
"VSS34":   PN = "79"  !CDS_PN = "79";
"VSS35":   PN = "81"  !CDS_PN = "81";
"VSS36":   PN = "83"  !CDS_PN = "83";
"VSS37":   PN = "85"  !CDS_PN = "85";
"VSS38":   PN = "88"  !CDS_PN = "88";
"VSS39":   PN = "90"  !CDS_PN = "90";
"VSS40":   PN = "92"  !CDS_PN = "92";
"VSS41":   PN = "95"  !CDS_PN = "95";
"VSS42":   PN = "97"  !CDS_PN = "97";
"VSS43":   PN = "99"  !CDS_PN = "99";
"VSS44":   PN = "101"  !CDS_PN = "101";
"VSS45":   PN = "103"  !CDS_PN = "103";
"VSS46":   PN = "106"  !CDS_PN = "106";
"VSS47":   PN = "108"  !CDS_PN = "108";
"VSS48":   PN = "110"  !CDS_PN = "110";
"VSS49":   PN = "112"  !CDS_PN = "112";
"VSS50":   PN = "114"  !CDS_PN = "114";
"VSS51":   PN = "117"  !CDS_PN = "117";
"VSS52":   PN = "119"  !CDS_PN = "119";
"VSS53":   PN = "121"  !CDS_PN = "121";
"VSS54":   PN = "123"  !CDS_PN = "123";
"VSS55":   PN = "125"  !CDS_PN = "125";
"VSS56":   PN = "128"  !CDS_PN = "128";
"VSS57":   PN = "130"  !CDS_PN = "130";
"VSS58":   PN = "132"  !CDS_PN = "132";
"VSS59":   PN = "134"  !CDS_PN = "134";
"VSS60":   PN = "136"  !CDS_PN = "136";
"VSS61":   PN = "139"  !CDS_PN = "139";
"VSS62":   PN = "141"  !CDS_PN = "141";
"VSS63":   PN = "143"  !CDS_PN = "143";
"VSS64":   PN = "151"  !CDS_PN = "151";
"VSS65":   PN = "153"  !CDS_PN = "153";
"VSS66":   PN = "155"  !CDS_PN = "155";
"VSS67":   PN = "158"  !CDS_PN = "158";
"VSS68":   PN = "160"  !CDS_PN = "160";
"VSS69":   PN = "162"  !CDS_PN = "162";
"VSS70":   PN = "164"  !CDS_PN = "164";
"VSS71":   PN = "166"  !CDS_PN = "166";
"VSS72":   PN = "169"  !CDS_PN = "169";
"VSS73":   PN = "171"  !CDS_PN = "171";
"VSS74":   PN = "173"  !CDS_PN = "173";
"VSS75":   PN = "175"  !CDS_PN = "175";
"VSS76":   PN = "177"  !CDS_PN = "177";
"VSS77":   PN = "180"  !CDS_PN = "180";
"VSS78":   PN = "182"  !CDS_PN = "182";
"VSS79":   PN = "184"  !CDS_PN = "184";
"VSS80":   PN = "186"  !CDS_PN = "186";
"VSS81":   PN = "188"  !CDS_PN = "188";
"VSS82":   PN = "191"  !CDS_PN = "191";
"VSS83":   PN = "193"  !CDS_PN = "193";
"VSS84":   PN = "195"  !CDS_PN = "195";
"VSS85":   PN = "197"  !CDS_PN = "197";
"VSS86":   PN = "199"  !CDS_PN = "199";
"VSS87":   PN = "202"  !CDS_PN = "202";
"VSS88":   PN = "204"  !CDS_PN = "204";
"VSS89":   PN = "206"  !CDS_PN = "206";
"VSS90":   PN = "208"  !CDS_PN = "208";
"VSS91":   PN = "210"  !CDS_PN = "210";
"VSS92":   PN = "212"  !CDS_PN = "212";
"VSS93":   PN = "214"  !CDS_PN = "214";
"VSS94":   PN = "216"  !CDS_PN = "216";
"VSS95":   PN = "219"  !CDS_PN = "219";
"VSS96":   PN = "222"  !CDS_PN = "222";
"VSS97":   PN = "224"  !CDS_PN = "224";
"VSS98":   PN = "226"  !CDS_PN = "226";
"VSS99":   PN = "228"  !CDS_PN = "228";
"VSS100":   PN = "230"  !CDS_PN = "230";
"VSS101":   PN = "233"  !CDS_PN = "233";
"VSS102":   PN = "235"  !CDS_PN = "235";
"VSS103":   PN = "237"  !CDS_PN = "237";
"VSS104":   PN = "240"  !CDS_PN = "240";
"VSS105":   PN = "242"  !CDS_PN = "242";
"VSS106":   PN = "244"  !CDS_PN = "244";
"VSS107":   PN = "246"  !CDS_PN = "246";
"VSS108":   PN = "248"  !CDS_PN = "248";
"VSS109":   PN = "251"  !CDS_PN = "251";
"VSS110":   PN = "253"  !CDS_PN = "253";
"VSS111":   PN = "255"  !CDS_PN = "255";
"VSS112":   PN = "257"  !CDS_PN = "257";
"VSS113":   PN = "259"  !CDS_PN = "259";
"VSS114":   PN = "262"  !CDS_PN = "262";
"VSS115":   PN = "264"  !CDS_PN = "264";
"VSS116":   PN = "266"  !CDS_PN = "266";
"VSS117":   PN = "268"  !CDS_PN = "268";
"VSS118":   PN = "270"  !CDS_PN = "270";
"VSS119":   PN = "273"  !CDS_PN = "273";
"VSS120":   PN = "275"  !CDS_PN = "275";
"VSS121":   PN = "277"  !CDS_PN = "277";
"VSS122":   PN = "279"  !CDS_PN = "279";
"VSS123":   PN = "281"  !CDS_PN = "281";
"VSS124":   PN = "284"  !CDS_PN = "284";
"VSS125":   PN = "286"  !CDS_PN = "286";
"VSS126":   PN = "288"  !CDS_PN = "288";
BODY = "Q_CAP","I185": #LOCATION = "C164" !CDS_LOCATION = "C164" &SEC = "1" #&CDS_SEC = "1";
"A":   PN = "1"  !CDS_PN = "1";
"B":   PN = "2"  !CDS_PN = "2";
BODY = "Q_RES","I189": #LOCATION = "R310" !CDS_LOCATION = "R310" &SEC = "1" #&CDS_SEC = "1";
"A":   PN = "1"  !CDS_PN = "1";
"B":   PN = "2"  !CDS_PN = "2";
BODY = "Q_RES","I190": #LOCATION = "R111" !CDS_LOCATION = "R111" &SEC = "1" #&CDS_SEC = "1";
"A":   PN = "1"  !CDS_PN = "1";
"B":   PN = "2"  !CDS_PN = "2";
BODY = "SCONN288_DDR506112002KQ","I238": #LOCATION = "J27" !CDS_LOCATION = "J27" &SEC = "2" #&CDS_SEC = "2";
"DQS0_A_C":   PN = "12"  !CDS_PN = "12";
"DQS0_A_T":   PN = "11"  !CDS_PN = "11";
"DQS0_B_C":   PN = "105"  !CDS_PN = "105";
"DQS0_B_T":   PN = "104"  !CDS_PN = "104";
"DQS1_A_C":   PN = "23"  !CDS_PN = "23";
"DQS1_A_T":   PN = "22"  !CDS_PN = "22";
"DQS1_B_C":   PN = "116"  !CDS_PN = "116";
"DQS1_B_T":   PN = "115"  !CDS_PN = "115";
"DQS2_A_C":   PN = "34"  !CDS_PN = "34";
"DQS2_A_T":   PN = "33"  !CDS_PN = "33";
"DQS2_B_C":   PN = "127"  !CDS_PN = "127";
"DQS2_B_T":   PN = "126"  !CDS_PN = "126";
"DQS3_A_C":   PN = "45"  !CDS_PN = "45";
"DQS3_A_T":   PN = "44"  !CDS_PN = "44";
"DQS3_B_C":   PN = "138"  !CDS_PN = "138";
"DQS3_B_T":   PN = "137"  !CDS_PN = "137";
"DQS4_A_C":   PN = "56"  !CDS_PN = "56";
"DQS4_A_T":   PN = "55"  !CDS_PN = "55";
"DQS4_B_C":   PN = "238"  !CDS_PN = "238";
"DQS4_B_T":   PN = "239"  !CDS_PN = "239";
"DQS5_A_C||TDQS5_A_C||DQS5_A_T||TDQS5_A_T":   PN = "156"  !CDS_PN = "156";
"DQS5_A_T||TDQS5_A_T":   PN = "157"  !CDS_PN = "157";
"DQS5_B_C||TDQS5_B_C":   PN = "249"  !CDS_PN = "249";
"DQS5_B_T||TDQS5_B_T":   PN = "250"  !CDS_PN = "250";
"DQS6_A_C||TDQS6_A_C||DQS6_A_T||TDQS6_A_T":   PN = "167"  !CDS_PN = "167";
"DQS6_A_T||TDQS6_A_T":   PN = "168"  !CDS_PN = "168";
"DQS6_B_C||TDQS6_B_C":   PN = "260"  !CDS_PN = "260";
"DQS6_B_T||TDQS6_B_T":   PN = "261"  !CDS_PN = "261";
"DQS7_A_C||TDQS7_A_C":   PN = "178"  !CDS_PN = "178";
"DQS7_A_T||TDQS7_A_T":   PN = "179"  !CDS_PN = "179";
"DQS7_B_C||TDQS7_B_C":   PN = "271"  !CDS_PN = "271";
"DQS7_B_T||TDQS7_B_T":   PN = "272"  !CDS_PN = "272";
"DQS8_A_C||TDQS8_A_C":   PN = "189"  !CDS_PN = "189";
"DQS8_A_T||TDQS8_A_T":   PN = "190"  !CDS_PN = "190";
"DQS8_B_C||TDQS8_B_C":   PN = "282"  !CDS_PN = "282";
"DQS8_B_T||TDQS8_B_T":   PN = "283"  !CDS_PN = "283";
"DQS9_A_C||TDQS9_A_C":   PN = "200"  !CDS_PN = "200";
"DQS9_A_T||TDQS9_A_T":   PN = "201"  !CDS_PN = "201";
"DQS9_B_C||TDQS9_B_C":   PN = "94"  !CDS_PN = "94";
"DQS9_B_T||TDQS9_B_T||DBI4_B_N":   PN = "93"  !CDS_PN = "93";
BODY = "Q_CAP","I240": #LOCATION = "C532" !CDS_LOCATION = "C532" &SEC = "1" #&CDS_SEC = "1";
"A":   PN = "1"  !CDS_PN = "1";
"B":   PN = "2"  !CDS_PN = "2";
BODY = "Q_CAP","I241": #LOCATION = "C533" !CDS_LOCATION = "C533" &SEC = "1" #&CDS_SEC = "1";
"A":   PN = "1"  !CDS_PN = "1";
"B":   PN = "2"  !CDS_PN = "2";
BODY = "Q_RES","I244": #LOCATION = "R1587" !CDS_LOCATION = "R1587" &SEC = "1" #&CDS_SEC = "1";
"A":   PN = "1"  !CDS_PN = "1";
"B":   PN = "2"  !CDS_PN = "2";
BODY = "Q_RES","I245": #LOCATION = "R1707" !CDS_LOCATION = "R1707" &SEC = "1" #&CDS_SEC = "1";
"A":   PN = "1"  !CDS_PN = "1";
"B":   PN = "2"  !CDS_PN = "2";
DRAWING = "@t6g_mb_lib.t6g(sch_1):page105";
BODY = "SCONN288_DDR506112002KQ","I22": #LOCATION = "J100" !CDS_LOCATION = "J100" &SEC = "1" #&CDS_SEC = "1";
"ALERT_N":   PN = "62"  !CDS_PN = "62";
"CA0_A":   PN = "66"  !CDS_PN = "66";
"CA0_B":   PN = "76"  !CDS_PN = "76";
"CA1_A":   PN = "211"  !CDS_PN = "211";
"CA1_B":   PN = "221"  !CDS_PN = "221";
"CA2_A":   PN = "68"  !CDS_PN = "68";
"CA2_B":   PN = "78"  !CDS_PN = "78";
"CA3_A":   PN = "213"  !CDS_PN = "213";
"CA3_B":   PN = "223"  !CDS_PN = "223";
"CA4_A":   PN = "70"  !CDS_PN = "70";
"CA4_B":   PN = "80"  !CDS_PN = "80";
"CA5_A":   PN = "215"  !CDS_PN = "215";
"CA5_B":   PN = "225"  !CDS_PN = "225";
"CA6_A":   PN = "72"  !CDS_PN = "72";
"CA6_B":   PN = "82"  !CDS_PN = "82";
"CB0_A":   PN = "51"  !CDS_PN = "51";
"CB0_B":   PN = "96"  !CDS_PN = "96";
"CB1_A":   PN = "53"  !CDS_PN = "53";
"CB1_B":   PN = "98"  !CDS_PN = "98";
"CB2_A":   PN = "196"  !CDS_PN = "196";
"CB2_B":   PN = "241"  !CDS_PN = "241";
"CB3_A":   PN = "198"  !CDS_PN = "198";
"CB3_B":   PN = "243"  !CDS_PN = "243";
"CB4_A":   PN = "58"  !CDS_PN = "58";
"CB4_B":   PN = "89"  !CDS_PN = "89";
"CB5_A":   PN = "60"  !CDS_PN = "60";
"CB5_B":   PN = "91"  !CDS_PN = "91";
"CB6_A":   PN = "203"  !CDS_PN = "203";
"CB6_B":   PN = "234"  !CDS_PN = "234";
"CB7_A":   PN = "205"  !CDS_PN = "205";
"CB7_B":   PN = "236"  !CDS_PN = "236";
"CK_C":   PN = "218"  !CDS_PN = "218";
"CK_T":   PN = "217"  !CDS_PN = "217";
"CS0_A_N":   PN = "64"  !CDS_PN = "64";
"CS0_B_N":   PN = "84"  !CDS_PN = "84";
"CS1_A_N":   PN = "209"  !CDS_PN = "209";
"CS1_B_N":   PN = "229"  !CDS_PN = "229";
"DQ0_A":   PN = "7"  !CDS_PN = "7";
"DQ0_B":   PN = "100"  !CDS_PN = "100";
"DQ1_A":   PN = "9"  !CDS_PN = "9";
"DQ1_B":   PN = "102"  !CDS_PN = "102";
"DQ2_A":   PN = "152"  !CDS_PN = "152";
"DQ2_B":   PN = "245"  !CDS_PN = "245";
"DQ3_A":   PN = "154"  !CDS_PN = "154";
"DQ3_B":   PN = "247"  !CDS_PN = "247";
"DQ4_A":   PN = "14"  !CDS_PN = "14";
"DQ4_B":   PN = "107"  !CDS_PN = "107";
"DQ5_A":   PN = "16"  !CDS_PN = "16";
"DQ5_B":   PN = "109"  !CDS_PN = "109";
"DQ6_A":   PN = "159"  !CDS_PN = "159";
"DQ6_B":   PN = "252"  !CDS_PN = "252";
"DQ7_A":   PN = "161"  !CDS_PN = "161";
"DQ7_B":   PN = "254"  !CDS_PN = "254";
"DQ8_A":   PN = "18"  !CDS_PN = "18";
"DQ8_B":   PN = "111"  !CDS_PN = "111";
"DQ9_A":   PN = "20"  !CDS_PN = "20";
"DQ9_B":   PN = "113"  !CDS_PN = "113";
"DQ10_A":   PN = "163"  !CDS_PN = "163";
"DQ10_B":   PN = "256"  !CDS_PN = "256";
"DQ11_A":   PN = "165"  !CDS_PN = "165";
"DQ11_B":   PN = "258"  !CDS_PN = "258";
"DQ12_A":   PN = "25"  !CDS_PN = "25";
"DQ12_B":   PN = "118"  !CDS_PN = "118";
"DQ13_A":   PN = "27"  !CDS_PN = "27";
"DQ13_B":   PN = "120"  !CDS_PN = "120";
"DQ14_A":   PN = "170"  !CDS_PN = "170";
"DQ14_B":   PN = "263"  !CDS_PN = "263";
"DQ15_A":   PN = "172"  !CDS_PN = "172";
"DQ15_B":   PN = "265"  !CDS_PN = "265";
"DQ16_A":   PN = "29"  !CDS_PN = "29";
"DQ16_B":   PN = "122"  !CDS_PN = "122";
"DQ17_A":   PN = "31"  !CDS_PN = "31";
"DQ17_B":   PN = "124"  !CDS_PN = "124";
"DQ18_A":   PN = "174"  !CDS_PN = "174";
"DQ18_B":   PN = "267"  !CDS_PN = "267";
"DQ19_A":   PN = "176"  !CDS_PN = "176";
"DQ19_B":   PN = "269"  !CDS_PN = "269";
"DQ20_A":   PN = "36"  !CDS_PN = "36";
"DQ20_B":   PN = "129"  !CDS_PN = "129";
"DQ21_A":   PN = "38"  !CDS_PN = "38";
"DQ21_B":   PN = "131"  !CDS_PN = "131";
"DQ22_A":   PN = "181"  !CDS_PN = "181";
"DQ22_B":   PN = "274"  !CDS_PN = "274";
"DQ23_A":   PN = "183"  !CDS_PN = "183";
"DQ23_B":   PN = "276"  !CDS_PN = "276";
"DQ24_A":   PN = "40"  !CDS_PN = "40";
"DQ24_B":   PN = "133"  !CDS_PN = "133";
"DQ25_A":   PN = "42"  !CDS_PN = "42";
"DQ25_B":   PN = "135"  !CDS_PN = "135";
"DQ26_A":   PN = "185"  !CDS_PN = "185";
"DQ26_B":   PN = "278"  !CDS_PN = "278";
"DQ27_A":   PN = "187"  !CDS_PN = "187";
"DQ27_B":   PN = "280"  !CDS_PN = "280";
"DQ28_A":   PN = "47"  !CDS_PN = "47";
"DQ28_B":   PN = "140"  !CDS_PN = "140";
"DQ29_A":   PN = "49"  !CDS_PN = "49";
"DQ29_B":   PN = "142"  !CDS_PN = "142";
"DQ30_A":   PN = "192"  !CDS_PN = "192";
"DQ30_B":   PN = "285"  !CDS_PN = "285";
"DQ31_A":   PN = "194"  !CDS_PN = "194";
"DQ31_B":   PN = "287"  !CDS_PN = "287";
"HAS":   PN = "148"  !CDS_PN = "148";
"HSCL":   PN = "4"  !CDS_PN = "4";
"HSDA":   PN = "5"  !CDS_PN = "5";
"LBD||RSP_A_N":   PN = "86"  !CDS_PN = "86";
"LBS||RSP_B_N":   PN = "87"  !CDS_PN = "87";
"PAR_A":   PN = "74"  !CDS_PN = "74";
"PAR_B":   PN = "227"  !CDS_PN = "227";
"PWR_GOOD||FAIL_N":   PN = "147"  !CDS_PN = "147";
"RESET_N":   PN = "207"  !CDS_PN = "207";
"RFU0":   PN = "2"  !CDS_PN = "2";
"RFU1":   PN = "144"  !CDS_PN = "144";
"RFU2":   PN = "149"  !CDS_PN = "149";
"RFU3":   PN = "150"  !CDS_PN = "150";
"RFU4":   PN = "220"  !CDS_PN = "220";
"RFU5":   PN = "231"  !CDS_PN = "231";
"RFU6":   PN = "232"  !CDS_PN = "232";
"VIN_MGMT":   PN = "3"  !CDS_PN = "3";
BODY = "Q_RES","I128": #LOCATION = "R775" !CDS_LOCATION = "R775" &SEC = "1" #&CDS_SEC = "1";
"A":   PN = "1"  !CDS_PN = "1";
"B":   PN = "2"  !CDS_PN = "2";
BODY = "SCONN288_DDR506112002KQ","I176": #LOCATION = "J100" !CDS_LOCATION = "J100" &SEC = "3" #&CDS_SEC = "3";
"G1":   PN = "G1"  !CDS_PN = "G1";
"G2":   PN = "G2"  !CDS_PN = "G2";
"G3":   PN = "G3"  !CDS_PN = "G3";
"VIN_BULK0":   PN = "1"  !CDS_PN = "1";
"VIN_BULK1":   PN = "145"  !CDS_PN = "145";
"VIN_BULK2":   PN = "146"  !CDS_PN = "146";
"VSS0":   PN = "6"  !CDS_PN = "6";
"VSS1":   PN = "8"  !CDS_PN = "8";
"VSS2":   PN = "10"  !CDS_PN = "10";
"VSS3":   PN = "13"  !CDS_PN = "13";
"VSS4":   PN = "15"  !CDS_PN = "15";
"VSS5":   PN = "17"  !CDS_PN = "17";
"VSS6":   PN = "19"  !CDS_PN = "19";
"VSS7":   PN = "21"  !CDS_PN = "21";
"VSS8":   PN = "24"  !CDS_PN = "24";
"VSS9":   PN = "26"  !CDS_PN = "26";
"VSS10":   PN = "28"  !CDS_PN = "28";
"VSS11":   PN = "30"  !CDS_PN = "30";
"VSS12":   PN = "32"  !CDS_PN = "32";
"VSS13":   PN = "35"  !CDS_PN = "35";
"VSS14":   PN = "37"  !CDS_PN = "37";
"VSS15":   PN = "39"  !CDS_PN = "39";
"VSS16":   PN = "41"  !CDS_PN = "41";
"VSS17":   PN = "43"  !CDS_PN = "43";
"VSS18":   PN = "46"  !CDS_PN = "46";
"VSS19":   PN = "48"  !CDS_PN = "48";
"VSS20":   PN = "50"  !CDS_PN = "50";
"VSS21":   PN = "52"  !CDS_PN = "52";
"VSS22":   PN = "54"  !CDS_PN = "54";
"VSS23":   PN = "57"  !CDS_PN = "57";
"VSS24":   PN = "59"  !CDS_PN = "59";
"VSS25":   PN = "61"  !CDS_PN = "61";
"VSS26":   PN = "63"  !CDS_PN = "63";
"VSS27":   PN = "65"  !CDS_PN = "65";
"VSS28":   PN = "67"  !CDS_PN = "67";
"VSS29":   PN = "69"  !CDS_PN = "69";
"VSS30":   PN = "71"  !CDS_PN = "71";
"VSS31":   PN = "73"  !CDS_PN = "73";
"VSS32":   PN = "75"  !CDS_PN = "75";
"VSS33":   PN = "77"  !CDS_PN = "77";
"VSS34":   PN = "79"  !CDS_PN = "79";
"VSS35":   PN = "81"  !CDS_PN = "81";
"VSS36":   PN = "83"  !CDS_PN = "83";
"VSS37":   PN = "85"  !CDS_PN = "85";
"VSS38":   PN = "88"  !CDS_PN = "88";
"VSS39":   PN = "90"  !CDS_PN = "90";
"VSS40":   PN = "92"  !CDS_PN = "92";
"VSS41":   PN = "95"  !CDS_PN = "95";
"VSS42":   PN = "97"  !CDS_PN = "97";
"VSS43":   PN = "99"  !CDS_PN = "99";
"VSS44":   PN = "101"  !CDS_PN = "101";
"VSS45":   PN = "103"  !CDS_PN = "103";
"VSS46":   PN = "106"  !CDS_PN = "106";
"VSS47":   PN = "108"  !CDS_PN = "108";
"VSS48":   PN = "110"  !CDS_PN = "110";
"VSS49":   PN = "112"  !CDS_PN = "112";
"VSS50":   PN = "114"  !CDS_PN = "114";
"VSS51":   PN = "117"  !CDS_PN = "117";
"VSS52":   PN = "119"  !CDS_PN = "119";
"VSS53":   PN = "121"  !CDS_PN = "121";
"VSS54":   PN = "123"  !CDS_PN = "123";
"VSS55":   PN = "125"  !CDS_PN = "125";
"VSS56":   PN = "128"  !CDS_PN = "128";
"VSS57":   PN = "130"  !CDS_PN = "130";
"VSS58":   PN = "132"  !CDS_PN = "132";
"VSS59":   PN = "134"  !CDS_PN = "134";
"VSS60":   PN = "136"  !CDS_PN = "136";
"VSS61":   PN = "139"  !CDS_PN = "139";
"VSS62":   PN = "141"  !CDS_PN = "141";
"VSS63":   PN = "143"  !CDS_PN = "143";
"VSS64":   PN = "151"  !CDS_PN = "151";
"VSS65":   PN = "153"  !CDS_PN = "153";
"VSS66":   PN = "155"  !CDS_PN = "155";
"VSS67":   PN = "158"  !CDS_PN = "158";
"VSS68":   PN = "160"  !CDS_PN = "160";
"VSS69":   PN = "162"  !CDS_PN = "162";
"VSS70":   PN = "164"  !CDS_PN = "164";
"VSS71":   PN = "166"  !CDS_PN = "166";
"VSS72":   PN = "169"  !CDS_PN = "169";
"VSS73":   PN = "171"  !CDS_PN = "171";
"VSS74":   PN = "173"  !CDS_PN = "173";
"VSS75":   PN = "175"  !CDS_PN = "175";
"VSS76":   PN = "177"  !CDS_PN = "177";
"VSS77":   PN = "180"  !CDS_PN = "180";
"VSS78":   PN = "182"  !CDS_PN = "182";
"VSS79":   PN = "184"  !CDS_PN = "184";
"VSS80":   PN = "186"  !CDS_PN = "186";
"VSS81":   PN = "188"  !CDS_PN = "188";
"VSS82":   PN = "191"  !CDS_PN = "191";
"VSS83":   PN = "193"  !CDS_PN = "193";
"VSS84":   PN = "195"  !CDS_PN = "195";
"VSS85":   PN = "197"  !CDS_PN = "197";
"VSS86":   PN = "199"  !CDS_PN = "199";
"VSS87":   PN = "202"  !CDS_PN = "202";
"VSS88":   PN = "204"  !CDS_PN = "204";
"VSS89":   PN = "206"  !CDS_PN = "206";
"VSS90":   PN = "208"  !CDS_PN = "208";
"VSS91":   PN = "210"  !CDS_PN = "210";
"VSS92":   PN = "212"  !CDS_PN = "212";
"VSS93":   PN = "214"  !CDS_PN = "214";
"VSS94":   PN = "216"  !CDS_PN = "216";
"VSS95":   PN = "219"  !CDS_PN = "219";
"VSS96":   PN = "222"  !CDS_PN = "222";
"VSS97":   PN = "224"  !CDS_PN = "224";
"VSS98":   PN = "226"  !CDS_PN = "226";
"VSS99":   PN = "228"  !CDS_PN = "228";
"VSS100":   PN = "230"  !CDS_PN = "230";
"VSS101":   PN = "233"  !CDS_PN = "233";
"VSS102":   PN = "235"  !CDS_PN = "235";
"VSS103":   PN = "237"  !CDS_PN = "237";
"VSS104":   PN = "240"  !CDS_PN = "240";
"VSS105":   PN = "242"  !CDS_PN = "242";
"VSS106":   PN = "244"  !CDS_PN = "244";
"VSS107":   PN = "246"  !CDS_PN = "246";
"VSS108":   PN = "248"  !CDS_PN = "248";
"VSS109":   PN = "251"  !CDS_PN = "251";
"VSS110":   PN = "253"  !CDS_PN = "253";
"VSS111":   PN = "255"  !CDS_PN = "255";
"VSS112":   PN = "257"  !CDS_PN = "257";
"VSS113":   PN = "259"  !CDS_PN = "259";
"VSS114":   PN = "262"  !CDS_PN = "262";
"VSS115":   PN = "264"  !CDS_PN = "264";
"VSS116":   PN = "266"  !CDS_PN = "266";
"VSS117":   PN = "268"  !CDS_PN = "268";
"VSS118":   PN = "270"  !CDS_PN = "270";
"VSS119":   PN = "273"  !CDS_PN = "273";
"VSS120":   PN = "275"  !CDS_PN = "275";
"VSS121":   PN = "277"  !CDS_PN = "277";
"VSS122":   PN = "279"  !CDS_PN = "279";
"VSS123":   PN = "281"  !CDS_PN = "281";
"VSS124":   PN = "284"  !CDS_PN = "284";
"VSS125":   PN = "286"  !CDS_PN = "286";
"VSS126":   PN = "288"  !CDS_PN = "288";
BODY = "Q_CAP","I185": #LOCATION = "C168" !CDS_LOCATION = "C168" &SEC = "1" #&CDS_SEC = "1";
"A":   PN = "1"  !CDS_PN = "1";
"B":   PN = "2"  !CDS_PN = "2";
BODY = "Q_RES","I188": #LOCATION = "R311" !CDS_LOCATION = "R311" &SEC = "1" #&CDS_SEC = "1";
"A":   PN = "1"  !CDS_PN = "1";
"B":   PN = "2"  !CDS_PN = "2";
BODY = "Q_RES","I190": #LOCATION = "R112" !CDS_LOCATION = "R112" &SEC = "1" #&CDS_SEC = "1";
"A":   PN = "1"  !CDS_PN = "1";
"B":   PN = "2"  !CDS_PN = "2";
BODY = "SCONN288_DDR506112002KQ","I236": #LOCATION = "J100" !CDS_LOCATION = "J100" &SEC = "2" #&CDS_SEC = "2";
"DQS0_A_C":   PN = "12"  !CDS_PN = "12";
"DQS0_A_T":   PN = "11"  !CDS_PN = "11";
"DQS0_B_C":   PN = "105"  !CDS_PN = "105";
"DQS0_B_T":   PN = "104"  !CDS_PN = "104";
"DQS1_A_C":   PN = "23"  !CDS_PN = "23";
"DQS1_A_T":   PN = "22"  !CDS_PN = "22";
"DQS1_B_C":   PN = "116"  !CDS_PN = "116";
"DQS1_B_T":   PN = "115"  !CDS_PN = "115";
"DQS2_A_C":   PN = "34"  !CDS_PN = "34";
"DQS2_A_T":   PN = "33"  !CDS_PN = "33";
"DQS2_B_C":   PN = "127"  !CDS_PN = "127";
"DQS2_B_T":   PN = "126"  !CDS_PN = "126";
"DQS3_A_C":   PN = "45"  !CDS_PN = "45";
"DQS3_A_T":   PN = "44"  !CDS_PN = "44";
"DQS3_B_C":   PN = "138"  !CDS_PN = "138";
"DQS3_B_T":   PN = "137"  !CDS_PN = "137";
"DQS4_A_C":   PN = "56"  !CDS_PN = "56";
"DQS4_A_T":   PN = "55"  !CDS_PN = "55";
"DQS4_B_C":   PN = "238"  !CDS_PN = "238";
"DQS4_B_T":   PN = "239"  !CDS_PN = "239";
"DQS5_A_C||TDQS5_A_C||DQS5_A_T||TDQS5_A_T":   PN = "156"  !CDS_PN = "156";
"DQS5_A_T||TDQS5_A_T":   PN = "157"  !CDS_PN = "157";
"DQS5_B_C||TDQS5_B_C":   PN = "249"  !CDS_PN = "249";
"DQS5_B_T||TDQS5_B_T":   PN = "250"  !CDS_PN = "250";
"DQS6_A_C||TDQS6_A_C||DQS6_A_T||TDQS6_A_T":   PN = "167"  !CDS_PN = "167";
"DQS6_A_T||TDQS6_A_T":   PN = "168"  !CDS_PN = "168";
"DQS6_B_C||TDQS6_B_C":   PN = "260"  !CDS_PN = "260";
"DQS6_B_T||TDQS6_B_T":   PN = "261"  !CDS_PN = "261";
"DQS7_A_C||TDQS7_A_C":   PN = "178"  !CDS_PN = "178";
"DQS7_A_T||TDQS7_A_T":   PN = "179"  !CDS_PN = "179";
"DQS7_B_C||TDQS7_B_C":   PN = "271"  !CDS_PN = "271";
"DQS7_B_T||TDQS7_B_T":   PN = "272"  !CDS_PN = "272";
"DQS8_A_C||TDQS8_A_C":   PN = "189"  !CDS_PN = "189";
"DQS8_A_T||TDQS8_A_T":   PN = "190"  !CDS_PN = "190";
"DQS8_B_C||TDQS8_B_C":   PN = "282"  !CDS_PN = "282";
"DQS8_B_T||TDQS8_B_T":   PN = "283"  !CDS_PN = "283";
"DQS9_A_C||TDQS9_A_C":   PN = "200"  !CDS_PN = "200";
"DQS9_A_T||TDQS9_A_T":   PN = "201"  !CDS_PN = "201";
"DQS9_B_C||TDQS9_B_C":   PN = "94"  !CDS_PN = "94";
"DQS9_B_T||TDQS9_B_T||DBI4_B_N":   PN = "93"  !CDS_PN = "93";
BODY = "Q_CAP","I238": #LOCATION = "C534" !CDS_LOCATION = "C534" &SEC = "1" #&CDS_SEC = "1";
"A":   PN = "1"  !CDS_PN = "1";
"B":   PN = "2"  !CDS_PN = "2";
BODY = "Q_CAP","I239": #LOCATION = "C535" !CDS_LOCATION = "C535" &SEC = "1" #&CDS_SEC = "1";
"A":   PN = "1"  !CDS_PN = "1";
"B":   PN = "2"  !CDS_PN = "2";
BODY = "Q_RES","I242": #LOCATION = "R1588" !CDS_LOCATION = "R1588" &SEC = "1" #&CDS_SEC = "1";
"A":   PN = "1"  !CDS_PN = "1";
"B":   PN = "2"  !CDS_PN = "2";
BODY = "Q_RES","I243": #LOCATION = "R1708" !CDS_LOCATION = "R1708" &SEC = "1" #&CDS_SEC = "1";
"A":   PN = "1"  !CDS_PN = "1";
"B":   PN = "2"  !CDS_PN = "2";
DRAWING = "@t6g_mb_lib.t6g(sch_1):page106";
BODY = "SCONN288_DDR506112002KQ","I22": #LOCATION = "J29" !CDS_LOCATION = "J29" &SEC = "1" #&CDS_SEC = "1";
"ALERT_N":   PN = "62"  !CDS_PN = "62";
"CA0_A":   PN = "66"  !CDS_PN = "66";
"CA0_B":   PN = "76"  !CDS_PN = "76";
"CA1_A":   PN = "211"  !CDS_PN = "211";
"CA1_B":   PN = "221"  !CDS_PN = "221";
"CA2_A":   PN = "68"  !CDS_PN = "68";
"CA2_B":   PN = "78"  !CDS_PN = "78";
"CA3_A":   PN = "213"  !CDS_PN = "213";
"CA3_B":   PN = "223"  !CDS_PN = "223";
"CA4_A":   PN = "70"  !CDS_PN = "70";
"CA4_B":   PN = "80"  !CDS_PN = "80";
"CA5_A":   PN = "215"  !CDS_PN = "215";
"CA5_B":   PN = "225"  !CDS_PN = "225";
"CA6_A":   PN = "72"  !CDS_PN = "72";
"CA6_B":   PN = "82"  !CDS_PN = "82";
"CB0_A":   PN = "51"  !CDS_PN = "51";
"CB0_B":   PN = "96"  !CDS_PN = "96";
"CB1_A":   PN = "53"  !CDS_PN = "53";
"CB1_B":   PN = "98"  !CDS_PN = "98";
"CB2_A":   PN = "196"  !CDS_PN = "196";
"CB2_B":   PN = "241"  !CDS_PN = "241";
"CB3_A":   PN = "198"  !CDS_PN = "198";
"CB3_B":   PN = "243"  !CDS_PN = "243";
"CB4_A":   PN = "58"  !CDS_PN = "58";
"CB4_B":   PN = "89"  !CDS_PN = "89";
"CB5_A":   PN = "60"  !CDS_PN = "60";
"CB5_B":   PN = "91"  !CDS_PN = "91";
"CB6_A":   PN = "203"  !CDS_PN = "203";
"CB6_B":   PN = "234"  !CDS_PN = "234";
"CB7_A":   PN = "205"  !CDS_PN = "205";
"CB7_B":   PN = "236"  !CDS_PN = "236";
"CK_C":   PN = "218"  !CDS_PN = "218";
"CK_T":   PN = "217"  !CDS_PN = "217";
"CS0_A_N":   PN = "64"  !CDS_PN = "64";
"CS0_B_N":   PN = "84"  !CDS_PN = "84";
"CS1_A_N":   PN = "209"  !CDS_PN = "209";
"CS1_B_N":   PN = "229"  !CDS_PN = "229";
"DQ0_A":   PN = "7"  !CDS_PN = "7";
"DQ0_B":   PN = "100"  !CDS_PN = "100";
"DQ1_A":   PN = "9"  !CDS_PN = "9";
"DQ1_B":   PN = "102"  !CDS_PN = "102";
"DQ2_A":   PN = "152"  !CDS_PN = "152";
"DQ2_B":   PN = "245"  !CDS_PN = "245";
"DQ3_A":   PN = "154"  !CDS_PN = "154";
"DQ3_B":   PN = "247"  !CDS_PN = "247";
"DQ4_A":   PN = "14"  !CDS_PN = "14";
"DQ4_B":   PN = "107"  !CDS_PN = "107";
"DQ5_A":   PN = "16"  !CDS_PN = "16";
"DQ5_B":   PN = "109"  !CDS_PN = "109";
"DQ6_A":   PN = "159"  !CDS_PN = "159";
"DQ6_B":   PN = "252"  !CDS_PN = "252";
"DQ7_A":   PN = "161"  !CDS_PN = "161";
"DQ7_B":   PN = "254"  !CDS_PN = "254";
"DQ8_A":   PN = "18"  !CDS_PN = "18";
"DQ8_B":   PN = "111"  !CDS_PN = "111";
"DQ9_A":   PN = "20"  !CDS_PN = "20";
"DQ9_B":   PN = "113"  !CDS_PN = "113";
"DQ10_A":   PN = "163"  !CDS_PN = "163";
"DQ10_B":   PN = "256"  !CDS_PN = "256";
"DQ11_A":   PN = "165"  !CDS_PN = "165";
"DQ11_B":   PN = "258"  !CDS_PN = "258";
"DQ12_A":   PN = "25"  !CDS_PN = "25";
"DQ12_B":   PN = "118"  !CDS_PN = "118";
"DQ13_A":   PN = "27"  !CDS_PN = "27";
"DQ13_B":   PN = "120"  !CDS_PN = "120";
"DQ14_A":   PN = "170"  !CDS_PN = "170";
"DQ14_B":   PN = "263"  !CDS_PN = "263";
"DQ15_A":   PN = "172"  !CDS_PN = "172";
"DQ15_B":   PN = "265"  !CDS_PN = "265";
"DQ16_A":   PN = "29"  !CDS_PN = "29";
"DQ16_B":   PN = "122"  !CDS_PN = "122";
"DQ17_A":   PN = "31"  !CDS_PN = "31";
"DQ17_B":   PN = "124"  !CDS_PN = "124";
"DQ18_A":   PN = "174"  !CDS_PN = "174";
"DQ18_B":   PN = "267"  !CDS_PN = "267";
"DQ19_A":   PN = "176"  !CDS_PN = "176";
"DQ19_B":   PN = "269"  !CDS_PN = "269";
"DQ20_A":   PN = "36"  !CDS_PN = "36";
"DQ20_B":   PN = "129"  !CDS_PN = "129";
"DQ21_A":   PN = "38"  !CDS_PN = "38";
"DQ21_B":   PN = "131"  !CDS_PN = "131";
"DQ22_A":   PN = "181"  !CDS_PN = "181";
"DQ22_B":   PN = "274"  !CDS_PN = "274";
"DQ23_A":   PN = "183"  !CDS_PN = "183";
"DQ23_B":   PN = "276"  !CDS_PN = "276";
"DQ24_A":   PN = "40"  !CDS_PN = "40";
"DQ24_B":   PN = "133"  !CDS_PN = "133";
"DQ25_A":   PN = "42"  !CDS_PN = "42";
"DQ25_B":   PN = "135"  !CDS_PN = "135";
"DQ26_A":   PN = "185"  !CDS_PN = "185";
"DQ26_B":   PN = "278"  !CDS_PN = "278";
"DQ27_A":   PN = "187"  !CDS_PN = "187";
"DQ27_B":   PN = "280"  !CDS_PN = "280";
"DQ28_A":   PN = "47"  !CDS_PN = "47";
"DQ28_B":   PN = "140"  !CDS_PN = "140";
"DQ29_A":   PN = "49"  !CDS_PN = "49";
"DQ29_B":   PN = "142"  !CDS_PN = "142";
"DQ30_A":   PN = "192"  !CDS_PN = "192";
"DQ30_B":   PN = "285"  !CDS_PN = "285";
"DQ31_A":   PN = "194"  !CDS_PN = "194";
"DQ31_B":   PN = "287"  !CDS_PN = "287";
"HAS":   PN = "148"  !CDS_PN = "148";
"HSCL":   PN = "4"  !CDS_PN = "4";
"HSDA":   PN = "5"  !CDS_PN = "5";
"LBD||RSP_A_N":   PN = "86"  !CDS_PN = "86";
"LBS||RSP_B_N":   PN = "87"  !CDS_PN = "87";
"PAR_A":   PN = "74"  !CDS_PN = "74";
"PAR_B":   PN = "227"  !CDS_PN = "227";
"PWR_GOOD||FAIL_N":   PN = "147"  !CDS_PN = "147";
"RESET_N":   PN = "207"  !CDS_PN = "207";
"RFU0":   PN = "2"  !CDS_PN = "2";
"RFU1":   PN = "144"  !CDS_PN = "144";
"RFU2":   PN = "149"  !CDS_PN = "149";
"RFU3":   PN = "150"  !CDS_PN = "150";
"RFU4":   PN = "220"  !CDS_PN = "220";
"RFU5":   PN = "231"  !CDS_PN = "231";
"RFU6":   PN = "232"  !CDS_PN = "232";
"VIN_MGMT":   PN = "3"  !CDS_PN = "3";
BODY = "Q_RES","I127": #LOCATION = "R776" !CDS_LOCATION = "R776" &SEC = "1" #&CDS_SEC = "1";
"A":   PN = "1"  !CDS_PN = "1";
"B":   PN = "2"  !CDS_PN = "2";
BODY = "SCONN288_DDR506112002KQ","I143": #LOCATION = "J29" !CDS_LOCATION = "J29" &SEC = "3" #&CDS_SEC = "3";
"G1":   PN = "G1"  !CDS_PN = "G1";
"G2":   PN = "G2"  !CDS_PN = "G2";
"G3":   PN = "G3"  !CDS_PN = "G3";
"VIN_BULK0":   PN = "1"  !CDS_PN = "1";
"VIN_BULK1":   PN = "145"  !CDS_PN = "145";
"VIN_BULK2":   PN = "146"  !CDS_PN = "146";
"VSS0":   PN = "6"  !CDS_PN = "6";
"VSS1":   PN = "8"  !CDS_PN = "8";
"VSS2":   PN = "10"  !CDS_PN = "10";
"VSS3":   PN = "13"  !CDS_PN = "13";
"VSS4":   PN = "15"  !CDS_PN = "15";
"VSS5":   PN = "17"  !CDS_PN = "17";
"VSS6":   PN = "19"  !CDS_PN = "19";
"VSS7":   PN = "21"  !CDS_PN = "21";
"VSS8":   PN = "24"  !CDS_PN = "24";
"VSS9":   PN = "26"  !CDS_PN = "26";
"VSS10":   PN = "28"  !CDS_PN = "28";
"VSS11":   PN = "30"  !CDS_PN = "30";
"VSS12":   PN = "32"  !CDS_PN = "32";
"VSS13":   PN = "35"  !CDS_PN = "35";
"VSS14":   PN = "37"  !CDS_PN = "37";
"VSS15":   PN = "39"  !CDS_PN = "39";
"VSS16":   PN = "41"  !CDS_PN = "41";
"VSS17":   PN = "43"  !CDS_PN = "43";
"VSS18":   PN = "46"  !CDS_PN = "46";
"VSS19":   PN = "48"  !CDS_PN = "48";
"VSS20":   PN = "50"  !CDS_PN = "50";
"VSS21":   PN = "52"  !CDS_PN = "52";
"VSS22":   PN = "54"  !CDS_PN = "54";
"VSS23":   PN = "57"  !CDS_PN = "57";
"VSS24":   PN = "59"  !CDS_PN = "59";
"VSS25":   PN = "61"  !CDS_PN = "61";
"VSS26":   PN = "63"  !CDS_PN = "63";
"VSS27":   PN = "65"  !CDS_PN = "65";
"VSS28":   PN = "67"  !CDS_PN = "67";
"VSS29":   PN = "69"  !CDS_PN = "69";
"VSS30":   PN = "71"  !CDS_PN = "71";
"VSS31":   PN = "73"  !CDS_PN = "73";
"VSS32":   PN = "75"  !CDS_PN = "75";
"VSS33":   PN = "77"  !CDS_PN = "77";
"VSS34":   PN = "79"  !CDS_PN = "79";
"VSS35":   PN = "81"  !CDS_PN = "81";
"VSS36":   PN = "83"  !CDS_PN = "83";
"VSS37":   PN = "85"  !CDS_PN = "85";
"VSS38":   PN = "88"  !CDS_PN = "88";
"VSS39":   PN = "90"  !CDS_PN = "90";
"VSS40":   PN = "92"  !CDS_PN = "92";
"VSS41":   PN = "95"  !CDS_PN = "95";
"VSS42":   PN = "97"  !CDS_PN = "97";
"VSS43":   PN = "99"  !CDS_PN = "99";
"VSS44":   PN = "101"  !CDS_PN = "101";
"VSS45":   PN = "103"  !CDS_PN = "103";
"VSS46":   PN = "106"  !CDS_PN = "106";
"VSS47":   PN = "108"  !CDS_PN = "108";
"VSS48":   PN = "110"  !CDS_PN = "110";
"VSS49":   PN = "112"  !CDS_PN = "112";
"VSS50":   PN = "114"  !CDS_PN = "114";
"VSS51":   PN = "117"  !CDS_PN = "117";
"VSS52":   PN = "119"  !CDS_PN = "119";
"VSS53":   PN = "121"  !CDS_PN = "121";
"VSS54":   PN = "123"  !CDS_PN = "123";
"VSS55":   PN = "125"  !CDS_PN = "125";
"VSS56":   PN = "128"  !CDS_PN = "128";
"VSS57":   PN = "130"  !CDS_PN = "130";
"VSS58":   PN = "132"  !CDS_PN = "132";
"VSS59":   PN = "134"  !CDS_PN = "134";
"VSS60":   PN = "136"  !CDS_PN = "136";
"VSS61":   PN = "139"  !CDS_PN = "139";
"VSS62":   PN = "141"  !CDS_PN = "141";
"VSS63":   PN = "143"  !CDS_PN = "143";
"VSS64":   PN = "151"  !CDS_PN = "151";
"VSS65":   PN = "153"  !CDS_PN = "153";
"VSS66":   PN = "155"  !CDS_PN = "155";
"VSS67":   PN = "158"  !CDS_PN = "158";
"VSS68":   PN = "160"  !CDS_PN = "160";
"VSS69":   PN = "162"  !CDS_PN = "162";
"VSS70":   PN = "164"  !CDS_PN = "164";
"VSS71":   PN = "166"  !CDS_PN = "166";
"VSS72":   PN = "169"  !CDS_PN = "169";
"VSS73":   PN = "171"  !CDS_PN = "171";
"VSS74":   PN = "173"  !CDS_PN = "173";
"VSS75":   PN = "175"  !CDS_PN = "175";
"VSS76":   PN = "177"  !CDS_PN = "177";
"VSS77":   PN = "180"  !CDS_PN = "180";
"VSS78":   PN = "182"  !CDS_PN = "182";
"VSS79":   PN = "184"  !CDS_PN = "184";
"VSS80":   PN = "186"  !CDS_PN = "186";
"VSS81":   PN = "188"  !CDS_PN = "188";
"VSS82":   PN = "191"  !CDS_PN = "191";
"VSS83":   PN = "193"  !CDS_PN = "193";
"VSS84":   PN = "195"  !CDS_PN = "195";
"VSS85":   PN = "197"  !CDS_PN = "197";
"VSS86":   PN = "199"  !CDS_PN = "199";
"VSS87":   PN = "202"  !CDS_PN = "202";
"VSS88":   PN = "204"  !CDS_PN = "204";
"VSS89":   PN = "206"  !CDS_PN = "206";
"VSS90":   PN = "208"  !CDS_PN = "208";
"VSS91":   PN = "210"  !CDS_PN = "210";
"VSS92":   PN = "212"  !CDS_PN = "212";
"VSS93":   PN = "214"  !CDS_PN = "214";
"VSS94":   PN = "216"  !CDS_PN = "216";
"VSS95":   PN = "219"  !CDS_PN = "219";
"VSS96":   PN = "222"  !CDS_PN = "222";
"VSS97":   PN = "224"  !CDS_PN = "224";
"VSS98":   PN = "226"  !CDS_PN = "226";
"VSS99":   PN = "228"  !CDS_PN = "228";
"VSS100":   PN = "230"  !CDS_PN = "230";
"VSS101":   PN = "233"  !CDS_PN = "233";
"VSS102":   PN = "235"  !CDS_PN = "235";
"VSS103":   PN = "237"  !CDS_PN = "237";
"VSS104":   PN = "240"  !CDS_PN = "240";
"VSS105":   PN = "242"  !CDS_PN = "242";
"VSS106":   PN = "244"  !CDS_PN = "244";
"VSS107":   PN = "246"  !CDS_PN = "246";
"VSS108":   PN = "248"  !CDS_PN = "248";
"VSS109":   PN = "251"  !CDS_PN = "251";
"VSS110":   PN = "253"  !CDS_PN = "253";
"VSS111":   PN = "255"  !CDS_PN = "255";
"VSS112":   PN = "257"  !CDS_PN = "257";
"VSS113":   PN = "259"  !CDS_PN = "259";
"VSS114":   PN = "262"  !CDS_PN = "262";
"VSS115":   PN = "264"  !CDS_PN = "264";
"VSS116":   PN = "266"  !CDS_PN = "266";
"VSS117":   PN = "268"  !CDS_PN = "268";
"VSS118":   PN = "270"  !CDS_PN = "270";
"VSS119":   PN = "273"  !CDS_PN = "273";
"VSS120":   PN = "275"  !CDS_PN = "275";
"VSS121":   PN = "277"  !CDS_PN = "277";
"VSS122":   PN = "279"  !CDS_PN = "279";
"VSS123":   PN = "281"  !CDS_PN = "281";
"VSS124":   PN = "284"  !CDS_PN = "284";
"VSS125":   PN = "286"  !CDS_PN = "286";
"VSS126":   PN = "288"  !CDS_PN = "288";
BODY = "Q_CAP","I185": #LOCATION = "C172" !CDS_LOCATION = "C172" &SEC = "1" #&CDS_SEC = "1";
"A":   PN = "1"  !CDS_PN = "1";
"B":   PN = "2"  !CDS_PN = "2";
BODY = "Q_RES","I188": #LOCATION = "R312" !CDS_LOCATION = "R312" &SEC = "1" #&CDS_SEC = "1";
"A":   PN = "1"  !CDS_PN = "1";
"B":   PN = "2"  !CDS_PN = "2";
BODY = "Q_RES","I190": #LOCATION = "R113" !CDS_LOCATION = "R113" &SEC = "1" #&CDS_SEC = "1";
"A":   PN = "1"  !CDS_PN = "1";
"B":   PN = "2"  !CDS_PN = "2";
BODY = "SCONN288_DDR506112002KQ","I236": #LOCATION = "J29" !CDS_LOCATION = "J29" &SEC = "2" #&CDS_SEC = "2";
"DQS0_A_C":   PN = "12"  !CDS_PN = "12";
"DQS0_A_T":   PN = "11"  !CDS_PN = "11";
"DQS0_B_C":   PN = "105"  !CDS_PN = "105";
"DQS0_B_T":   PN = "104"  !CDS_PN = "104";
"DQS1_A_C":   PN = "23"  !CDS_PN = "23";
"DQS1_A_T":   PN = "22"  !CDS_PN = "22";
"DQS1_B_C":   PN = "116"  !CDS_PN = "116";
"DQS1_B_T":   PN = "115"  !CDS_PN = "115";
"DQS2_A_C":   PN = "34"  !CDS_PN = "34";
"DQS2_A_T":   PN = "33"  !CDS_PN = "33";
"DQS2_B_C":   PN = "127"  !CDS_PN = "127";
"DQS2_B_T":   PN = "126"  !CDS_PN = "126";
"DQS3_A_C":   PN = "45"  !CDS_PN = "45";
"DQS3_A_T":   PN = "44"  !CDS_PN = "44";
"DQS3_B_C":   PN = "138"  !CDS_PN = "138";
"DQS3_B_T":   PN = "137"  !CDS_PN = "137";
"DQS4_A_C":   PN = "56"  !CDS_PN = "56";
"DQS4_A_T":   PN = "55"  !CDS_PN = "55";
"DQS4_B_C":   PN = "238"  !CDS_PN = "238";
"DQS4_B_T":   PN = "239"  !CDS_PN = "239";
"DQS5_A_C||TDQS5_A_C||DQS5_A_T||TDQS5_A_T":   PN = "156"  !CDS_PN = "156";
"DQS5_A_T||TDQS5_A_T":   PN = "157"  !CDS_PN = "157";
"DQS5_B_C||TDQS5_B_C":   PN = "249"  !CDS_PN = "249";
"DQS5_B_T||TDQS5_B_T":   PN = "250"  !CDS_PN = "250";
"DQS6_A_C||TDQS6_A_C||DQS6_A_T||TDQS6_A_T":   PN = "167"  !CDS_PN = "167";
"DQS6_A_T||TDQS6_A_T":   PN = "168"  !CDS_PN = "168";
"DQS6_B_C||TDQS6_B_C":   PN = "260"  !CDS_PN = "260";
"DQS6_B_T||TDQS6_B_T":   PN = "261"  !CDS_PN = "261";
"DQS7_A_C||TDQS7_A_C":   PN = "178"  !CDS_PN = "178";
"DQS7_A_T||TDQS7_A_T":   PN = "179"  !CDS_PN = "179";
"DQS7_B_C||TDQS7_B_C":   PN = "271"  !CDS_PN = "271";
"DQS7_B_T||TDQS7_B_T":   PN = "272"  !CDS_PN = "272";
"DQS8_A_C||TDQS8_A_C":   PN = "189"  !CDS_PN = "189";
"DQS8_A_T||TDQS8_A_T":   PN = "190"  !CDS_PN = "190";
"DQS8_B_C||TDQS8_B_C":   PN = "282"  !CDS_PN = "282";
"DQS8_B_T||TDQS8_B_T":   PN = "283"  !CDS_PN = "283";
"DQS9_A_C||TDQS9_A_C":   PN = "200"  !CDS_PN = "200";
"DQS9_A_T||TDQS9_A_T":   PN = "201"  !CDS_PN = "201";
"DQS9_B_C||TDQS9_B_C":   PN = "94"  !CDS_PN = "94";
"DQS9_B_T||TDQS9_B_T||DBI4_B_N":   PN = "93"  !CDS_PN = "93";
BODY = "Q_CAP","I238": #LOCATION = "C536" !CDS_LOCATION = "C536" &SEC = "1" #&CDS_SEC = "1";
"A":   PN = "1"  !CDS_PN = "1";
"B":   PN = "2"  !CDS_PN = "2";
BODY = "Q_CAP","I239": #LOCATION = "C537" !CDS_LOCATION = "C537" &SEC = "1" #&CDS_SEC = "1";
"A":   PN = "1"  !CDS_PN = "1";
"B":   PN = "2"  !CDS_PN = "2";
BODY = "Q_RES","I242": #LOCATION = "R1589" !CDS_LOCATION = "R1589" &SEC = "1" #&CDS_SEC = "1";
"A":   PN = "1"  !CDS_PN = "1";
"B":   PN = "2"  !CDS_PN = "2";
BODY = "Q_RES","I243": #LOCATION = "R1709" !CDS_LOCATION = "R1709" &SEC = "1" #&CDS_SEC = "1";
"A":   PN = "1"  !CDS_PN = "1";
"B":   PN = "2"  !CDS_PN = "2";
DRAWING = "@t6g_mb_lib.t6g(sch_1):page107";
BODY = "SCONN288_DDR506112002KQ","I22": #LOCATION = "J99" !CDS_LOCATION = "J99" &SEC = "1" #&CDS_SEC = "1";
"ALERT_N":   PN = "62"  !CDS_PN = "62";
"CA0_A":   PN = "66"  !CDS_PN = "66";
"CA0_B":   PN = "76"  !CDS_PN = "76";
"CA1_A":   PN = "211"  !CDS_PN = "211";
"CA1_B":   PN = "221"  !CDS_PN = "221";
"CA2_A":   PN = "68"  !CDS_PN = "68";
"CA2_B":   PN = "78"  !CDS_PN = "78";
"CA3_A":   PN = "213"  !CDS_PN = "213";
"CA3_B":   PN = "223"  !CDS_PN = "223";
"CA4_A":   PN = "70"  !CDS_PN = "70";
"CA4_B":   PN = "80"  !CDS_PN = "80";
"CA5_A":   PN = "215"  !CDS_PN = "215";
"CA5_B":   PN = "225"  !CDS_PN = "225";
"CA6_A":   PN = "72"  !CDS_PN = "72";
"CA6_B":   PN = "82"  !CDS_PN = "82";
"CB0_A":   PN = "51"  !CDS_PN = "51";
"CB0_B":   PN = "96"  !CDS_PN = "96";
"CB1_A":   PN = "53"  !CDS_PN = "53";
"CB1_B":   PN = "98"  !CDS_PN = "98";
"CB2_A":   PN = "196"  !CDS_PN = "196";
"CB2_B":   PN = "241"  !CDS_PN = "241";
"CB3_A":   PN = "198"  !CDS_PN = "198";
"CB3_B":   PN = "243"  !CDS_PN = "243";
"CB4_A":   PN = "58"  !CDS_PN = "58";
"CB4_B":   PN = "89"  !CDS_PN = "89";
"CB5_A":   PN = "60"  !CDS_PN = "60";
"CB5_B":   PN = "91"  !CDS_PN = "91";
"CB6_A":   PN = "203"  !CDS_PN = "203";
"CB6_B":   PN = "234"  !CDS_PN = "234";
"CB7_A":   PN = "205"  !CDS_PN = "205";
"CB7_B":   PN = "236"  !CDS_PN = "236";
"CK_C":   PN = "218"  !CDS_PN = "218";
"CK_T":   PN = "217"  !CDS_PN = "217";
"CS0_A_N":   PN = "64"  !CDS_PN = "64";
"CS0_B_N":   PN = "84"  !CDS_PN = "84";
"CS1_A_N":   PN = "209"  !CDS_PN = "209";
"CS1_B_N":   PN = "229"  !CDS_PN = "229";
"DQ0_A":   PN = "7"  !CDS_PN = "7";
"DQ0_B":   PN = "100"  !CDS_PN = "100";
"DQ1_A":   PN = "9"  !CDS_PN = "9";
"DQ1_B":   PN = "102"  !CDS_PN = "102";
"DQ2_A":   PN = "152"  !CDS_PN = "152";
"DQ2_B":   PN = "245"  !CDS_PN = "245";
"DQ3_A":   PN = "154"  !CDS_PN = "154";
"DQ3_B":   PN = "247"  !CDS_PN = "247";
"DQ4_A":   PN = "14"  !CDS_PN = "14";
"DQ4_B":   PN = "107"  !CDS_PN = "107";
"DQ5_A":   PN = "16"  !CDS_PN = "16";
"DQ5_B":   PN = "109"  !CDS_PN = "109";
"DQ6_A":   PN = "159"  !CDS_PN = "159";
"DQ6_B":   PN = "252"  !CDS_PN = "252";
"DQ7_A":   PN = "161"  !CDS_PN = "161";
"DQ7_B":   PN = "254"  !CDS_PN = "254";
"DQ8_A":   PN = "18"  !CDS_PN = "18";
"DQ8_B":   PN = "111"  !CDS_PN = "111";
"DQ9_A":   PN = "20"  !CDS_PN = "20";
"DQ9_B":   PN = "113"  !CDS_PN = "113";
"DQ10_A":   PN = "163"  !CDS_PN = "163";
"DQ10_B":   PN = "256"  !CDS_PN = "256";
"DQ11_A":   PN = "165"  !CDS_PN = "165";
"DQ11_B":   PN = "258"  !CDS_PN = "258";
"DQ12_A":   PN = "25"  !CDS_PN = "25";
"DQ12_B":   PN = "118"  !CDS_PN = "118";
"DQ13_A":   PN = "27"  !CDS_PN = "27";
"DQ13_B":   PN = "120"  !CDS_PN = "120";
"DQ14_A":   PN = "170"  !CDS_PN = "170";
"DQ14_B":   PN = "263"  !CDS_PN = "263";
"DQ15_A":   PN = "172"  !CDS_PN = "172";
"DQ15_B":   PN = "265"  !CDS_PN = "265";
"DQ16_A":   PN = "29"  !CDS_PN = "29";
"DQ16_B":   PN = "122"  !CDS_PN = "122";
"DQ17_A":   PN = "31"  !CDS_PN = "31";
"DQ17_B":   PN = "124"  !CDS_PN = "124";
"DQ18_A":   PN = "174"  !CDS_PN = "174";
"DQ18_B":   PN = "267"  !CDS_PN = "267";
"DQ19_A":   PN = "176"  !CDS_PN = "176";
"DQ19_B":   PN = "269"  !CDS_PN = "269";
"DQ20_A":   PN = "36"  !CDS_PN = "36";
"DQ20_B":   PN = "129"  !CDS_PN = "129";
"DQ21_A":   PN = "38"  !CDS_PN = "38";
"DQ21_B":   PN = "131"  !CDS_PN = "131";
"DQ22_A":   PN = "181"  !CDS_PN = "181";
"DQ22_B":   PN = "274"  !CDS_PN = "274";
"DQ23_A":   PN = "183"  !CDS_PN = "183";
"DQ23_B":   PN = "276"  !CDS_PN = "276";
"DQ24_A":   PN = "40"  !CDS_PN = "40";
"DQ24_B":   PN = "133"  !CDS_PN = "133";
"DQ25_A":   PN = "42"  !CDS_PN = "42";
"DQ25_B":   PN = "135"  !CDS_PN = "135";
"DQ26_A":   PN = "185"  !CDS_PN = "185";
"DQ26_B":   PN = "278"  !CDS_PN = "278";
"DQ27_A":   PN = "187"  !CDS_PN = "187";
"DQ27_B":   PN = "280"  !CDS_PN = "280";
"DQ28_A":   PN = "47"  !CDS_PN = "47";
"DQ28_B":   PN = "140"  !CDS_PN = "140";
"DQ29_A":   PN = "49"  !CDS_PN = "49";
"DQ29_B":   PN = "142"  !CDS_PN = "142";
"DQ30_A":   PN = "192"  !CDS_PN = "192";
"DQ30_B":   PN = "285"  !CDS_PN = "285";
"DQ31_A":   PN = "194"  !CDS_PN = "194";
"DQ31_B":   PN = "287"  !CDS_PN = "287";
"HAS":   PN = "148"  !CDS_PN = "148";
"HSCL":   PN = "4"  !CDS_PN = "4";
"HSDA":   PN = "5"  !CDS_PN = "5";
"LBD||RSP_A_N":   PN = "86"  !CDS_PN = "86";
"LBS||RSP_B_N":   PN = "87"  !CDS_PN = "87";
"PAR_A":   PN = "74"  !CDS_PN = "74";
"PAR_B":   PN = "227"  !CDS_PN = "227";
"PWR_GOOD||FAIL_N":   PN = "147"  !CDS_PN = "147";
"RESET_N":   PN = "207"  !CDS_PN = "207";
"RFU0":   PN = "2"  !CDS_PN = "2";
"RFU1":   PN = "144"  !CDS_PN = "144";
"RFU2":   PN = "149"  !CDS_PN = "149";
"RFU3":   PN = "150"  !CDS_PN = "150";
"RFU4":   PN = "220"  !CDS_PN = "220";
"RFU5":   PN = "231"  !CDS_PN = "231";
"RFU6":   PN = "232"  !CDS_PN = "232";
"VIN_MGMT":   PN = "3"  !CDS_PN = "3";
BODY = "Q_RES","I136": #LOCATION = "R777" !CDS_LOCATION = "R777" &SEC = "1" #&CDS_SEC = "1";
"A":   PN = "1"  !CDS_PN = "1";
"B":   PN = "2"  !CDS_PN = "2";
BODY = "SCONN288_DDR506112002KQ","I139": #LOCATION = "J99" !CDS_LOCATION = "J99" &SEC = "3" #&CDS_SEC = "3";
"G1":   PN = "G1"  !CDS_PN = "G1";
"G2":   PN = "G2"  !CDS_PN = "G2";
"G3":   PN = "G3"  !CDS_PN = "G3";
"VIN_BULK0":   PN = "1"  !CDS_PN = "1";
"VIN_BULK1":   PN = "145"  !CDS_PN = "145";
"VIN_BULK2":   PN = "146"  !CDS_PN = "146";
"VSS0":   PN = "6"  !CDS_PN = "6";
"VSS1":   PN = "8"  !CDS_PN = "8";
"VSS2":   PN = "10"  !CDS_PN = "10";
"VSS3":   PN = "13"  !CDS_PN = "13";
"VSS4":   PN = "15"  !CDS_PN = "15";
"VSS5":   PN = "17"  !CDS_PN = "17";
"VSS6":   PN = "19"  !CDS_PN = "19";
"VSS7":   PN = "21"  !CDS_PN = "21";
"VSS8":   PN = "24"  !CDS_PN = "24";
"VSS9":   PN = "26"  !CDS_PN = "26";
"VSS10":   PN = "28"  !CDS_PN = "28";
"VSS11":   PN = "30"  !CDS_PN = "30";
"VSS12":   PN = "32"  !CDS_PN = "32";
"VSS13":   PN = "35"  !CDS_PN = "35";
"VSS14":   PN = "37"  !CDS_PN = "37";
"VSS15":   PN = "39"  !CDS_PN = "39";
"VSS16":   PN = "41"  !CDS_PN = "41";
"VSS17":   PN = "43"  !CDS_PN = "43";
"VSS18":   PN = "46"  !CDS_PN = "46";
"VSS19":   PN = "48"  !CDS_PN = "48";
"VSS20":   PN = "50"  !CDS_PN = "50";
"VSS21":   PN = "52"  !CDS_PN = "52";
"VSS22":   PN = "54"  !CDS_PN = "54";
"VSS23":   PN = "57"  !CDS_PN = "57";
"VSS24":   PN = "59"  !CDS_PN = "59";
"VSS25":   PN = "61"  !CDS_PN = "61";
"VSS26":   PN = "63"  !CDS_PN = "63";
"VSS27":   PN = "65"  !CDS_PN = "65";
"VSS28":   PN = "67"  !CDS_PN = "67";
"VSS29":   PN = "69"  !CDS_PN = "69";
"VSS30":   PN = "71"  !CDS_PN = "71";
"VSS31":   PN = "73"  !CDS_PN = "73";
"VSS32":   PN = "75"  !CDS_PN = "75";
"VSS33":   PN = "77"  !CDS_PN = "77";
"VSS34":   PN = "79"  !CDS_PN = "79";
"VSS35":   PN = "81"  !CDS_PN = "81";
"VSS36":   PN = "83"  !CDS_PN = "83";
"VSS37":   PN = "85"  !CDS_PN = "85";
"VSS38":   PN = "88"  !CDS_PN = "88";
"VSS39":   PN = "90"  !CDS_PN = "90";
"VSS40":   PN = "92"  !CDS_PN = "92";
"VSS41":   PN = "95"  !CDS_PN = "95";
"VSS42":   PN = "97"  !CDS_PN = "97";
"VSS43":   PN = "99"  !CDS_PN = "99";
"VSS44":   PN = "101"  !CDS_PN = "101";
"VSS45":   PN = "103"  !CDS_PN = "103";
"VSS46":   PN = "106"  !CDS_PN = "106";
"VSS47":   PN = "108"  !CDS_PN = "108";
"VSS48":   PN = "110"  !CDS_PN = "110";
"VSS49":   PN = "112"  !CDS_PN = "112";
"VSS50":   PN = "114"  !CDS_PN = "114";
"VSS51":   PN = "117"  !CDS_PN = "117";
"VSS52":   PN = "119"  !CDS_PN = "119";
"VSS53":   PN = "121"  !CDS_PN = "121";
"VSS54":   PN = "123"  !CDS_PN = "123";
"VSS55":   PN = "125"  !CDS_PN = "125";
"VSS56":   PN = "128"  !CDS_PN = "128";
"VSS57":   PN = "130"  !CDS_PN = "130";
"VSS58":   PN = "132"  !CDS_PN = "132";
"VSS59":   PN = "134"  !CDS_PN = "134";
"VSS60":   PN = "136"  !CDS_PN = "136";
"VSS61":   PN = "139"  !CDS_PN = "139";
"VSS62":   PN = "141"  !CDS_PN = "141";
"VSS63":   PN = "143"  !CDS_PN = "143";
"VSS64":   PN = "151"  !CDS_PN = "151";
"VSS65":   PN = "153"  !CDS_PN = "153";
"VSS66":   PN = "155"  !CDS_PN = "155";
"VSS67":   PN = "158"  !CDS_PN = "158";
"VSS68":   PN = "160"  !CDS_PN = "160";
"VSS69":   PN = "162"  !CDS_PN = "162";
"VSS70":   PN = "164"  !CDS_PN = "164";
"VSS71":   PN = "166"  !CDS_PN = "166";
"VSS72":   PN = "169"  !CDS_PN = "169";
"VSS73":   PN = "171"  !CDS_PN = "171";
"VSS74":   PN = "173"  !CDS_PN = "173";
"VSS75":   PN = "175"  !CDS_PN = "175";
"VSS76":   PN = "177"  !CDS_PN = "177";
"VSS77":   PN = "180"  !CDS_PN = "180";
"VSS78":   PN = "182"  !CDS_PN = "182";
"VSS79":   PN = "184"  !CDS_PN = "184";
"VSS80":   PN = "186"  !CDS_PN = "186";
"VSS81":   PN = "188"  !CDS_PN = "188";
"VSS82":   PN = "191"  !CDS_PN = "191";
"VSS83":   PN = "193"  !CDS_PN = "193";
"VSS84":   PN = "195"  !CDS_PN = "195";
"VSS85":   PN = "197"  !CDS_PN = "197";
"VSS86":   PN = "199"  !CDS_PN = "199";
"VSS87":   PN = "202"  !CDS_PN = "202";
"VSS88":   PN = "204"  !CDS_PN = "204";
"VSS89":   PN = "206"  !CDS_PN = "206";
"VSS90":   PN = "208"  !CDS_PN = "208";
"VSS91":   PN = "210"  !CDS_PN = "210";
"VSS92":   PN = "212"  !CDS_PN = "212";
"VSS93":   PN = "214"  !CDS_PN = "214";
"VSS94":   PN = "216"  !CDS_PN = "216";
"VSS95":   PN = "219"  !CDS_PN = "219";
"VSS96":   PN = "222"  !CDS_PN = "222";
"VSS97":   PN = "224"  !CDS_PN = "224";
"VSS98":   PN = "226"  !CDS_PN = "226";
"VSS99":   PN = "228"  !CDS_PN = "228";
"VSS100":   PN = "230"  !CDS_PN = "230";
"VSS101":   PN = "233"  !CDS_PN = "233";
"VSS102":   PN = "235"  !CDS_PN = "235";
"VSS103":   PN = "237"  !CDS_PN = "237";
"VSS104":   PN = "240"  !CDS_PN = "240";
"VSS105":   PN = "242"  !CDS_PN = "242";
"VSS106":   PN = "244"  !CDS_PN = "244";
"VSS107":   PN = "246"  !CDS_PN = "246";
"VSS108":   PN = "248"  !CDS_PN = "248";
"VSS109":   PN = "251"  !CDS_PN = "251";
"VSS110":   PN = "253"  !CDS_PN = "253";
"VSS111":   PN = "255"  !CDS_PN = "255";
"VSS112":   PN = "257"  !CDS_PN = "257";
"VSS113":   PN = "259"  !CDS_PN = "259";
"VSS114":   PN = "262"  !CDS_PN = "262";
"VSS115":   PN = "264"  !CDS_PN = "264";
"VSS116":   PN = "266"  !CDS_PN = "266";
"VSS117":   PN = "268"  !CDS_PN = "268";
"VSS118":   PN = "270"  !CDS_PN = "270";
"VSS119":   PN = "273"  !CDS_PN = "273";
"VSS120":   PN = "275"  !CDS_PN = "275";
"VSS121":   PN = "277"  !CDS_PN = "277";
"VSS122":   PN = "279"  !CDS_PN = "279";
"VSS123":   PN = "281"  !CDS_PN = "281";
"VSS124":   PN = "284"  !CDS_PN = "284";
"VSS125":   PN = "286"  !CDS_PN = "286";
"VSS126":   PN = "288"  !CDS_PN = "288";
BODY = "Q_CAP","I185": #LOCATION = "C176" !CDS_LOCATION = "C176" &SEC = "1" #&CDS_SEC = "1";
"A":   PN = "1"  !CDS_PN = "1";
"B":   PN = "2"  !CDS_PN = "2";
BODY = "Q_RES","I188": #LOCATION = "R313" !CDS_LOCATION = "R313" &SEC = "1" #&CDS_SEC = "1";
"A":   PN = "1"  !CDS_PN = "1";
"B":   PN = "2"  !CDS_PN = "2";
BODY = "Q_RES","I190": #LOCATION = "R114" !CDS_LOCATION = "R114" &SEC = "1" #&CDS_SEC = "1";
"A":   PN = "1"  !CDS_PN = "1";
"B":   PN = "2"  !CDS_PN = "2";
BODY = "SCONN288_DDR506112002KQ","I235": #LOCATION = "J99" !CDS_LOCATION = "J99" &SEC = "2" #&CDS_SEC = "2";
"DQS0_A_C":   PN = "12"  !CDS_PN = "12";
"DQS0_A_T":   PN = "11"  !CDS_PN = "11";
"DQS0_B_C":   PN = "105"  !CDS_PN = "105";
"DQS0_B_T":   PN = "104"  !CDS_PN = "104";
"DQS1_A_C":   PN = "23"  !CDS_PN = "23";
"DQS1_A_T":   PN = "22"  !CDS_PN = "22";
"DQS1_B_C":   PN = "116"  !CDS_PN = "116";
"DQS1_B_T":   PN = "115"  !CDS_PN = "115";
"DQS2_A_C":   PN = "34"  !CDS_PN = "34";
"DQS2_A_T":   PN = "33"  !CDS_PN = "33";
"DQS2_B_C":   PN = "127"  !CDS_PN = "127";
"DQS2_B_T":   PN = "126"  !CDS_PN = "126";
"DQS3_A_C":   PN = "45"  !CDS_PN = "45";
"DQS3_A_T":   PN = "44"  !CDS_PN = "44";
"DQS3_B_C":   PN = "138"  !CDS_PN = "138";
"DQS3_B_T":   PN = "137"  !CDS_PN = "137";
"DQS4_A_C":   PN = "56"  !CDS_PN = "56";
"DQS4_A_T":   PN = "55"  !CDS_PN = "55";
"DQS4_B_C":   PN = "238"  !CDS_PN = "238";
"DQS4_B_T":   PN = "239"  !CDS_PN = "239";
"DQS5_A_C||TDQS5_A_C||DQS5_A_T||TDQS5_A_T":   PN = "156"  !CDS_PN = "156";
"DQS5_A_T||TDQS5_A_T":   PN = "157"  !CDS_PN = "157";
"DQS5_B_C||TDQS5_B_C":   PN = "249"  !CDS_PN = "249";
"DQS5_B_T||TDQS5_B_T":   PN = "250"  !CDS_PN = "250";
"DQS6_A_C||TDQS6_A_C||DQS6_A_T||TDQS6_A_T":   PN = "167"  !CDS_PN = "167";
"DQS6_A_T||TDQS6_A_T":   PN = "168"  !CDS_PN = "168";
"DQS6_B_C||TDQS6_B_C":   PN = "260"  !CDS_PN = "260";
"DQS6_B_T||TDQS6_B_T":   PN = "261"  !CDS_PN = "261";
"DQS7_A_C||TDQS7_A_C":   PN = "178"  !CDS_PN = "178";
"DQS7_A_T||TDQS7_A_T":   PN = "179"  !CDS_PN = "179";
"DQS7_B_C||TDQS7_B_C":   PN = "271"  !CDS_PN = "271";
"DQS7_B_T||TDQS7_B_T":   PN = "272"  !CDS_PN = "272";
"DQS8_A_C||TDQS8_A_C":   PN = "189"  !CDS_PN = "189";
"DQS8_A_T||TDQS8_A_T":   PN = "190"  !CDS_PN = "190";
"DQS8_B_C||TDQS8_B_C":   PN = "282"  !CDS_PN = "282";
"DQS8_B_T||TDQS8_B_T":   PN = "283"  !CDS_PN = "283";
"DQS9_A_C||TDQS9_A_C":   PN = "200"  !CDS_PN = "200";
"DQS9_A_T||TDQS9_A_T":   PN = "201"  !CDS_PN = "201";
"DQS9_B_C||TDQS9_B_C":   PN = "94"  !CDS_PN = "94";
"DQS9_B_T||TDQS9_B_T||DBI4_B_N":   PN = "93"  !CDS_PN = "93";
BODY = "Q_CAP","I237": #LOCATION = "C546" !CDS_LOCATION = "C546" &SEC = "1" #&CDS_SEC = "1";
"A":   PN = "1"  !CDS_PN = "1";
"B":   PN = "2"  !CDS_PN = "2";
BODY = "Q_CAP","I238": #LOCATION = "C547" !CDS_LOCATION = "C547" &SEC = "1" #&CDS_SEC = "1";
"A":   PN = "1"  !CDS_PN = "1";
"B":   PN = "2"  !CDS_PN = "2";
BODY = "Q_RES","I241": #LOCATION = "R1590" !CDS_LOCATION = "R1590" &SEC = "1" #&CDS_SEC = "1";
"A":   PN = "1"  !CDS_PN = "1";
"B":   PN = "2"  !CDS_PN = "2";
BODY = "Q_RES","I242": #LOCATION = "R1710" !CDS_LOCATION = "R1710" &SEC = "1" #&CDS_SEC = "1";
"A":   PN = "1"  !CDS_PN = "1";
"B":   PN = "2"  !CDS_PN = "2";
DRAWING = "@t6g_mb_lib.t6g(sch_1):page108";
BODY = "SCONN288_DDR506112002KQ","I22": #LOCATION = "J37" !CDS_LOCATION = "J37" &SEC = "1" #&CDS_SEC = "1";
"ALERT_N":   PN = "62"  !CDS_PN = "62";
"CA0_A":   PN = "66"  !CDS_PN = "66";
"CA0_B":   PN = "76"  !CDS_PN = "76";
"CA1_A":   PN = "211"  !CDS_PN = "211";
"CA1_B":   PN = "221"  !CDS_PN = "221";
"CA2_A":   PN = "68"  !CDS_PN = "68";
"CA2_B":   PN = "78"  !CDS_PN = "78";
"CA3_A":   PN = "213"  !CDS_PN = "213";
"CA3_B":   PN = "223"  !CDS_PN = "223";
"CA4_A":   PN = "70"  !CDS_PN = "70";
"CA4_B":   PN = "80"  !CDS_PN = "80";
"CA5_A":   PN = "215"  !CDS_PN = "215";
"CA5_B":   PN = "225"  !CDS_PN = "225";
"CA6_A":   PN = "72"  !CDS_PN = "72";
"CA6_B":   PN = "82"  !CDS_PN = "82";
"CB0_A":   PN = "51"  !CDS_PN = "51";
"CB0_B":   PN = "96"  !CDS_PN = "96";
"CB1_A":   PN = "53"  !CDS_PN = "53";
"CB1_B":   PN = "98"  !CDS_PN = "98";
"CB2_A":   PN = "196"  !CDS_PN = "196";
"CB2_B":   PN = "241"  !CDS_PN = "241";
"CB3_A":   PN = "198"  !CDS_PN = "198";
"CB3_B":   PN = "243"  !CDS_PN = "243";
"CB4_A":   PN = "58"  !CDS_PN = "58";
"CB4_B":   PN = "89"  !CDS_PN = "89";
"CB5_A":   PN = "60"  !CDS_PN = "60";
"CB5_B":   PN = "91"  !CDS_PN = "91";
"CB6_A":   PN = "203"  !CDS_PN = "203";
"CB6_B":   PN = "234"  !CDS_PN = "234";
"CB7_A":   PN = "205"  !CDS_PN = "205";
"CB7_B":   PN = "236"  !CDS_PN = "236";
"CK_C":   PN = "218"  !CDS_PN = "218";
"CK_T":   PN = "217"  !CDS_PN = "217";
"CS0_A_N":   PN = "64"  !CDS_PN = "64";
"CS0_B_N":   PN = "84"  !CDS_PN = "84";
"CS1_A_N":   PN = "209"  !CDS_PN = "209";
"CS1_B_N":   PN = "229"  !CDS_PN = "229";
"DQ0_A":   PN = "7"  !CDS_PN = "7";
"DQ0_B":   PN = "100"  !CDS_PN = "100";
"DQ1_A":   PN = "9"  !CDS_PN = "9";
"DQ1_B":   PN = "102"  !CDS_PN = "102";
"DQ2_A":   PN = "152"  !CDS_PN = "152";
"DQ2_B":   PN = "245"  !CDS_PN = "245";
"DQ3_A":   PN = "154"  !CDS_PN = "154";
"DQ3_B":   PN = "247"  !CDS_PN = "247";
"DQ4_A":   PN = "14"  !CDS_PN = "14";
"DQ4_B":   PN = "107"  !CDS_PN = "107";
"DQ5_A":   PN = "16"  !CDS_PN = "16";
"DQ5_B":   PN = "109"  !CDS_PN = "109";
"DQ6_A":   PN = "159"  !CDS_PN = "159";
"DQ6_B":   PN = "252"  !CDS_PN = "252";
"DQ7_A":   PN = "161"  !CDS_PN = "161";
"DQ7_B":   PN = "254"  !CDS_PN = "254";
"DQ8_A":   PN = "18"  !CDS_PN = "18";
"DQ8_B":   PN = "111"  !CDS_PN = "111";
"DQ9_A":   PN = "20"  !CDS_PN = "20";
"DQ9_B":   PN = "113"  !CDS_PN = "113";
"DQ10_A":   PN = "163"  !CDS_PN = "163";
"DQ10_B":   PN = "256"  !CDS_PN = "256";
"DQ11_A":   PN = "165"  !CDS_PN = "165";
"DQ11_B":   PN = "258"  !CDS_PN = "258";
"DQ12_A":   PN = "25"  !CDS_PN = "25";
"DQ12_B":   PN = "118"  !CDS_PN = "118";
"DQ13_A":   PN = "27"  !CDS_PN = "27";
"DQ13_B":   PN = "120"  !CDS_PN = "120";
"DQ14_A":   PN = "170"  !CDS_PN = "170";
"DQ14_B":   PN = "263"  !CDS_PN = "263";
"DQ15_A":   PN = "172"  !CDS_PN = "172";
"DQ15_B":   PN = "265"  !CDS_PN = "265";
"DQ16_A":   PN = "29"  !CDS_PN = "29";
"DQ16_B":   PN = "122"  !CDS_PN = "122";
"DQ17_A":   PN = "31"  !CDS_PN = "31";
"DQ17_B":   PN = "124"  !CDS_PN = "124";
"DQ18_A":   PN = "174"  !CDS_PN = "174";
"DQ18_B":   PN = "267"  !CDS_PN = "267";
"DQ19_A":   PN = "176"  !CDS_PN = "176";
"DQ19_B":   PN = "269"  !CDS_PN = "269";
"DQ20_A":   PN = "36"  !CDS_PN = "36";
"DQ20_B":   PN = "129"  !CDS_PN = "129";
"DQ21_A":   PN = "38"  !CDS_PN = "38";
"DQ21_B":   PN = "131"  !CDS_PN = "131";
"DQ22_A":   PN = "181"  !CDS_PN = "181";
"DQ22_B":   PN = "274"  !CDS_PN = "274";
"DQ23_A":   PN = "183"  !CDS_PN = "183";
"DQ23_B":   PN = "276"  !CDS_PN = "276";
"DQ24_A":   PN = "40"  !CDS_PN = "40";
"DQ24_B":   PN = "133"  !CDS_PN = "133";
"DQ25_A":   PN = "42"  !CDS_PN = "42";
"DQ25_B":   PN = "135"  !CDS_PN = "135";
"DQ26_A":   PN = "185"  !CDS_PN = "185";
"DQ26_B":   PN = "278"  !CDS_PN = "278";
"DQ27_A":   PN = "187"  !CDS_PN = "187";
"DQ27_B":   PN = "280"  !CDS_PN = "280";
"DQ28_A":   PN = "47"  !CDS_PN = "47";
"DQ28_B":   PN = "140"  !CDS_PN = "140";
"DQ29_A":   PN = "49"  !CDS_PN = "49";
"DQ29_B":   PN = "142"  !CDS_PN = "142";
"DQ30_A":   PN = "192"  !CDS_PN = "192";
"DQ30_B":   PN = "285"  !CDS_PN = "285";
"DQ31_A":   PN = "194"  !CDS_PN = "194";
"DQ31_B":   PN = "287"  !CDS_PN = "287";
"HAS":   PN = "148"  !CDS_PN = "148";
"HSCL":   PN = "4"  !CDS_PN = "4";
"HSDA":   PN = "5"  !CDS_PN = "5";
"LBD||RSP_A_N":   PN = "86"  !CDS_PN = "86";
"LBS||RSP_B_N":   PN = "87"  !CDS_PN = "87";
"PAR_A":   PN = "74"  !CDS_PN = "74";
"PAR_B":   PN = "227"  !CDS_PN = "227";
"PWR_GOOD||FAIL_N":   PN = "147"  !CDS_PN = "147";
"RESET_N":   PN = "207"  !CDS_PN = "207";
"RFU0":   PN = "2"  !CDS_PN = "2";
"RFU1":   PN = "144"  !CDS_PN = "144";
"RFU2":   PN = "149"  !CDS_PN = "149";
"RFU3":   PN = "150"  !CDS_PN = "150";
"RFU4":   PN = "220"  !CDS_PN = "220";
"RFU5":   PN = "231"  !CDS_PN = "231";
"RFU6":   PN = "232"  !CDS_PN = "232";
"VIN_MGMT":   PN = "3"  !CDS_PN = "3";
BODY = "Q_RES","I136": #LOCATION = "R778" !CDS_LOCATION = "R778" &SEC = "1" #&CDS_SEC = "1";
"A":   PN = "1"  !CDS_PN = "1";
"B":   PN = "2"  !CDS_PN = "2";
BODY = "SCONN288_DDR506112002KQ","I138": #LOCATION = "J37" !CDS_LOCATION = "J37" &SEC = "3" #&CDS_SEC = "3";
"G1":   PN = "G1"  !CDS_PN = "G1";
"G2":   PN = "G2"  !CDS_PN = "G2";
"G3":   PN = "G3"  !CDS_PN = "G3";
"VIN_BULK0":   PN = "1"  !CDS_PN = "1";
"VIN_BULK1":   PN = "145"  !CDS_PN = "145";
"VIN_BULK2":   PN = "146"  !CDS_PN = "146";
"VSS0":   PN = "6"  !CDS_PN = "6";
"VSS1":   PN = "8"  !CDS_PN = "8";
"VSS2":   PN = "10"  !CDS_PN = "10";
"VSS3":   PN = "13"  !CDS_PN = "13";
"VSS4":   PN = "15"  !CDS_PN = "15";
"VSS5":   PN = "17"  !CDS_PN = "17";
"VSS6":   PN = "19"  !CDS_PN = "19";
"VSS7":   PN = "21"  !CDS_PN = "21";
"VSS8":   PN = "24"  !CDS_PN = "24";
"VSS9":   PN = "26"  !CDS_PN = "26";
"VSS10":   PN = "28"  !CDS_PN = "28";
"VSS11":   PN = "30"  !CDS_PN = "30";
"VSS12":   PN = "32"  !CDS_PN = "32";
"VSS13":   PN = "35"  !CDS_PN = "35";
"VSS14":   PN = "37"  !CDS_PN = "37";
"VSS15":   PN = "39"  !CDS_PN = "39";
"VSS16":   PN = "41"  !CDS_PN = "41";
"VSS17":   PN = "43"  !CDS_PN = "43";
"VSS18":   PN = "46"  !CDS_PN = "46";
"VSS19":   PN = "48"  !CDS_PN = "48";
"VSS20":   PN = "50"  !CDS_PN = "50";
"VSS21":   PN = "52"  !CDS_PN = "52";
"VSS22":   PN = "54"  !CDS_PN = "54";
"VSS23":   PN = "57"  !CDS_PN = "57";
"VSS24":   PN = "59"  !CDS_PN = "59";
"VSS25":   PN = "61"  !CDS_PN = "61";
"VSS26":   PN = "63"  !CDS_PN = "63";
"VSS27":   PN = "65"  !CDS_PN = "65";
"VSS28":   PN = "67"  !CDS_PN = "67";
"VSS29":   PN = "69"  !CDS_PN = "69";
"VSS30":   PN = "71"  !CDS_PN = "71";
"VSS31":   PN = "73"  !CDS_PN = "73";
"VSS32":   PN = "75"  !CDS_PN = "75";
"VSS33":   PN = "77"  !CDS_PN = "77";
"VSS34":   PN = "79"  !CDS_PN = "79";
"VSS35":   PN = "81"  !CDS_PN = "81";
"VSS36":   PN = "83"  !CDS_PN = "83";
"VSS37":   PN = "85"  !CDS_PN = "85";
"VSS38":   PN = "88"  !CDS_PN = "88";
"VSS39":   PN = "90"  !CDS_PN = "90";
"VSS40":   PN = "92"  !CDS_PN = "92";
"VSS41":   PN = "95"  !CDS_PN = "95";
"VSS42":   PN = "97"  !CDS_PN = "97";
"VSS43":   PN = "99"  !CDS_PN = "99";
"VSS44":   PN = "101"  !CDS_PN = "101";
"VSS45":   PN = "103"  !CDS_PN = "103";
"VSS46":   PN = "106"  !CDS_PN = "106";
"VSS47":   PN = "108"  !CDS_PN = "108";
"VSS48":   PN = "110"  !CDS_PN = "110";
"VSS49":   PN = "112"  !CDS_PN = "112";
"VSS50":   PN = "114"  !CDS_PN = "114";
"VSS51":   PN = "117"  !CDS_PN = "117";
"VSS52":   PN = "119"  !CDS_PN = "119";
"VSS53":   PN = "121"  !CDS_PN = "121";
"VSS54":   PN = "123"  !CDS_PN = "123";
"VSS55":   PN = "125"  !CDS_PN = "125";
"VSS56":   PN = "128"  !CDS_PN = "128";
"VSS57":   PN = "130"  !CDS_PN = "130";
"VSS58":   PN = "132"  !CDS_PN = "132";
"VSS59":   PN = "134"  !CDS_PN = "134";
"VSS60":   PN = "136"  !CDS_PN = "136";
"VSS61":   PN = "139"  !CDS_PN = "139";
"VSS62":   PN = "141"  !CDS_PN = "141";
"VSS63":   PN = "143"  !CDS_PN = "143";
"VSS64":   PN = "151"  !CDS_PN = "151";
"VSS65":   PN = "153"  !CDS_PN = "153";
"VSS66":   PN = "155"  !CDS_PN = "155";
"VSS67":   PN = "158"  !CDS_PN = "158";
"VSS68":   PN = "160"  !CDS_PN = "160";
"VSS69":   PN = "162"  !CDS_PN = "162";
"VSS70":   PN = "164"  !CDS_PN = "164";
"VSS71":   PN = "166"  !CDS_PN = "166";
"VSS72":   PN = "169"  !CDS_PN = "169";
"VSS73":   PN = "171"  !CDS_PN = "171";
"VSS74":   PN = "173"  !CDS_PN = "173";
"VSS75":   PN = "175"  !CDS_PN = "175";
"VSS76":   PN = "177"  !CDS_PN = "177";
"VSS77":   PN = "180"  !CDS_PN = "180";
"VSS78":   PN = "182"  !CDS_PN = "182";
"VSS79":   PN = "184"  !CDS_PN = "184";
"VSS80":   PN = "186"  !CDS_PN = "186";
"VSS81":   PN = "188"  !CDS_PN = "188";
"VSS82":   PN = "191"  !CDS_PN = "191";
"VSS83":   PN = "193"  !CDS_PN = "193";
"VSS84":   PN = "195"  !CDS_PN = "195";
"VSS85":   PN = "197"  !CDS_PN = "197";
"VSS86":   PN = "199"  !CDS_PN = "199";
"VSS87":   PN = "202"  !CDS_PN = "202";
"VSS88":   PN = "204"  !CDS_PN = "204";
"VSS89":   PN = "206"  !CDS_PN = "206";
"VSS90":   PN = "208"  !CDS_PN = "208";
"VSS91":   PN = "210"  !CDS_PN = "210";
"VSS92":   PN = "212"  !CDS_PN = "212";
"VSS93":   PN = "214"  !CDS_PN = "214";
"VSS94":   PN = "216"  !CDS_PN = "216";
"VSS95":   PN = "219"  !CDS_PN = "219";
"VSS96":   PN = "222"  !CDS_PN = "222";
"VSS97":   PN = "224"  !CDS_PN = "224";
"VSS98":   PN = "226"  !CDS_PN = "226";
"VSS99":   PN = "228"  !CDS_PN = "228";
"VSS100":   PN = "230"  !CDS_PN = "230";
"VSS101":   PN = "233"  !CDS_PN = "233";
"VSS102":   PN = "235"  !CDS_PN = "235";
"VSS103":   PN = "237"  !CDS_PN = "237";
"VSS104":   PN = "240"  !CDS_PN = "240";
"VSS105":   PN = "242"  !CDS_PN = "242";
"VSS106":   PN = "244"  !CDS_PN = "244";
"VSS107":   PN = "246"  !CDS_PN = "246";
"VSS108":   PN = "248"  !CDS_PN = "248";
"VSS109":   PN = "251"  !CDS_PN = "251";
"VSS110":   PN = "253"  !CDS_PN = "253";
"VSS111":   PN = "255"  !CDS_PN = "255";
"VSS112":   PN = "257"  !CDS_PN = "257";
"VSS113":   PN = "259"  !CDS_PN = "259";
"VSS114":   PN = "262"  !CDS_PN = "262";
"VSS115":   PN = "264"  !CDS_PN = "264";
"VSS116":   PN = "266"  !CDS_PN = "266";
"VSS117":   PN = "268"  !CDS_PN = "268";
"VSS118":   PN = "270"  !CDS_PN = "270";
"VSS119":   PN = "273"  !CDS_PN = "273";
"VSS120":   PN = "275"  !CDS_PN = "275";
"VSS121":   PN = "277"  !CDS_PN = "277";
"VSS122":   PN = "279"  !CDS_PN = "279";
"VSS123":   PN = "281"  !CDS_PN = "281";
"VSS124":   PN = "284"  !CDS_PN = "284";
"VSS125":   PN = "286"  !CDS_PN = "286";
"VSS126":   PN = "288"  !CDS_PN = "288";
BODY = "Q_CAP","I185": #LOCATION = "C180" !CDS_LOCATION = "C180" &SEC = "1" #&CDS_SEC = "1";
"A":   PN = "1"  !CDS_PN = "1";
"B":   PN = "2"  !CDS_PN = "2";
BODY = "Q_RES","I188": #LOCATION = "R314" !CDS_LOCATION = "R314" &SEC = "1" #&CDS_SEC = "1";
"A":   PN = "1"  !CDS_PN = "1";
"B":   PN = "2"  !CDS_PN = "2";
BODY = "Q_RES","I190": #LOCATION = "R115" !CDS_LOCATION = "R115" &SEC = "1" #&CDS_SEC = "1";
"A":   PN = "1"  !CDS_PN = "1";
"B":   PN = "2"  !CDS_PN = "2";
BODY = "SCONN288_DDR506112002KQ","I235": #LOCATION = "J37" !CDS_LOCATION = "J37" &SEC = "2" #&CDS_SEC = "2";
"DQS0_A_C":   PN = "12"  !CDS_PN = "12";
"DQS0_A_T":   PN = "11"  !CDS_PN = "11";
"DQS0_B_C":   PN = "105"  !CDS_PN = "105";
"DQS0_B_T":   PN = "104"  !CDS_PN = "104";
"DQS1_A_C":   PN = "23"  !CDS_PN = "23";
"DQS1_A_T":   PN = "22"  !CDS_PN = "22";
"DQS1_B_C":   PN = "116"  !CDS_PN = "116";
"DQS1_B_T":   PN = "115"  !CDS_PN = "115";
"DQS2_A_C":   PN = "34"  !CDS_PN = "34";
"DQS2_A_T":   PN = "33"  !CDS_PN = "33";
"DQS2_B_C":   PN = "127"  !CDS_PN = "127";
"DQS2_B_T":   PN = "126"  !CDS_PN = "126";
"DQS3_A_C":   PN = "45"  !CDS_PN = "45";
"DQS3_A_T":   PN = "44"  !CDS_PN = "44";
"DQS3_B_C":   PN = "138"  !CDS_PN = "138";
"DQS3_B_T":   PN = "137"  !CDS_PN = "137";
"DQS4_A_C":   PN = "56"  !CDS_PN = "56";
"DQS4_A_T":   PN = "55"  !CDS_PN = "55";
"DQS4_B_C":   PN = "238"  !CDS_PN = "238";
"DQS4_B_T":   PN = "239"  !CDS_PN = "239";
"DQS5_A_C||TDQS5_A_C||DQS5_A_T||TDQS5_A_T":   PN = "156"  !CDS_PN = "156";
"DQS5_A_T||TDQS5_A_T":   PN = "157"  !CDS_PN = "157";
"DQS5_B_C||TDQS5_B_C":   PN = "249"  !CDS_PN = "249";
"DQS5_B_T||TDQS5_B_T":   PN = "250"  !CDS_PN = "250";
"DQS6_A_C||TDQS6_A_C||DQS6_A_T||TDQS6_A_T":   PN = "167"  !CDS_PN = "167";
"DQS6_A_T||TDQS6_A_T":   PN = "168"  !CDS_PN = "168";
"DQS6_B_C||TDQS6_B_C":   PN = "260"  !CDS_PN = "260";
"DQS6_B_T||TDQS6_B_T":   PN = "261"  !CDS_PN = "261";
"DQS7_A_C||TDQS7_A_C":   PN = "178"  !CDS_PN = "178";
"DQS7_A_T||TDQS7_A_T":   PN = "179"  !CDS_PN = "179";
"DQS7_B_C||TDQS7_B_C":   PN = "271"  !CDS_PN = "271";
"DQS7_B_T||TDQS7_B_T":   PN = "272"  !CDS_PN = "272";
"DQS8_A_C||TDQS8_A_C":   PN = "189"  !CDS_PN = "189";
"DQS8_A_T||TDQS8_A_T":   PN = "190"  !CDS_PN = "190";
"DQS8_B_C||TDQS8_B_C":   PN = "282"  !CDS_PN = "282";
"DQS8_B_T||TDQS8_B_T":   PN = "283"  !CDS_PN = "283";
"DQS9_A_C||TDQS9_A_C":   PN = "200"  !CDS_PN = "200";
"DQS9_A_T||TDQS9_A_T":   PN = "201"  !CDS_PN = "201";
"DQS9_B_C||TDQS9_B_C":   PN = "94"  !CDS_PN = "94";
"DQS9_B_T||TDQS9_B_T||DBI4_B_N":   PN = "93"  !CDS_PN = "93";
BODY = "Q_CAP","I237": #LOCATION = "C548" !CDS_LOCATION = "C548" &SEC = "1" #&CDS_SEC = "1";
"A":   PN = "1"  !CDS_PN = "1";
"B":   PN = "2"  !CDS_PN = "2";
BODY = "Q_CAP","I238": #LOCATION = "C549" !CDS_LOCATION = "C549" &SEC = "1" #&CDS_SEC = "1";
"A":   PN = "1"  !CDS_PN = "1";
"B":   PN = "2"  !CDS_PN = "2";
BODY = "Q_RES","I241": #LOCATION = "R1591" !CDS_LOCATION = "R1591" &SEC = "1" #&CDS_SEC = "1";
"A":   PN = "1"  !CDS_PN = "1";
"B":   PN = "2"  !CDS_PN = "2";
BODY = "Q_RES","I242": #LOCATION = "R1711" !CDS_LOCATION = "R1711" &SEC = "1" #&CDS_SEC = "1";
"A":   PN = "1"  !CDS_PN = "1";
"B":   PN = "2"  !CDS_PN = "2";
DRAWING = "@t6g_mb_lib.t6g(sch_1):page132";
BODY = "MOSFET_DUAL_6P","I12": #LOCATION = "Q4" !CDS_LOCATION = "Q4" &SEC = "1" #&CDS_SEC = "1";
"D1":   PN = "6"  !CDS_PN = "6";
"D2":   PN = "3"  !CDS_PN = "3";
"G1":   PN = "2"  !CDS_PN = "2";
"G2":   PN = "5"  !CDS_PN = "5";
"S1":   PN = "1"  !CDS_PN = "1";
"S2":   PN = "4"  !CDS_PN = "4";
BODY = "Q_RES","I4": #LOCATION = "R1005" !CDS_LOCATION = "R1005" &SEC = "1" #&CDS_SEC = "1";
"A":   PN = "1"  !CDS_PN = "1";
"B":   PN = "2"  !CDS_PN = "2";
BODY = "Q_RES","I5": #LOCATION = "R116" !CDS_LOCATION = "R116" &SEC = "1" #&CDS_SEC = "1";
"A":   PN = "1"  !CDS_PN = "1";
"B":   PN = "2"  !CDS_PN = "2";
BODY = "Q_RES","I6": #LOCATION = "R6063" !CDS_LOCATION = "R6063" &SEC = "1" #&CDS_SEC = "1";
"A":   PN = "1"  !CDS_PN = "1";
"B":   PN = "2"  !CDS_PN = "2";
BODY = "Q_RES","I7": #LOCATION = "R994" !CDS_LOCATION = "R994" &SEC = "1" #&CDS_SEC = "1";
"A":   PN = "1"  !CDS_PN = "1";
"B":   PN = "2"  !CDS_PN = "2";
BODY = "Q_RES","I10": #LOCATION = "R1009" !CDS_LOCATION = "R1009" &SEC = "1" #&CDS_SEC = "1";
"A":   PN = "1"  !CDS_PN = "1";
"B":   PN = "2"  !CDS_PN = "2";
BODY = "Q_RES","I16": #LOCATION = "R1311" !CDS_LOCATION = "R1311" &SEC = "1" #&CDS_SEC = "1";
"A":   PN = "1"  !CDS_PN = "1";
"B":   PN = "2"  !CDS_PN = "2";
BODY = "Q_RES","I18": #LOCATION = "R437" !CDS_LOCATION = "R437" &SEC = "1" #&CDS_SEC = "1";
"A":   PN = "1"  !CDS_PN = "1";
"B":   PN = "2"  !CDS_PN = "2";
DRAWING = "@t6g_mb_lib.t6g(sch_1):page136";
BODY = "Q_RES","I31": #LOCATION = "R1297" !CDS_LOCATION = "R1297" &SEC = "1" #&CDS_SEC = "1";
"A":   PN = "1"  !CDS_PN = "1";
"B":   PN = "2"  !CDS_PN = "2";
BODY = "Q_RES","I32": #LOCATION = "R1298" !CDS_LOCATION = "R1298" &SEC = "1" #&CDS_SEC = "1";
"A":   PN = "1"  !CDS_PN = "1";
"B":   PN = "2"  !CDS_PN = "2";
BODY = "Q_RES","I33": #LOCATION = "R1299" !CDS_LOCATION = "R1299" &SEC = "1" #&CDS_SEC = "1";
"A":   PN = "1"  !CDS_PN = "1";
"B":   PN = "2"  !CDS_PN = "2";
BODY = "Q_RES","I34": #LOCATION = "R1300" !CDS_LOCATION = "R1300" &SEC = "1" #&CDS_SEC = "1";
"A":   PN = "1"  !CDS_PN = "1";
"B":   PN = "2"  !CDS_PN = "2";
BODY = "Q_RES","I35": #LOCATION = "R1293" !CDS_LOCATION = "R1293" &SEC = "1" #&CDS_SEC = "1";
"A":   PN = "1"  !CDS_PN = "1";
"B":   PN = "2"  !CDS_PN = "2";
BODY = "Q_RES","I36": #LOCATION = "R1294" !CDS_LOCATION = "R1294" &SEC = "1" #&CDS_SEC = "1";
"A":   PN = "1"  !CDS_PN = "1";
"B":   PN = "2"  !CDS_PN = "2";
BODY = "Q_RES","I37": #LOCATION = "R1295" !CDS_LOCATION = "R1295" &SEC = "1" #&CDS_SEC = "1";
"A":   PN = "1"  !CDS_PN = "1";
"B":   PN = "2"  !CDS_PN = "2";
BODY = "Q_RES","I38": #LOCATION = "R1296" !CDS_LOCATION = "R1296" &SEC = "1" #&CDS_SEC = "1";
"A":   PN = "1"  !CDS_PN = "1";
"B":   PN = "2"  !CDS_PN = "2";
BODY = "PI3CSW12ZUAEX","I47": #LOCATION = "U105" !CDS_LOCATION = "U105" &SEC = "1" #&CDS_SEC = "1";
"1D+":   PN = "1"  !CDS_PN = "1";
"1D-":   PN = "2"  !CDS_PN = "2";
"2D+":   PN = "3"  !CDS_PN = "3";
"2D-":   PN = "4"  !CDS_PN = "4";
"D+":   PN = "8"  !CDS_PN = "8";
"D-":   PN = "7"  !CDS_PN = "7";
"GND":   PN = "5"  !CDS_PN = "5";
"OE#":   PN = "6"  !CDS_PN = "6";
"S":   PN = "9"  !CDS_PN = "9";
"VDD":   PN = "10"  !CDS_PN = "10";
BODY = "Q_CAP","I50": #LOCATION = "C1336" !CDS_LOCATION = "C1336" &SEC = "1" #&CDS_SEC = "1";
"A":   PN = "1"  !CDS_PN = "1";
"B":   PN = "2"  !CDS_PN = "2";
BODY = "PI3CSW12ZUAEX","I54": #LOCATION = "U106" !CDS_LOCATION = "U106" &SEC = "1" #&CDS_SEC = "1";
"1D+":   PN = "1"  !CDS_PN = "1";
"1D-":   PN = "2"  !CDS_PN = "2";
"2D+":   PN = "3"  !CDS_PN = "3";
"2D-":   PN = "4"  !CDS_PN = "4";
"D+":   PN = "8"  !CDS_PN = "8";
"D-":   PN = "7"  !CDS_PN = "7";
"GND":   PN = "5"  !CDS_PN = "5";
"OE#":   PN = "6"  !CDS_PN = "6";
"S":   PN = "9"  !CDS_PN = "9";
"VDD":   PN = "10"  !CDS_PN = "10";
BODY = "Q_CAP","I56": #LOCATION = "C1337" !CDS_LOCATION = "C1337" &SEC = "1" #&CDS_SEC = "1";
"A":   PN = "1"  !CDS_PN = "1";
"B":   PN = "2"  !CDS_PN = "2";
BODY = "Q_CAP","I61": #LOCATION = "C1338" !CDS_LOCATION = "C1338" &SEC = "1" #&CDS_SEC = "1";
"A":   PN = "1"  !CDS_PN = "1";
"B":   PN = "2"  !CDS_PN = "2";
BODY = "PI3CSW12ZUAEX","I63": #LOCATION = "U107" !CDS_LOCATION = "U107" &SEC = "1" #&CDS_SEC = "1";
"1D+":   PN = "1"  !CDS_PN = "1";
"1D-":   PN = "2"  !CDS_PN = "2";
"2D+":   PN = "3"  !CDS_PN = "3";
"2D-":   PN = "4"  !CDS_PN = "4";
"D+":   PN = "8"  !CDS_PN = "8";
"D-":   PN = "7"  !CDS_PN = "7";
"GND":   PN = "5"  !CDS_PN = "5";
"OE#":   PN = "6"  !CDS_PN = "6";
"S":   PN = "9"  !CDS_PN = "9";
"VDD":   PN = "10"  !CDS_PN = "10";
BODY = "Q_CAP","I66": #LOCATION = "C1339" !CDS_LOCATION = "C1339" &SEC = "1" #&CDS_SEC = "1";
"A":   PN = "1"  !CDS_PN = "1";
"B":   PN = "2"  !CDS_PN = "2";
BODY = "PI3CSW12ZUAEX","I68": #LOCATION = "U108" !CDS_LOCATION = "U108" &SEC = "1" #&CDS_SEC = "1";
"1D+":   PN = "1"  !CDS_PN = "1";
"1D-":   PN = "2"  !CDS_PN = "2";
"2D+":   PN = "3"  !CDS_PN = "3";
"2D-":   PN = "4"  !CDS_PN = "4";
"D+":   PN = "8"  !CDS_PN = "8";
"D-":   PN = "7"  !CDS_PN = "7";
"GND":   PN = "5"  !CDS_PN = "5";
"OE#":   PN = "6"  !CDS_PN = "6";
"S":   PN = "9"  !CDS_PN = "9";
"VDD":   PN = "10"  !CDS_PN = "10";
BODY = "Q_RES","I99": #LOCATION = "R426" !CDS_LOCATION = "R426" &SEC = "1" #&CDS_SEC = "1";
"A":   PN = "1"  !CDS_PN = "1";
"B":   PN = "2"  !CDS_PN = "2";
BODY = "Q_RES","I100": #LOCATION = "R427" !CDS_LOCATION = "R427" &SEC = "1" #&CDS_SEC = "1";
"A":   PN = "1"  !CDS_PN = "1";
"B":   PN = "2"  !CDS_PN = "2";
BODY = "Q_RES","I103": #LOCATION = "R428" !CDS_LOCATION = "R428" &SEC = "1" #&CDS_SEC = "1";
"A":   PN = "1"  !CDS_PN = "1";
"B":   PN = "2"  !CDS_PN = "2";
BODY = "Q_RES","I104": #LOCATION = "R429" !CDS_LOCATION = "R429" &SEC = "1" #&CDS_SEC = "1";
"A":   PN = "1"  !CDS_PN = "1";
"B":   PN = "2"  !CDS_PN = "2";
BODY = "Q_RES","I107": #LOCATION = "R565" !CDS_LOCATION = "R565" &SEC = "1" #&CDS_SEC = "1";
"A":   PN = "1"  !CDS_PN = "1";
"B":   PN = "2"  !CDS_PN = "2";
BODY = "Q_RES","I108": #LOCATION = "R564" !CDS_LOCATION = "R564" &SEC = "1" #&CDS_SEC = "1";
"A":   PN = "1"  !CDS_PN = "1";
"B":   PN = "2"  !CDS_PN = "2";
BODY = "Q_RES","I111": #LOCATION = "R566" !CDS_LOCATION = "R566" &SEC = "1" #&CDS_SEC = "1";
"A":   PN = "1"  !CDS_PN = "1";
"B":   PN = "2"  !CDS_PN = "2";
BODY = "Q_RES","I112": #LOCATION = "R567" !CDS_LOCATION = "R567" &SEC = "1" #&CDS_SEC = "1";
"A":   PN = "1"  !CDS_PN = "1";
"B":   PN = "2"  !CDS_PN = "2";
BODY = "Q_RES","I123": #LOCATION = "R2310" !CDS_LOCATION = "R2310" &SEC = "1" #&CDS_SEC = "1";
"A":   PN = "1"  !CDS_PN = "1";
"B":   PN = "2"  !CDS_PN = "2";
BODY = "Q_RES","I124": #LOCATION = "R2311" !CDS_LOCATION = "R2311" &SEC = "1" #&CDS_SEC = "1";
"A":   PN = "1"  !CDS_PN = "1";
"B":   PN = "2"  !CDS_PN = "2";
BODY = "Q_RES","I131": #LOCATION = "R1330" !CDS_LOCATION = "R1330" &SEC = "1" #&CDS_SEC = "1";
"A":   PN = "1"  !CDS_PN = "1";
"B":   PN = "2"  !CDS_PN = "2";
BODY = "Q_RES","I132": #LOCATION = "R1331" !CDS_LOCATION = "R1331" &SEC = "1" #&CDS_SEC = "1";
"A":   PN = "1"  !CDS_PN = "1";
"B":   PN = "2"  !CDS_PN = "2";
BODY = "Q_RES","I133": #LOCATION = "R1333" !CDS_LOCATION = "R1333" &SEC = "1" #&CDS_SEC = "1";
"A":   PN = "1"  !CDS_PN = "1";
"B":   PN = "2"  !CDS_PN = "2";
BODY = "Q_RES","I134": #LOCATION = "R1332" !CDS_LOCATION = "R1332" &SEC = "1" #&CDS_SEC = "1";
"A":   PN = "1"  !CDS_PN = "1";
"B":   PN = "2"  !CDS_PN = "2";
BODY = "Q_RES","I135": #LOCATION = "R986" !CDS_LOCATION = "R986" &SEC = "1" #&CDS_SEC = "1";
"A":   PN = "1"  !CDS_PN = "1";
"B":   PN = "2"  !CDS_PN = "2";
BODY = "Q_RES","I136": #LOCATION = "R987" !CDS_LOCATION = "R987" &SEC = "1" #&CDS_SEC = "1";
"A":   PN = "1"  !CDS_PN = "1";
"B":   PN = "2"  !CDS_PN = "2";
BODY = "Q_RES","I137": #LOCATION = "R989" !CDS_LOCATION = "R989" &SEC = "1" #&CDS_SEC = "1";
"A":   PN = "1"  !CDS_PN = "1";
"B":   PN = "2"  !CDS_PN = "2";
BODY = "Q_RES","I138": #LOCATION = "R988" !CDS_LOCATION = "R988" &SEC = "1" #&CDS_SEC = "1";
"A":   PN = "1"  !CDS_PN = "1";
"B":   PN = "2"  !CDS_PN = "2";
BODY = "Q_RES","I139": #LOCATION = "R1334" !CDS_LOCATION = "R1334" &SEC = "1" #&CDS_SEC = "1";
"A":   PN = "1"  !CDS_PN = "1";
"B":   PN = "2"  !CDS_PN = "2";
BODY = "Q_RES","I140": #LOCATION = "R1335" !CDS_LOCATION = "R1335" &SEC = "1" #&CDS_SEC = "1";
"A":   PN = "1"  !CDS_PN = "1";
"B":   PN = "2"  !CDS_PN = "2";
BODY = "Q_RES","I141": #LOCATION = "R991" !CDS_LOCATION = "R991" &SEC = "1" #&CDS_SEC = "1";
"A":   PN = "1"  !CDS_PN = "1";
"B":   PN = "2"  !CDS_PN = "2";
BODY = "Q_RES","I142": #LOCATION = "R990" !CDS_LOCATION = "R990" &SEC = "1" #&CDS_SEC = "1";
"A":   PN = "1"  !CDS_PN = "1";
"B":   PN = "2"  !CDS_PN = "2";
BODY = "Q_RES","I143": #LOCATION = "R1336" !CDS_LOCATION = "R1336" &SEC = "1" #&CDS_SEC = "1";
"A":   PN = "1"  !CDS_PN = "1";
"B":   PN = "2"  !CDS_PN = "2";
BODY = "Q_RES","I144": #LOCATION = "R1337" !CDS_LOCATION = "R1337" &SEC = "1" #&CDS_SEC = "1";
"A":   PN = "1"  !CDS_PN = "1";
"B":   PN = "2"  !CDS_PN = "2";
BODY = "Q_RES","I145": #LOCATION = "R5006" !CDS_LOCATION = "R5006" &SEC = "1" #&CDS_SEC = "1";
"A":   PN = "1"  !CDS_PN = "1";
"B":   PN = "2"  !CDS_PN = "2";
BODY = "Q_RES","I147": #LOCATION = "R5007" !CDS_LOCATION = "R5007" &SEC = "1" #&CDS_SEC = "1";
"A":   PN = "1"  !CDS_PN = "1";
"B":   PN = "2"  !CDS_PN = "2";
BODY = "Q_RES","I148": #LOCATION = "R5008" !CDS_LOCATION = "R5008" &SEC = "1" #&CDS_SEC = "1";
"A":   PN = "1"  !CDS_PN = "1";
"B":   PN = "2"  !CDS_PN = "2";
BODY = "Q_RES","I150": #LOCATION = "R5009" !CDS_LOCATION = "R5009" &SEC = "1" #&CDS_SEC = "1";
"A":   PN = "1"  !CDS_PN = "1";
"B":   PN = "2"  !CDS_PN = "2";
BODY = "Q_RES","I151": #LOCATION = "R5010" !CDS_LOCATION = "R5010" &SEC = "1" #&CDS_SEC = "1";
"A":   PN = "1"  !CDS_PN = "1";
"B":   PN = "2"  !CDS_PN = "2";
BODY = "Q_RES","I152": #LOCATION = "R5011" !CDS_LOCATION = "R5011" &SEC = "1" #&CDS_SEC = "1";
"A":   PN = "1"  !CDS_PN = "1";
"B":   PN = "2"  !CDS_PN = "2";
BODY = "Q_RES","I154": #LOCATION = "R5013" !CDS_LOCATION = "R5013" &SEC = "1" #&CDS_SEC = "1";
"A":   PN = "1"  !CDS_PN = "1";
"B":   PN = "2"  !CDS_PN = "2";
BODY = "Q_RES","I156": #LOCATION = "R5012" !CDS_LOCATION = "R5012" &SEC = "1" #&CDS_SEC = "1";
"A":   PN = "1"  !CDS_PN = "1";
"B":   PN = "2"  !CDS_PN = "2";
BODY = "Q_RES","I157": #LOCATION = "R5015" !CDS_LOCATION = "R5015" &SEC = "1" #&CDS_SEC = "1";
"A":   PN = "1"  !CDS_PN = "1";
"B":   PN = "2"  !CDS_PN = "2";
BODY = "Q_RES","I159": #LOCATION = "R5014" !CDS_LOCATION = "R5014" &SEC = "1" #&CDS_SEC = "1";
"A":   PN = "1"  !CDS_PN = "1";
"B":   PN = "2"  !CDS_PN = "2";
BODY = "Q_RES","I161": #LOCATION = "R5017" !CDS_LOCATION = "R5017" &SEC = "1" #&CDS_SEC = "1";
"A":   PN = "1"  !CDS_PN = "1";
"B":   PN = "2"  !CDS_PN = "2";
BODY = "Q_RES","I162": #LOCATION = "R5016" !CDS_LOCATION = "R5016" &SEC = "1" #&CDS_SEC = "1";
"A":   PN = "1"  !CDS_PN = "1";
"B":   PN = "2"  !CDS_PN = "2";
BODY = "Q_RES","I163": #LOCATION = "R5018" !CDS_LOCATION = "R5018" &SEC = "1" #&CDS_SEC = "1";
"A":   PN = "1"  !CDS_PN = "1";
"B":   PN = "2"  !CDS_PN = "2";
BODY = "Q_RES","I164": #LOCATION = "R5019" !CDS_LOCATION = "R5019" &SEC = "1" #&CDS_SEC = "1";
"A":   PN = "1"  !CDS_PN = "1";
"B":   PN = "2"  !CDS_PN = "2";
BODY = "Q_RES","I166": #LOCATION = "R5021" !CDS_LOCATION = "R5021" &SEC = "1" #&CDS_SEC = "1";
"A":   PN = "1"  !CDS_PN = "1";
"B":   PN = "2"  !CDS_PN = "2";
BODY = "Q_RES","I167": #LOCATION = "R5020" !CDS_LOCATION = "R5020" &SEC = "1" #&CDS_SEC = "1";
"A":   PN = "1"  !CDS_PN = "1";
"B":   PN = "2"  !CDS_PN = "2";
DRAWING = "@t6g_mb_lib.t6g(sch_1):page138";
BODY = "Q_RES","I5": #LOCATION = "R358" !CDS_LOCATION = "R358" &SEC = "1" #&CDS_SEC = "1";
"A":   PN = "1"  !CDS_PN = "1";
"B":   PN = "2"  !CDS_PN = "2";
BODY = "Q_RES","I6": #LOCATION = "R148" !CDS_LOCATION = "R148" &SEC = "1" #&CDS_SEC = "1";
"A":   PN = "1"  !CDS_PN = "1";
"B":   PN = "2"  !CDS_PN = "2";
BODY = "Q_RES","I14": #LOCATION = "R145" !CDS_LOCATION = "R145" &SEC = "1" #&CDS_SEC = "1";
"A":   PN = "1"  !CDS_PN = "1";
"B":   PN = "2"  !CDS_PN = "2";
BODY = "Q_RES","I15": #LOCATION = "R144" !CDS_LOCATION = "R144" &SEC = "1" #&CDS_SEC = "1";
"A":   PN = "1"  !CDS_PN = "1";
"B":   PN = "2"  !CDS_PN = "2";
BODY = "Q_RES","I17": #LOCATION = "R146" !CDS_LOCATION = "R146" &SEC = "1" #&CDS_SEC = "1";
"A":   PN = "1"  !CDS_PN = "1";
"B":   PN = "2"  !CDS_PN = "2";
BODY = "Q_RES","I27": #LOCATION = "R5004" !CDS_LOCATION = "R5004" &SEC = "1" #&CDS_SEC = "1";
"A":   PN = "1"  !CDS_PN = "1";
"B":   PN = "2"  !CDS_PN = "2";
BODY = "Q_RES","I30": #LOCATION = "R139" !CDS_LOCATION = "R139" &SEC = "1" #&CDS_SEC = "1";
"A":   PN = "1"  !CDS_PN = "1";
"B":   PN = "2"  !CDS_PN = "2";
BODY = "Q_RES","I35": #LOCATION = "R142" !CDS_LOCATION = "R142" &SEC = "1" #&CDS_SEC = "1";
"A":   PN = "1"  !CDS_PN = "1";
"B":   PN = "2"  !CDS_PN = "2";
BODY = "Q_RES","I38": #LOCATION = "R1156" !CDS_LOCATION = "R1156" &SEC = "1" #&CDS_SEC = "1";
"A":   PN = "1"  !CDS_PN = "1";
"B":   PN = "2"  !CDS_PN = "2";
BODY = "Q_RES","I52": #LOCATION = "R359" !CDS_LOCATION = "R359" &SEC = "1" #&CDS_SEC = "1";
"A":   PN = "1"  !CDS_PN = "1";
"B":   PN = "2"  !CDS_PN = "2";
BODY = "Q_RES","I54": #LOCATION = "R366" !CDS_LOCATION = "R366" &SEC = "1" #&CDS_SEC = "1";
"A":   PN = "1"  !CDS_PN = "1";
"B":   PN = "2"  !CDS_PN = "2";
BODY = "Q_RES","I56": #LOCATION = "R363" !CDS_LOCATION = "R363" &SEC = "1" #&CDS_SEC = "1";
"A":   PN = "1"  !CDS_PN = "1";
"B":   PN = "2"  !CDS_PN = "2";
BODY = "Q_RES","I58": #LOCATION = "R369" !CDS_LOCATION = "R369" &SEC = "1" #&CDS_SEC = "1";
"A":   PN = "1"  !CDS_PN = "1";
"B":   PN = "2"  !CDS_PN = "2";
BODY = "Q_RES","I60": #LOCATION = "R370" !CDS_LOCATION = "R370" &SEC = "1" #&CDS_SEC = "1";
"A":   PN = "1"  !CDS_PN = "1";
"B":   PN = "2"  !CDS_PN = "2";
BODY = "Q_RES","I16": #LOCATION = "R147" !CDS_LOCATION = "R147" &SEC = "1" #&CDS_SEC = "1";
"A":   PN = "1"  !CDS_PN = "1";
"B":   PN = "2"  !CDS_PN = "2";
BODY = "Q_RES","I22": #LOCATION = "R1162" !CDS_LOCATION = "R1162" &SEC = "1" #&CDS_SEC = "1";
"A":   PN = "1"  !CDS_PN = "1";
"B":   PN = "2"  !CDS_PN = "2";
BODY = "Q_RES","I23": #LOCATION = "R1161" !CDS_LOCATION = "R1161" &SEC = "1" #&CDS_SEC = "1";
"A":   PN = "1"  !CDS_PN = "1";
"B":   PN = "2"  !CDS_PN = "2";
BODY = "Q_RES","I34": #LOCATION = "R143" !CDS_LOCATION = "R143" &SEC = "1" #&CDS_SEC = "1";
"A":   PN = "1"  !CDS_PN = "1";
"B":   PN = "2"  !CDS_PN = "2";
BODY = "Q_RES","I39": #LOCATION = "R1155" !CDS_LOCATION = "R1155" &SEC = "1" #&CDS_SEC = "1";
"A":   PN = "1"  !CDS_PN = "1";
"B":   PN = "2"  !CDS_PN = "2";
BODY = "Q_RES","I53": #LOCATION = "R362" !CDS_LOCATION = "R362" &SEC = "1" #&CDS_SEC = "1";
"A":   PN = "1"  !CDS_PN = "1";
"B":   PN = "2"  !CDS_PN = "2";
BODY = "Q_RES","I55": #LOCATION = "R360" !CDS_LOCATION = "R360" &SEC = "1" #&CDS_SEC = "1";
"A":   PN = "1"  !CDS_PN = "1";
"B":   PN = "2"  !CDS_PN = "2";
BODY = "Q_RES","I57": #LOCATION = "R367" !CDS_LOCATION = "R367" &SEC = "1" #&CDS_SEC = "1";
"A":   PN = "1"  !CDS_PN = "1";
"B":   PN = "2"  !CDS_PN = "2";
BODY = "PI3CSW12ZUAEX","I67": #LOCATION = "U6" !CDS_LOCATION = "U6" #SEC = "1" !CDS_SEC = "1";
"1D+":   PN = "1"  !CDS_PN = "1";
"1D-":   PN = "2"  !CDS_PN = "2";
"2D+":   PN = "3"  !CDS_PN = "3";
"2D-":   PN = "4"  !CDS_PN = "4";
"D+":   PN = "8"  !CDS_PN = "8";
"D-":   PN = "7"  !CDS_PN = "7";
"GND":   PN = "5"  !CDS_PN = "5";
"OE#":   PN = "6"  !CDS_PN = "6";
"S":   PN = "9"  !CDS_PN = "9";
"VDD":   PN = "10"  !CDS_PN = "10";
BODY = "Q_CAP","I69": #LOCATION = "C25" !CDS_LOCATION = "C25" &SEC = "1" #&CDS_SEC = "1";
"A":   PN = "1"  !CDS_PN = "1";
"B":   PN = "2"  !CDS_PN = "2";
BODY = "Q_RES","I73": #LOCATION = "R1158" !CDS_LOCATION = "R1158" &SEC = "1" #&CDS_SEC = "1";
"A":   PN = "1"  !CDS_PN = "1";
"B":   PN = "2"  !CDS_PN = "2";
BODY = "Q_RES","I74": #LOCATION = "R1157" !CDS_LOCATION = "R1157" &SEC = "1" #&CDS_SEC = "1";
"A":   PN = "1"  !CDS_PN = "1";
"B":   PN = "2"  !CDS_PN = "2";
BODY = "Q_RES","I75": #LOCATION = "R1160" !CDS_LOCATION = "R1160" &SEC = "1" #&CDS_SEC = "1";
"A":   PN = "1"  !CDS_PN = "1";
"B":   PN = "2"  !CDS_PN = "2";
BODY = "Q_RES","I76": #LOCATION = "R1159" !CDS_LOCATION = "R1159" &SEC = "1" #&CDS_SEC = "1";
"A":   PN = "1"  !CDS_PN = "1";
"B":   PN = "2"  !CDS_PN = "2";
BODY = "Q_CAP","I89": #LOCATION = "C11" !CDS_LOCATION = "C11" &SEC = "1" #&CDS_SEC = "1";
"A":   PN = "1"  !CDS_PN = "1";
"B":   PN = "2"  !CDS_PN = "2";
BODY = "Q_RES","I91": #LOCATION = "R327" !CDS_LOCATION = "R327" &SEC = "1" #&CDS_SEC = "1";
"A":   PN = "1"  !CDS_PN = "1";
"B":   PN = "2"  !CDS_PN = "2";
BODY = "Q_RES","I92": #LOCATION = "R328" !CDS_LOCATION = "R328" &SEC = "1" #&CDS_SEC = "1";
"A":   PN = "1"  !CDS_PN = "1";
"B":   PN = "2"  !CDS_PN = "2";
BODY = "Q_RES","I93": #LOCATION = "R337" !CDS_LOCATION = "R337" &SEC = "1" #&CDS_SEC = "1";
"A":   PN = "1"  !CDS_PN = "1";
"B":   PN = "2"  !CDS_PN = "2";
BODY = "Q_RES","I94": #LOCATION = "R338" !CDS_LOCATION = "R338" &SEC = "1" #&CDS_SEC = "1";
"A":   PN = "1"  !CDS_PN = "1";
"B":   PN = "2"  !CDS_PN = "2";
BODY = "Q_RES","I99": #LOCATION = "R325" !CDS_LOCATION = "R325" &SEC = "1" #&CDS_SEC = "1";
"A":   PN = "1"  !CDS_PN = "1";
"B":   PN = "2"  !CDS_PN = "2";
BODY = "Q_RES","I100": #LOCATION = "R326" !CDS_LOCATION = "R326" &SEC = "1" #&CDS_SEC = "1";
"A":   PN = "1"  !CDS_PN = "1";
"B":   PN = "2"  !CDS_PN = "2";
BODY = "Q_RES","I109": #LOCATION = "R323" !CDS_LOCATION = "R323" &SEC = "1" #&CDS_SEC = "1";
"A":   PN = "1"  !CDS_PN = "1";
"B":   PN = "2"  !CDS_PN = "2";
BODY = "Q_RES","I110": #LOCATION = "R324" !CDS_LOCATION = "R324" &SEC = "1" #&CDS_SEC = "1";
"A":   PN = "1"  !CDS_PN = "1";
"B":   PN = "2"  !CDS_PN = "2";
BODY = "IML3112Y2B000NCG8","I111": #LOCATION = "U213" !CDS_LOCATION = "U213" #SEC = "1" !CDS_SEC = "1";
"HSCL":   PN = "3"  !CDS_PN = "3";
"HSDA":   PN = "2"  !CDS_PN = "2";
"LSCL_0":   PN = "4"  !CDS_PN = "4";
"LSCL_1":   PN = "6"  !CDS_PN = "6";
"LSDA_0":   PN = "1"  !CDS_PN = "1";
"LSDA_1||HSA":   PN = "8"  !CDS_PN = "8";
"TH_GND":   PN = "9"  !CDS_PN = "9";
"VDD":   PN = "5"  !CDS_PN = "5";
"VIO":   PN = "7"  !CDS_PN = "7";
BODY = "Q_CAP","I112": #LOCATION = "C24" !CDS_LOCATION = "C24" &SEC = "1" #&CDS_SEC = "1";
"A":   PN = "1"  !CDS_PN = "1";
"B":   PN = "2"  !CDS_PN = "2";
BODY = "Q_CAP","I113": #LOCATION = "C9" !CDS_LOCATION = "C9" &SEC = "1" #&CDS_SEC = "1";
"A":   PN = "1"  !CDS_PN = "1";
"B":   PN = "2"  !CDS_PN = "2";
BODY = "PI3CSW12ZUAEX","I114": #LOCATION = "U4" !CDS_LOCATION = "U4" #SEC = "1" !CDS_SEC = "1";
"1D+":   PN = "1"  !CDS_PN = "1";
"1D-":   PN = "2"  !CDS_PN = "2";
"2D+":   PN = "3"  !CDS_PN = "3";
"2D-":   PN = "4"  !CDS_PN = "4";
"D+":   PN = "8"  !CDS_PN = "8";
"D-":   PN = "7"  !CDS_PN = "7";
"GND":   PN = "5"  !CDS_PN = "5";
"OE#":   PN = "6"  !CDS_PN = "6";
"S":   PN = "9"  !CDS_PN = "9";
"VDD":   PN = "10"  !CDS_PN = "10";
DRAWING = "@t6g_mb_lib.t6g(sch_1):page141";
BODY = "MOSFET_N_GSD","I89": #LOCATION = "Q61" !CDS_LOCATION = "Q61" &SEC = "1" #&CDS_SEC = "1";
"DRAIN":   PN = "D"  !CDS_PN = "D";
"GATE":   PN = "G"  !CDS_PN = "G";
"SOURCE":   PN = "S"  !CDS_PN = "S";
BODY = "Q_RES","I91": #LOCATION = "R1419" !CDS_LOCATION = "R1419" &SEC = "1" #&CDS_SEC = "1";
"A":   PN = "1"  !CDS_PN = "1";
"B":   PN = "2"  !CDS_PN = "2";
BODY = "SN74AVC4T774PWR","I117": #LOCATION = "U116" !CDS_LOCATION = "U116" &SEC = "1" #&CDS_SEC = "1";
"A1":   PN = "3"  !CDS_PN = "3";
"A2":   PN = "4"  !CDS_PN = "4";
"A3":   PN = "5"  !CDS_PN = "5";
"A4":   PN = "6"  !CDS_PN = "6";
"B1":   PN = "14"  !CDS_PN = "14";
"B2":   PN = "13"  !CDS_PN = "13";
"B3":   PN = "12"  !CDS_PN = "12";
"B4":   PN = "11"  !CDS_PN = "11";
"DIR1":   PN = "1"  !CDS_PN = "1";
"DIR2":   PN = "2"  !CDS_PN = "2";
"DIR3":   PN = "7"  !CDS_PN = "7";
"DIR4":   PN = "8"  !CDS_PN = "8";
"GND":   PN = "10"  !CDS_PN = "10";
"OE":   PN = "9"  !CDS_PN = "9";
"VCCA":   PN = "16"  !CDS_PN = "16";
"VCCB":   PN = "15"  !CDS_PN = "15";
BODY = "Q_CAP","I133": #LOCATION = "C1354" !CDS_LOCATION = "C1354" &SEC = "1" #&CDS_SEC = "1";
"A":   PN = "1"  !CDS_PN = "1";
"B":   PN = "2"  !CDS_PN = "2";
BODY = "Q_CAP","I137": #LOCATION = "C1352" !CDS_LOCATION = "C1352" &SEC = "1" #&CDS_SEC = "1";
"A":   PN = "1"  !CDS_PN = "1";
"B":   PN = "2"  !CDS_PN = "2";
BODY = "Q_RES","I185": #LOCATION = "R821" !CDS_LOCATION = "R821" &SEC = "1" #&CDS_SEC = "1";
"A":   PN = "1"  !CDS_PN = "1";
"B":   PN = "2"  !CDS_PN = "2";
BODY = "Q_RES","I186": #LOCATION = "R820" !CDS_LOCATION = "R820" &SEC = "1" #&CDS_SEC = "1";
"A":   PN = "1"  !CDS_PN = "1";
"B":   PN = "2"  !CDS_PN = "2";
BODY = "Q_CAP","I187": #LOCATION = "C364" !CDS_LOCATION = "C364" &SEC = "1" #&CDS_SEC = "1";
"A":   PN = "1"  !CDS_PN = "1";
"B":   PN = "2"  !CDS_PN = "2";
BODY = "Q_CAP","I190": #LOCATION = "C363" !CDS_LOCATION = "C363" &SEC = "1" #&CDS_SEC = "1";
"A":   PN = "1"  !CDS_PN = "1";
"B":   PN = "2"  !CDS_PN = "2";
BODY = "CONN4_HFK1040L0P1L7H","I195": #LOCATION = "J13" !CDS_LOCATION = "J13" &SEC = "1" #&CDS_SEC = "1";
"1":   PN = "1"  !CDS_PN = "1";
"2":   PN = "2"  !CDS_PN = "2";
"3":   PN = "3"  !CDS_PN = "3";
"4":   PN = "4"  !CDS_PN = "4";
BODY = "Q_RES","I196": #LOCATION = "R816" !CDS_LOCATION = "R816" &SEC = "1" #&CDS_SEC = "1";
"A":   PN = "1"  !CDS_PN = "1";
"B":   PN = "2"  !CDS_PN = "2";
BODY = "Q_RES","I197": #LOCATION = "R815" !CDS_LOCATION = "R815" &SEC = "1" #&CDS_SEC = "1";
"A":   PN = "1"  !CDS_PN = "1";
"B":   PN = "2"  !CDS_PN = "2";
BODY = "Q_RES","I198": #LOCATION = "R814" !CDS_LOCATION = "R814" &SEC = "1" #&CDS_SEC = "1";
"A":   PN = "1"  !CDS_PN = "1";
"B":   PN = "2"  !CDS_PN = "2";
BODY = "Q_RES","I199": #LOCATION = "R813" !CDS_LOCATION = "R813" &SEC = "1" #&CDS_SEC = "1";
"A":   PN = "1"  !CDS_PN = "1";
"B":   PN = "2"  !CDS_PN = "2";
BODY = "Q_RES","I203": #LOCATION = "R825" !CDS_LOCATION = "R825" &SEC = "1" #&CDS_SEC = "1";
"A":   PN = "1"  !CDS_PN = "1";
"B":   PN = "2"  !CDS_PN = "2";
BODY = "Q_RES","I204": #LOCATION = "R824" !CDS_LOCATION = "R824" &SEC = "1" #&CDS_SEC = "1";
"A":   PN = "1"  !CDS_PN = "1";
"B":   PN = "2"  !CDS_PN = "2";
BODY = "Q_RES","I205": #LOCATION = "R823" !CDS_LOCATION = "R823" &SEC = "1" #&CDS_SEC = "1";
"A":   PN = "1"  !CDS_PN = "1";
"B":   PN = "2"  !CDS_PN = "2";
BODY = "Q_RES","I206": #LOCATION = "R822" !CDS_LOCATION = "R822" &SEC = "1" #&CDS_SEC = "1";
"A":   PN = "1"  !CDS_PN = "1";
"B":   PN = "2"  !CDS_PN = "2";
BODY = "Q_RES","I211": #LOCATION = "R1253" !CDS_LOCATION = "R1253" &SEC = "1" #&CDS_SEC = "1";
"A":   PN = "1"  !CDS_PN = "1";
"B":   PN = "2"  !CDS_PN = "2";
BODY = "Q_RES","I212": #LOCATION = "R819" !CDS_LOCATION = "R819" &SEC = "1" #&CDS_SEC = "1";
"A":   PN = "1"  !CDS_PN = "1";
"B":   PN = "2"  !CDS_PN = "2";
BODY = "Q_RES","I220": #LOCATION = "R818" !CDS_LOCATION = "R818" &SEC = "1" #&CDS_SEC = "1";
"A":   PN = "1"  !CDS_PN = "1";
"B":   PN = "2"  !CDS_PN = "2";
BODY = "Q_RES","I221": #LOCATION = "R1425" !CDS_LOCATION = "R1425" &SEC = "1" #&CDS_SEC = "1";
"A":   PN = "1"  !CDS_PN = "1";
"B":   PN = "2"  !CDS_PN = "2";
BODY = "Q_RES","I231": #LOCATION = "R817" !CDS_LOCATION = "R817" &SEC = "1" #&CDS_SEC = "1";
"A":   PN = "1"  !CDS_PN = "1";
"B":   PN = "2"  !CDS_PN = "2";
BODY = "Q_RES","I232": #LOCATION = "R1423" !CDS_LOCATION = "R1423" &SEC = "1" #&CDS_SEC = "1";
"A":   PN = "1"  !CDS_PN = "1";
"B":   PN = "2"  !CDS_PN = "2";
DRAWING = "@t6g_mb_lib.t6g(sch_1):page143";
BODY = "Q_RES","I3": #LOCATION = "R950" !CDS_LOCATION = "R950" &SEC = "1" #&CDS_SEC = "1";
"A":   PN = "1"  !CDS_PN = "1";
"B":   PN = "2"  !CDS_PN = "2";
BODY = "Q_RES","I5": #LOCATION = "R946" !CDS_LOCATION = "R946" &SEC = "1" #&CDS_SEC = "1";
"A":   PN = "1"  !CDS_PN = "1";
"B":   PN = "2"  !CDS_PN = "2";
BODY = "Q_RES","I7": #LOCATION = "R948" !CDS_LOCATION = "R948" &SEC = "1" #&CDS_SEC = "1";
"A":   PN = "1"  !CDS_PN = "1";
"B":   PN = "2"  !CDS_PN = "2";
BODY = "Q_LED","I8": #LOCATION = "D5" !CDS_LOCATION = "D5" &SEC = "1" #&CDS_SEC = "1";
"A":   PN = "A"  !CDS_PN = "A";
"C":   PN = "C"  !CDS_PN = "C";
BODY = "Q_LED","I9": #LOCATION = "D6" !CDS_LOCATION = "D6" &SEC = "1" #&CDS_SEC = "1";
"A":   PN = "A"  !CDS_PN = "A";
"C":   PN = "C"  !CDS_PN = "C";
BODY = "Q_RES","I11": #LOCATION = "R947" !CDS_LOCATION = "R947" &SEC = "1" #&CDS_SEC = "1";
"A":   PN = "1"  !CDS_PN = "1";
"B":   PN = "2"  !CDS_PN = "2";
BODY = "Q_RES","I15": #LOCATION = "R944" !CDS_LOCATION = "R944" &SEC = "1" #&CDS_SEC = "1";
"A":   PN = "1"  !CDS_PN = "1";
"B":   PN = "2"  !CDS_PN = "2";
BODY = "MOSFET_DUAL_6P","I16": #LOCATION = "Q2" !CDS_LOCATION = "Q2" &SEC = "1" #&CDS_SEC = "1";
"D1":   PN = "6"  !CDS_PN = "6";
"D2":   PN = "3"  !CDS_PN = "3";
"G1":   PN = "2"  !CDS_PN = "2";
"G2":   PN = "5"  !CDS_PN = "5";
"S1":   PN = "1"  !CDS_PN = "1";
"S2":   PN = "4"  !CDS_PN = "4";
BODY = "Q_RES","I18": #LOCATION = "R945" !CDS_LOCATION = "R945" &SEC = "1" #&CDS_SEC = "1";
"A":   PN = "1"  !CDS_PN = "1";
"B":   PN = "2"  !CDS_PN = "2";
BODY = "MOSFET_DUAL_6P","I19": #LOCATION = "Q11" !CDS_LOCATION = "Q11" &SEC = "1" #&CDS_SEC = "1";
"D1":   PN = "6"  !CDS_PN = "6";
"D2":   PN = "3"  !CDS_PN = "3";
"G1":   PN = "2"  !CDS_PN = "2";
"G2":   PN = "5"  !CDS_PN = "5";
"S1":   PN = "1"  !CDS_PN = "1";
"S2":   PN = "4"  !CDS_PN = "4";
BODY = "Q_RES","I21": #LOCATION = "R935" !CDS_LOCATION = "R935" &SEC = "1" #&CDS_SEC = "1";
"A":   PN = "1"  !CDS_PN = "1";
"B":   PN = "2"  !CDS_PN = "2";
BODY = "Q_RES","I22": #LOCATION = "R936" !CDS_LOCATION = "R936" &SEC = "1" #&CDS_SEC = "1";
"A":   PN = "1"  !CDS_PN = "1";
"B":   PN = "2"  !CDS_PN = "2";
BODY = "Q_CAP","I24": #LOCATION = "C218" !CDS_LOCATION = "C218" &SEC = "1" #&CDS_SEC = "1";
"A":   PN = "1"  !CDS_PN = "1";
"B":   PN = "2"  !CDS_PN = "2";
BODY = "SN74LVC1G07DBVR","I26": #LOCATION = "U82" !CDS_LOCATION = "U82" &SEC = "1" #&CDS_SEC = "1";
"A":   PN = "2"  !CDS_PN = "2";
"GND":   PN = "3"  !CDS_PN = "3";
"NC":   PN = "1"  !CDS_PN = "1";
"VCC":   PN = "5"  !CDS_PN = "5";
"Y":   PN = "4"  !CDS_PN = "4";
BODY = "Q_CAP","I29": #LOCATION = "C219" !CDS_LOCATION = "C219" &SEC = "1" #&CDS_SEC = "1";
"A":   PN = "1"  !CDS_PN = "1";
"B":   PN = "2"  !CDS_PN = "2";
BODY = "SN74LVC1G07DBVR","I31": #LOCATION = "U86" !CDS_LOCATION = "U86" &SEC = "1" #&CDS_SEC = "1";
"A":   PN = "2"  !CDS_PN = "2";
"GND":   PN = "3"  !CDS_PN = "3";
"NC":   PN = "1"  !CDS_PN = "1";
"VCC":   PN = "5"  !CDS_PN = "5";
"Y":   PN = "4"  !CDS_PN = "4";
BODY = "Q_RES","I33": #LOCATION = "R934" !CDS_LOCATION = "R934" &SEC = "1" #&CDS_SEC = "1";
"A":   PN = "1"  !CDS_PN = "1";
"B":   PN = "2"  !CDS_PN = "2";
BODY = "Q_RES","I34": #LOCATION = "R941" !CDS_LOCATION = "R941" &SEC = "1" #&CDS_SEC = "1";
"A":   PN = "1"  !CDS_PN = "1";
"B":   PN = "2"  !CDS_PN = "2";
BODY = "Q_LED","I38": #LOCATION = "D49" !CDS_LOCATION = "D49" &SEC = "1" #&CDS_SEC = "1";
"A":   PN = "A"  !CDS_PN = "A";
"C":   PN = "C"  !CDS_PN = "C";
BODY = "Q_RES","I41": #LOCATION = "R1207" !CDS_LOCATION = "R1207" &SEC = "1" #&CDS_SEC = "1";
"A":   PN = "1"  !CDS_PN = "1";
"B":   PN = "2"  !CDS_PN = "2";
BODY = "Q_RES","I42": #LOCATION = "R1208" !CDS_LOCATION = "R1208" &SEC = "1" #&CDS_SEC = "1";
"A":   PN = "1"  !CDS_PN = "1";
"B":   PN = "2"  !CDS_PN = "2";
BODY = "Q_LED","I43": #LOCATION = "D46" !CDS_LOCATION = "D46" &SEC = "1" #&CDS_SEC = "1";
"A":   PN = "A"  !CDS_PN = "A";
"C":   PN = "C"  !CDS_PN = "C";
BODY = "MOSFET_N_GSD","I44": #LOCATION = "Q12" !CDS_LOCATION = "Q12" &SEC = "1" #&CDS_SEC = "1";
"DRAIN":   PN = "D"  !CDS_PN = "D";
"GATE":   PN = "G"  !CDS_PN = "G";
"SOURCE":   PN = "S"  !CDS_PN = "S";
DRAWING = "@t6g_mb_lib.t6g(sch_1):page144";
BODY = "SN74LVC1G07DBVR","I38": #LOCATION = "U124" !CDS_LOCATION = "U124" &SEC = "1" #&CDS_SEC = "1";
"A":   PN = "2"  !CDS_PN = "2";
"GND":   PN = "3"  !CDS_PN = "3";
"NC":   PN = "1"  !CDS_PN = "1";
"VCC":   PN = "5"  !CDS_PN = "5";
"Y":   PN = "4"  !CDS_PN = "4";
BODY = "Q_CAP","I39": #LOCATION = "C693" !CDS_LOCATION = "C693" &SEC = "1" #&CDS_SEC = "1";
"A":   PN = "1"  !CDS_PN = "1";
"B":   PN = "2"  !CDS_PN = "2";
BODY = "Q_RES","I6": #LOCATION = "R1508" !CDS_LOCATION = "R1508" &SEC = "1" #&CDS_SEC = "1";
"A":   PN = "1"  !CDS_PN = "1";
"B":   PN = "2"  !CDS_PN = "2";
BODY = "Q_RES","I15": #LOCATION = "R1261" !CDS_LOCATION = "R1261" &SEC = "1" #&CDS_SEC = "1";
"A":   PN = "1"  !CDS_PN = "1";
"B":   PN = "2"  !CDS_PN = "2";
BODY = "Q_RES","I17": #LOCATION = "R744" !CDS_LOCATION = "R744" &SEC = "1" #&CDS_SEC = "1";
"A":   PN = "1"  !CDS_PN = "1";
"B":   PN = "2"  !CDS_PN = "2";
BODY = "Q_RES","I19": #LOCATION = "R734" !CDS_LOCATION = "R734" &SEC = "1" #&CDS_SEC = "1";
"A":   PN = "1"  !CDS_PN = "1";
"B":   PN = "2"  !CDS_PN = "2";
BODY = "Q_RES","I30": #LOCATION = "R1262" !CDS_LOCATION = "R1262" &SEC = "1" #&CDS_SEC = "1";
"A":   PN = "1"  !CDS_PN = "1";
"B":   PN = "2"  !CDS_PN = "2";
BODY = "Q_RES","I33": #LOCATION = "R6044" !CDS_LOCATION = "R6044" &SEC = "1" #&CDS_SEC = "1";
"A":   PN = "1"  !CDS_PN = "1";
"B":   PN = "2"  !CDS_PN = "2";
BODY = "Q_RES","I34": #LOCATION = "R5071" !CDS_LOCATION = "R5071" &SEC = "1" #&CDS_SEC = "1";
"A":   PN = "1"  !CDS_PN = "1";
"B":   PN = "2"  !CDS_PN = "2";
BODY = "Q_RES","I44": #LOCATION = "R1264" !CDS_LOCATION = "R1264" &SEC = "1" #&CDS_SEC = "1";
"A":   PN = "1"  !CDS_PN = "1";
"B":   PN = "2"  !CDS_PN = "2";
BODY = "Q_RES","I47": #LOCATION = "R8" !CDS_LOCATION = "R8" &SEC = "1" #&CDS_SEC = "1";
"A":   PN = "1"  !CDS_PN = "1";
"B":   PN = "2"  !CDS_PN = "2";
BODY = "Q_RES","I50": #LOCATION = "R733" !CDS_LOCATION = "R733" &SEC = "1" #&CDS_SEC = "1";
"A":   PN = "1"  !CDS_PN = "1";
"B":   PN = "2"  !CDS_PN = "2";
BODY = "Q_RES","I52": #LOCATION = "R1265" !CDS_LOCATION = "R1265" &SEC = "1" #&CDS_SEC = "1";
"A":   PN = "1"  !CDS_PN = "1";
"B":   PN = "2"  !CDS_PN = "2";
BODY = "Q_RES","I54": #LOCATION = "R22" !CDS_LOCATION = "R22" &SEC = "1" #&CDS_SEC = "1";
"A":   PN = "1"  !CDS_PN = "1";
"B":   PN = "2"  !CDS_PN = "2";
BODY = "Q_RES","I61": #LOCATION = "R6043" !CDS_LOCATION = "R6043" &SEC = "1" #&CDS_SEC = "1";
"A":   PN = "1"  !CDS_PN = "1";
"B":   PN = "2"  !CDS_PN = "2";
BODY = "Q_RES","I62": #LOCATION = "R6042" !CDS_LOCATION = "R6042" &SEC = "1" #&CDS_SEC = "1";
"A":   PN = "1"  !CDS_PN = "1";
"B":   PN = "2"  !CDS_PN = "2";
BODY = "Q_RES","I69": #LOCATION = "R6041" !CDS_LOCATION = "R6041" &SEC = "1" #&CDS_SEC = "1";
"A":   PN = "1"  !CDS_PN = "1";
"B":   PN = "2"  !CDS_PN = "2";
BODY = "Q_RES","I70": #LOCATION = "R6040" !CDS_LOCATION = "R6040" &SEC = "1" #&CDS_SEC = "1";
"A":   PN = "1"  !CDS_PN = "1";
"B":   PN = "2"  !CDS_PN = "2";
BODY = "Q_RES","I72": #LOCATION = "R1358" !CDS_LOCATION = "R1358" &SEC = "1" #&CDS_SEC = "1";
"A":   PN = "1"  !CDS_PN = "1";
"B":   PN = "2"  !CDS_PN = "2";
BODY = "Q_RES","I74": #LOCATION = "R1357" !CDS_LOCATION = "R1357" &SEC = "1" #&CDS_SEC = "1";
"A":   PN = "1"  !CDS_PN = "1";
"B":   PN = "2"  !CDS_PN = "2";
BODY = "Q_RES","I77": #LOCATION = "R1356" !CDS_LOCATION = "R1356" &SEC = "1" #&CDS_SEC = "1";
"A":   PN = "1"  !CDS_PN = "1";
"B":   PN = "2"  !CDS_PN = "2";
BODY = "Q_RES","I81": #LOCATION = "R6106" !CDS_LOCATION = "R6106" &SEC = "1" #&CDS_SEC = "1";
"A":   PN = "1"  !CDS_PN = "1";
"B":   PN = "2"  !CDS_PN = "2";
BODY = "Q_RES","I83": #LOCATION = "R6107" !CDS_LOCATION = "R6107" &SEC = "1" #&CDS_SEC = "1";
"A":   PN = "1"  !CDS_PN = "1";
"B":   PN = "2"  !CDS_PN = "2";
BODY = "Q_RES","I84": #LOCATION = "R8018" !CDS_LOCATION = "R8018" &SEC = "1" #&CDS_SEC = "1";
"A":   PN = "1"  !CDS_PN = "1";
"B":   PN = "2"  !CDS_PN = "2";
BODY = "Q_RES","I85": #LOCATION = "R8017" !CDS_LOCATION = "R8017" #SEC = "1" !CDS_SEC = "1";
"A":   PN = "1"  !CDS_PN = "1";
"B":   PN = "2"  !CDS_PN = "2";
BODY = "Q_RES","I89": #LOCATION = "R8019" !CDS_LOCATION = "R8019" &SEC = "1" #&CDS_SEC = "1";
"A":   PN = "1"  !CDS_PN = "1";
"B":   PN = "2"  !CDS_PN = "2";
BODY = "SW20S_DHNF10FQTR","I90": #LOCATION = "SW1" !CDS_LOCATION = "SW1" #SEC = "1" !CDS_SEC = "1";
"1":   PN = "1"  !CDS_PN = "1";
"2":   PN = "2"  !CDS_PN = "2";
"3":   PN = "3"  !CDS_PN = "3";
"4":   PN = "4"  !CDS_PN = "4";
"5":   PN = "5"  !CDS_PN = "5";
"6":   PN = "6"  !CDS_PN = "6";
"7":   PN = "7"  !CDS_PN = "7";
"8":   PN = "8"  !CDS_PN = "8";
"9":   PN = "9"  !CDS_PN = "9";
"10":   PN = "10"  !CDS_PN = "10";
"11":   PN = "11"  !CDS_PN = "11";
"12":   PN = "12"  !CDS_PN = "12";
"13":   PN = "13"  !CDS_PN = "13";
"14":   PN = "14"  !CDS_PN = "14";
"15":   PN = "15"  !CDS_PN = "15";
"16":   PN = "16"  !CDS_PN = "16";
"17":   PN = "17"  !CDS_PN = "17";
"18":   PN = "18"  !CDS_PN = "18";
"19":   PN = "19"  !CDS_PN = "19";
"20":   PN = "20"  !CDS_PN = "20";
DRAWING = "@t6g_mb_lib.t6g(sch_1):page148";
BODY = "Q_RES","I244": #LOCATION = "R1734" !CDS_LOCATION = "R1734" &SEC = "1" #&CDS_SEC = "1";
"A":   PN = "1"  !CDS_PN = "1";
"B":   PN = "2"  !CDS_PN = "2";
BODY = "Q_RES","I245": #LOCATION = "R1731" !CDS_LOCATION = "R1731" &SEC = "1" #&CDS_SEC = "1";
"A":   PN = "1"  !CDS_PN = "1";
"B":   PN = "2"  !CDS_PN = "2";
BODY = "Q_RES","I246": #LOCATION = "R1735" !CDS_LOCATION = "R1735" &SEC = "1" #&CDS_SEC = "1";
"A":   PN = "1"  !CDS_PN = "1";
"B":   PN = "2"  !CDS_PN = "2";
BODY = "Q_RES","I249": #LOCATION = "R1728" !CDS_LOCATION = "R1728" &SEC = "1" #&CDS_SEC = "1";
"A":   PN = "1"  !CDS_PN = "1";
"B":   PN = "2"  !CDS_PN = "2";
BODY = "Q_RES","I250": #LOCATION = "R1727" !CDS_LOCATION = "R1727" &SEC = "1" #&CDS_SEC = "1";
"A":   PN = "1"  !CDS_PN = "1";
"B":   PN = "2"  !CDS_PN = "2";
BODY = "Q_RES","I255": #LOCATION = "R1747" !CDS_LOCATION = "R1747" &SEC = "1" #&CDS_SEC = "1";
"A":   PN = "1"  !CDS_PN = "1";
"B":   PN = "2"  !CDS_PN = "2";
BODY = "Q_RES","I256": #LOCATION = "R1746" !CDS_LOCATION = "R1746" &SEC = "1" #&CDS_SEC = "1";
"A":   PN = "1"  !CDS_PN = "1";
"B":   PN = "2"  !CDS_PN = "2";
BODY = "Q_RES","I257": #LOCATION = "R1745" !CDS_LOCATION = "R1745" &SEC = "1" #&CDS_SEC = "1";
"A":   PN = "1"  !CDS_PN = "1";
"B":   PN = "2"  !CDS_PN = "2";
BODY = "Q_RES","I258": #LOCATION = "R1748" !CDS_LOCATION = "R1748" &SEC = "1" #&CDS_SEC = "1";
"A":   PN = "1"  !CDS_PN = "1";
"B":   PN = "2"  !CDS_PN = "2";
BODY = "Q_RES","I261": #LOCATION = "R1744" !CDS_LOCATION = "R1744" &SEC = "1" #&CDS_SEC = "1";
"A":   PN = "1"  !CDS_PN = "1";
"B":   PN = "2"  !CDS_PN = "2";
BODY = "74LV4052PW","I266": #LOCATION = "U160" !CDS_LOCATION = "U160" #SEC = "1" !CDS_SEC = "1";
"1Y0":   PN = "12"  !CDS_PN = "12";
"1Y1":   PN = "14"  !CDS_PN = "14";
"1Y2":   PN = "15"  !CDS_PN = "15";
"1Y3":   PN = "11"  !CDS_PN = "11";
"1Z":   PN = "13"  !CDS_PN = "13";
"2Y0":   PN = "1"  !CDS_PN = "1";
"2Y1":   PN = "5"  !CDS_PN = "5";
"2Y2":   PN = "2"  !CDS_PN = "2";
"2Y3":   PN = "4"  !CDS_PN = "4";
"2Z":   PN = "3"  !CDS_PN = "3";
"E_N":   PN = "6"  !CDS_PN = "6";
"GND":   PN = "8"  !CDS_PN = "8";
"S0":   PN = "10"  !CDS_PN = "10";
"S1":   PN = "9"  !CDS_PN = "9";
"VCC":   PN = "16"  !CDS_PN = "16";
"VEE":   PN = "7"  !CDS_PN = "7";
BODY = "Q_CAP","I293": #LOCATION = "C1554" !CDS_LOCATION = "C1554" &SEC = "1" #&CDS_SEC = "1";
"A":   PN = "1"  !CDS_PN = "1";
"B":   PN = "2"  !CDS_PN = "2";
BODY = "Q_CAP","I299": #LOCATION = "C194" !CDS_LOCATION = "C194" &SEC = "1" #&CDS_SEC = "1";
"A":   PN = "1"  !CDS_PN = "1";
"B":   PN = "2"  !CDS_PN = "2";
BODY = "74LV4052PW","I302": #LOCATION = "U212" !CDS_LOCATION = "U212" #SEC = "1" !CDS_SEC = "1";
"1Y0":   PN = "12"  !CDS_PN = "12";
"1Y1":   PN = "14"  !CDS_PN = "14";
"1Y2":   PN = "15"  !CDS_PN = "15";
"1Y3":   PN = "11"  !CDS_PN = "11";
"1Z":   PN = "13"  !CDS_PN = "13";
"2Y0":   PN = "1"  !CDS_PN = "1";
"2Y1":   PN = "5"  !CDS_PN = "5";
"2Y2":   PN = "2"  !CDS_PN = "2";
"2Y3":   PN = "4"  !CDS_PN = "4";
"2Z":   PN = "3"  !CDS_PN = "3";
"E_N":   PN = "6"  !CDS_PN = "6";
"GND":   PN = "8"  !CDS_PN = "8";
"S0":   PN = "10"  !CDS_PN = "10";
"S1":   PN = "9"  !CDS_PN = "9";
"VCC":   PN = "16"  !CDS_PN = "16";
"VEE":   PN = "7"  !CDS_PN = "7";
BODY = "Q_RES","I305": #LOCATION = "R1730" !CDS_LOCATION = "R1730" &SEC = "1" #&CDS_SEC = "1";
"A":   PN = "1"  !CDS_PN = "1";
"B":   PN = "2"  !CDS_PN = "2";
BODY = "Q_RES","I306": #LOCATION = "R1729" !CDS_LOCATION = "R1729" &SEC = "1" #&CDS_SEC = "1";
"A":   PN = "1"  !CDS_PN = "1";
"B":   PN = "2"  !CDS_PN = "2";
BODY = "Q_RES","I309": #LOCATION = "R1659" !CDS_LOCATION = "R1659" &SEC = "1" #&CDS_SEC = "1";
"A":   PN = "1"  !CDS_PN = "1";
"B":   PN = "2"  !CDS_PN = "2";
BODY = "Q_RES","I310": #LOCATION = "R1658" !CDS_LOCATION = "R1658" &SEC = "1" #&CDS_SEC = "1";
"A":   PN = "1"  !CDS_PN = "1";
"B":   PN = "2"  !CDS_PN = "2";
BODY = "Q_RES","I332": #LOCATION = "R1743" !CDS_LOCATION = "R1743" &SEC = "1" #&CDS_SEC = "1";
"A":   PN = "1"  !CDS_PN = "1";
"B":   PN = "2"  !CDS_PN = "2";
BODY = "Q_RES","I339": #LOCATION = "R1343" !CDS_LOCATION = "R1343" &SEC = "1" #&CDS_SEC = "1";
"A":   PN = "1"  !CDS_PN = "1";
"B":   PN = "2"  !CDS_PN = "2";
BODY = "SN74LVC1G07DBVR","I340": #LOCATION = "U99" !CDS_LOCATION = "U99" &SEC = "1" #&CDS_SEC = "1";
"A":   PN = "2"  !CDS_PN = "2";
"GND":   PN = "3"  !CDS_PN = "3";
"NC":   PN = "1"  !CDS_PN = "1";
"VCC":   PN = "5"  !CDS_PN = "5";
"Y":   PN = "4"  !CDS_PN = "4";
BODY = "Q_CAP","I342": #LOCATION = "C553" !CDS_LOCATION = "C553" &SEC = "1" #&CDS_SEC = "1";
"A":   PN = "1"  !CDS_PN = "1";
"B":   PN = "2"  !CDS_PN = "2";
BODY = "Q_RES","I349": #LOCATION = "R1738" !CDS_LOCATION = "R1738" &SEC = "1" #&CDS_SEC = "1";
"A":   PN = "1"  !CDS_PN = "1";
"B":   PN = "2"  !CDS_PN = "2";
BODY = "Q_RES","I352": #LOCATION = "R1742" !CDS_LOCATION = "R1742" &SEC = "1" #&CDS_SEC = "1";
"A":   PN = "1"  !CDS_PN = "1";
"B":   PN = "2"  !CDS_PN = "2";
BODY = "Q_RES","I357": #LOCATION = "R1737" !CDS_LOCATION = "R1737" &SEC = "1" #&CDS_SEC = "1";
"A":   PN = "1"  !CDS_PN = "1";
"B":   PN = "2"  !CDS_PN = "2";
BODY = "Q_RES","I363": #LOCATION = "R1736" !CDS_LOCATION = "R1736" &SEC = "1" #&CDS_SEC = "1";
"A":   PN = "1"  !CDS_PN = "1";
"B":   PN = "2"  !CDS_PN = "2";
BODY = "Q_RES","I366": #LOCATION = "R1741" !CDS_LOCATION = "R1741" &SEC = "1" #&CDS_SEC = "1";
"A":   PN = "1"  !CDS_PN = "1";
"B":   PN = "2"  !CDS_PN = "2";
BODY = "Q_RES","I368": #LOCATION = "R1740" !CDS_LOCATION = "R1740" &SEC = "1" #&CDS_SEC = "1";
"A":   PN = "1"  !CDS_PN = "1";
"B":   PN = "2"  !CDS_PN = "2";
BODY = "Q_RES","I369": #LOCATION = "R1342" !CDS_LOCATION = "R1342" &SEC = "1" #&CDS_SEC = "1";
"A":   PN = "1"  !CDS_PN = "1";
"B":   PN = "2"  !CDS_PN = "2";
BODY = "Q_RES","I375": #LOCATION = "R6101" !CDS_LOCATION = "R6101" &SEC = "1" #&CDS_SEC = "1";
"A":   PN = "1"  !CDS_PN = "1";
"B":   PN = "2"  !CDS_PN = "2";
BODY = "Q_RES","I376": #LOCATION = "R6102" !CDS_LOCATION = "R6102" &SEC = "1" #&CDS_SEC = "1";
"A":   PN = "1"  !CDS_PN = "1";
"B":   PN = "2"  !CDS_PN = "2";
BODY = "Q_RES","I378": #LOCATION = "R1318" !CDS_LOCATION = "R1318" &SEC = "1" #&CDS_SEC = "1";
"A":   PN = "1"  !CDS_PN = "1";
"B":   PN = "2"  !CDS_PN = "2";
BODY = "Q_RES","I381": #LOCATION = "R6181" !CDS_LOCATION = "R6181" &SEC = "1" #&CDS_SEC = "1";
"A":   PN = "1"  !CDS_PN = "1";
"B":   PN = "2"  !CDS_PN = "2";
BODY = "Q_RES","I383": #LOCATION = "R1313" !CDS_LOCATION = "R1313" &SEC = "1" #&CDS_SEC = "1";
"A":   PN = "1"  !CDS_PN = "1";
"B":   PN = "2"  !CDS_PN = "2";
BODY = "Q_RES","I384": #LOCATION = "R6182" !CDS_LOCATION = "R6182" &SEC = "1" #&CDS_SEC = "1";
"A":   PN = "1"  !CDS_PN = "1";
"B":   PN = "2"  !CDS_PN = "2";
BODY = "CONN3_210HP1030BR1","I386": #LOCATION = "JP6000" !CDS_LOCATION = "JP6000" #SEC = "1" !CDS_SEC = "1";
"1":   PN = "1"  !CDS_PN = "1";
"2":   PN = "2"  !CDS_PN = "2";
"3":   PN = "3"  !CDS_PN = "3";
BODY = "CONN3_210HP1030BR1","I387": #LOCATION = "JP6001" !CDS_LOCATION = "JP6001" &SEC = "1" #&CDS_SEC = "1";
"1":   PN = "1"  !CDS_PN = "1";
"2":   PN = "2"  !CDS_PN = "2";
"3":   PN = "3"  !CDS_PN = "3";
BODY = "Q_RES","I388": #LOCATION = "R1739" !CDS_LOCATION = "R1739" &SEC = "1" #&CDS_SEC = "1";
"A":   PN = "1"  !CDS_PN = "1";
"B":   PN = "2"  !CDS_PN = "2";
DRAWING = "@t6g_mb_lib.t6g(sch_1):page149";
BODY = "SN74AVC2T245RSWR","I1": #LOCATION = "U147" !CDS_LOCATION = "U147" &SEC = "1" #&CDS_SEC = "1";
"A1":   PN = "8"  !CDS_PN = "8";
"A2":   PN = "9"  !CDS_PN = "9";
"B1":   PN = "5"  !CDS_PN = "5";
"B2":   PN = "4"  !CDS_PN = "4";
"DIR1":   PN = "10"  !CDS_PN = "10";
"DIR2":   PN = "1"  !CDS_PN = "1";
"GND":   PN = "3"  !CDS_PN = "3";
"OE_#":   PN = "2"  !CDS_PN = "2";
"VCCA":   PN = "7"  !CDS_PN = "7";
"VCCB":   PN = "6"  !CDS_PN = "6";
BODY = "Q_RES","I7": #LOCATION = "R1633" !CDS_LOCATION = "R1633" &SEC = "1" #&CDS_SEC = "1";
"A":   PN = "1"  !CDS_PN = "1";
"B":   PN = "2"  !CDS_PN = "2";
BODY = "Q_RES","I8": #LOCATION = "R1635" !CDS_LOCATION = "R1635" &SEC = "1" #&CDS_SEC = "1";
"A":   PN = "1"  !CDS_PN = "1";
"B":   PN = "2"  !CDS_PN = "2";
BODY = "Q_RES","I9": #LOCATION = "R1636" !CDS_LOCATION = "R1636" &SEC = "1" #&CDS_SEC = "1";
"A":   PN = "1"  !CDS_PN = "1";
"B":   PN = "2"  !CDS_PN = "2";
BODY = "Q_CAP","I10": #LOCATION = "C1509" !CDS_LOCATION = "C1509" &SEC = "1" #&CDS_SEC = "1";
"A":   PN = "1"  !CDS_PN = "1";
"B":   PN = "2"  !CDS_PN = "2";
BODY = "Q_CAP","I21": #LOCATION = "C1512" !CDS_LOCATION = "C1512" &SEC = "1" #&CDS_SEC = "1";
"A":   PN = "1"  !CDS_PN = "1";
"B":   PN = "2"  !CDS_PN = "2";
BODY = "Q_CAP","I23": #LOCATION = "C1511" !CDS_LOCATION = "C1511" &SEC = "1" #&CDS_SEC = "1";
"A":   PN = "1"  !CDS_PN = "1";
"B":   PN = "2"  !CDS_PN = "2";
BODY = "Q_CAP","I25": #LOCATION = "C1510" !CDS_LOCATION = "C1510" &SEC = "1" #&CDS_SEC = "1";
"A":   PN = "1"  !CDS_PN = "1";
"B":   PN = "2"  !CDS_PN = "2";
BODY = "Q_CAP","I29": #LOCATION = "C1508" !CDS_LOCATION = "C1508" &SEC = "1" #&CDS_SEC = "1";
"A":   PN = "1"  !CDS_PN = "1";
"B":   PN = "2"  !CDS_PN = "2";
BODY = "SN74AVC4T774PWR","I31": #LOCATION = "U149" !CDS_LOCATION = "U149" &SEC = "1" #&CDS_SEC = "1";
"A1":   PN = "3"  !CDS_PN = "3";
"A2":   PN = "4"  !CDS_PN = "4";
"A3":   PN = "5"  !CDS_PN = "5";
"A4":   PN = "6"  !CDS_PN = "6";
"B1":   PN = "14"  !CDS_PN = "14";
"B2":   PN = "13"  !CDS_PN = "13";
"B3":   PN = "12"  !CDS_PN = "12";
"B4":   PN = "11"  !CDS_PN = "11";
"DIR1":   PN = "1"  !CDS_PN = "1";
"DIR2":   PN = "2"  !CDS_PN = "2";
"DIR3":   PN = "7"  !CDS_PN = "7";
"DIR4":   PN = "8"  !CDS_PN = "8";
"GND":   PN = "10"  !CDS_PN = "10";
"OE":   PN = "9"  !CDS_PN = "9";
"VCCA":   PN = "16"  !CDS_PN = "16";
"VCCB":   PN = "15"  !CDS_PN = "15";
BODY = "SN74AVC4T774PWR","I34": #LOCATION = "U148" !CDS_LOCATION = "U148" &SEC = "1" #&CDS_SEC = "1";
"A1":   PN = "3"  !CDS_PN = "3";
"A2":   PN = "4"  !CDS_PN = "4";
"A3":   PN = "5"  !CDS_PN = "5";
"A4":   PN = "6"  !CDS_PN = "6";
"B1":   PN = "14"  !CDS_PN = "14";
"B2":   PN = "13"  !CDS_PN = "13";
"B3":   PN = "12"  !CDS_PN = "12";
"B4":   PN = "11"  !CDS_PN = "11";
"DIR1":   PN = "1"  !CDS_PN = "1";
"DIR2":   PN = "2"  !CDS_PN = "2";
"DIR3":   PN = "7"  !CDS_PN = "7";
"DIR4":   PN = "8"  !CDS_PN = "8";
"GND":   PN = "10"  !CDS_PN = "10";
"OE":   PN = "9"  !CDS_PN = "9";
"VCCA":   PN = "16"  !CDS_PN = "16";
"VCCB":   PN = "15"  !CDS_PN = "15";
BODY = "Q_CAP","I41": #LOCATION = "C1507" !CDS_LOCATION = "C1507" &SEC = "1" #&CDS_SEC = "1";
"A":   PN = "1"  !CDS_PN = "1";
"B":   PN = "2"  !CDS_PN = "2";
BODY = "Q_RES","I53": #LOCATION = "R1625" !CDS_LOCATION = "R1625" &SEC = "1" #&CDS_SEC = "1";
"A":   PN = "1"  !CDS_PN = "1";
"B":   PN = "2"  !CDS_PN = "2";
BODY = "Q_CAP","I56": #LOCATION = "C1504" !CDS_LOCATION = "C1504" &SEC = "1" #&CDS_SEC = "1";
"A":   PN = "1"  !CDS_PN = "1";
"B":   PN = "2"  !CDS_PN = "2";
BODY = "Q_CAP","I62": #LOCATION = "C1506" !CDS_LOCATION = "C1506" &SEC = "1" #&CDS_SEC = "1";
"A":   PN = "1"  !CDS_PN = "1";
"B":   PN = "2"  !CDS_PN = "2";
BODY = "Q_CAP","I74": #LOCATION = "C1505" !CDS_LOCATION = "C1505" &SEC = "1" #&CDS_SEC = "1";
"A":   PN = "1"  !CDS_PN = "1";
"B":   PN = "2"  !CDS_PN = "2";
BODY = "SN74AVC2T245RSWR","I76": #LOCATION = "U146" !CDS_LOCATION = "U146" &SEC = "1" #&CDS_SEC = "1";
"A1":   PN = "8"  !CDS_PN = "8";
"A2":   PN = "9"  !CDS_PN = "9";
"B1":   PN = "5"  !CDS_PN = "5";
"B2":   PN = "4"  !CDS_PN = "4";
"DIR1":   PN = "10"  !CDS_PN = "10";
"DIR2":   PN = "1"  !CDS_PN = "1";
"GND":   PN = "3"  !CDS_PN = "3";
"OE_#":   PN = "2"  !CDS_PN = "2";
"VCCA":   PN = "7"  !CDS_PN = "7";
"VCCB":   PN = "6"  !CDS_PN = "6";
BODY = "Q_CAP","I80": #LOCATION = "C1503" !CDS_LOCATION = "C1503" &SEC = "1" #&CDS_SEC = "1";
"A":   PN = "1"  !CDS_PN = "1";
"B":   PN = "2"  !CDS_PN = "2";
BODY = "Q_RES","I83": #LOCATION = "R1622" !CDS_LOCATION = "R1622" &SEC = "1" #&CDS_SEC = "1";
"A":   PN = "1"  !CDS_PN = "1";
"B":   PN = "2"  !CDS_PN = "2";
BODY = "Q_RES","I92": #LOCATION = "R1619" !CDS_LOCATION = "R1619" &SEC = "1" #&CDS_SEC = "1";
"A":   PN = "1"  !CDS_PN = "1";
"B":   PN = "2"  !CDS_PN = "2";
BODY = "Q_RES","I96": #LOCATION = "R1634" !CDS_LOCATION = "R1634" &SEC = "1" #&CDS_SEC = "1";
"A":   PN = "1"  !CDS_PN = "1";
"B":   PN = "2"  !CDS_PN = "2";
BODY = "Q_RES","I101": #LOCATION = "R617" !CDS_LOCATION = "R617" &SEC = "1" #&CDS_SEC = "1";
"A":   PN = "1"  !CDS_PN = "1";
"B":   PN = "2"  !CDS_PN = "2";
BODY = "MOSFET_N","I102": #LOCATION = "Q62" !CDS_LOCATION = "Q62" &SEC = "1" #&CDS_SEC = "1";
"DRAIN":   PN = "D"  !CDS_PN = "D";
"GATE":   PN = "G"  !CDS_PN = "G";
"SOURCE":   PN = "S"  !CDS_PN = "S";
BODY = "Q_RES","I109": #LOCATION = "R1354" !CDS_LOCATION = "R1354" &SEC = "1" #&CDS_SEC = "1";
"A":   PN = "1"  !CDS_PN = "1";
"B":   PN = "2"  !CDS_PN = "2";
BODY = "Q_RES","I111": #LOCATION = "R1624" !CDS_LOCATION = "R1624" &SEC = "1" #&CDS_SEC = "1";
"A":   PN = "1"  !CDS_PN = "1";
"B":   PN = "2"  !CDS_PN = "2";
BODY = "Q_RES","I112": #LOCATION = "R1629" !CDS_LOCATION = "R1629" &SEC = "1" #&CDS_SEC = "1";
"A":   PN = "1"  !CDS_PN = "1";
"B":   PN = "2"  !CDS_PN = "2";
BODY = "Q_RES","I113": #LOCATION = "R1631" !CDS_LOCATION = "R1631" &SEC = "1" #&CDS_SEC = "1";
"A":   PN = "1"  !CDS_PN = "1";
"B":   PN = "2"  !CDS_PN = "2";
BODY = "Q_RES","I114": #LOCATION = "R1632" !CDS_LOCATION = "R1632" &SEC = "1" #&CDS_SEC = "1";
"A":   PN = "1"  !CDS_PN = "1";
"B":   PN = "2"  !CDS_PN = "2";
BODY = "Q_RES","I115": #LOCATION = "R1626" !CDS_LOCATION = "R1626" &SEC = "1" #&CDS_SEC = "1";
"A":   PN = "1"  !CDS_PN = "1";
"B":   PN = "2"  !CDS_PN = "2";
BODY = "Q_RES","I116": #LOCATION = "R1627" !CDS_LOCATION = "R1627" &SEC = "1" #&CDS_SEC = "1";
"A":   PN = "1"  !CDS_PN = "1";
"B":   PN = "2"  !CDS_PN = "2";
BODY = "Q_RES","I117": #LOCATION = "R1628" !CDS_LOCATION = "R1628" &SEC = "1" #&CDS_SEC = "1";
"A":   PN = "1"  !CDS_PN = "1";
"B":   PN = "2"  !CDS_PN = "2";
BODY = "Q_RES","I118": #LOCATION = "R1630" !CDS_LOCATION = "R1630" &SEC = "1" #&CDS_SEC = "1";
"A":   PN = "1"  !CDS_PN = "1";
"B":   PN = "2"  !CDS_PN = "2";
BODY = "Q_CAP","I123": #LOCATION = "C551" !CDS_LOCATION = "C551" &SEC = "1" #&CDS_SEC = "1";
"A":   PN = "1"  !CDS_PN = "1";
"B":   PN = "2"  !CDS_PN = "2";
BODY = "Q_RES","I132": #LOCATION = "R1352" !CDS_LOCATION = "R1352" &SEC = "1" #&CDS_SEC = "1";
"A":   PN = "1"  !CDS_PN = "1";
"B":   PN = "2"  !CDS_PN = "2";
BODY = "Q_RES","I133": #LOCATION = "R1353" !CDS_LOCATION = "R1353" &SEC = "1" #&CDS_SEC = "1";
"A":   PN = "1"  !CDS_PN = "1";
"B":   PN = "2"  !CDS_PN = "2";
BODY = "Q_CAP","I134": #LOCATION = "C87" !CDS_LOCATION = "C87" &SEC = "1" #&CDS_SEC = "1";
"A":   PN = "1"  !CDS_PN = "1";
"B":   PN = "2"  !CDS_PN = "2";
BODY = "Q_CAP","I137": #LOCATION = "C605" !CDS_LOCATION = "C605" &SEC = "1" #&CDS_SEC = "1";
"A":   PN = "1"  !CDS_PN = "1";
"B":   PN = "2"  !CDS_PN = "2";
BODY = "Q_CAP","I140": #LOCATION = "C604" !CDS_LOCATION = "C604" &SEC = "1" #&CDS_SEC = "1";
"A":   PN = "1"  !CDS_PN = "1";
"B":   PN = "2"  !CDS_PN = "2";
BODY = "SCONN20_HSU2101L00007H","I142": #LOCATION = "J54" !CDS_LOCATION = "J54" &SEC = "1" #&CDS_SEC = "1";
"1":   PN = "1"  !CDS_PN = "1";
"2":   PN = "2"  !CDS_PN = "2";
"3":   PN = "3"  !CDS_PN = "3";
"4":   PN = "4"  !CDS_PN = "4";
"5":   PN = "5"  !CDS_PN = "5";
"6":   PN = "6"  !CDS_PN = "6";
"7":   PN = "7"  !CDS_PN = "7";
"8":   PN = "8"  !CDS_PN = "8";
"9":   PN = "9"  !CDS_PN = "9";
"10":   PN = "10"  !CDS_PN = "10";
"11":   PN = "11"  !CDS_PN = "11";
"12":   PN = "12"  !CDS_PN = "12";
"13":   PN = "13"  !CDS_PN = "13";
"14":   PN = "14"  !CDS_PN = "14";
"15":   PN = "15"  !CDS_PN = "15";
"16":   PN = "16"  !CDS_PN = "16";
"17":   PN = "17"  !CDS_PN = "17";
"18":   PN = "18"  !CDS_PN = "18";
"19":   PN = "19"  !CDS_PN = "19";
"20":   PN = "20"  !CDS_PN = "20";
BODY = "Q_RES","I146": #LOCATION = "R1621" !CDS_LOCATION = "R1621" &SEC = "1" #&CDS_SEC = "1";
"A":   PN = "1"  !CDS_PN = "1";
"B":   PN = "2"  !CDS_PN = "2";
BODY = "Q_RES","I147": #LOCATION = "R477" !CDS_LOCATION = "R477" &SEC = "1" #&CDS_SEC = "1";
"A":   PN = "1"  !CDS_PN = "1";
"B":   PN = "2"  !CDS_PN = "2";
BODY = "Q_RES","I148": #LOCATION = "R476" !CDS_LOCATION = "R476" &SEC = "1" #&CDS_SEC = "1";
"A":   PN = "1"  !CDS_PN = "1";
"B":   PN = "2"  !CDS_PN = "2";
BODY = "Q_RES","I149": #LOCATION = "R1620" !CDS_LOCATION = "R1620" &SEC = "1" #&CDS_SEC = "1";
"A":   PN = "1"  !CDS_PN = "1";
"B":   PN = "2"  !CDS_PN = "2";
BODY = "Q_RES","I150": #LOCATION = "R478" !CDS_LOCATION = "R478" &SEC = "1" #&CDS_SEC = "1";
"A":   PN = "1"  !CDS_PN = "1";
"B":   PN = "2"  !CDS_PN = "2";
BODY = "Q_CAP","I152": #LOCATION = "C85" !CDS_LOCATION = "C85" &SEC = "1" #&CDS_SEC = "1";
"A":   PN = "1"  !CDS_PN = "1";
"B":   PN = "2"  !CDS_PN = "2";
BODY = "Q_RES","I157": #LOCATION = "R1528" !CDS_LOCATION = "R1528" &SEC = "1" #&CDS_SEC = "1";
"A":   PN = "1"  !CDS_PN = "1";
"B":   PN = "2"  !CDS_PN = "2";
BODY = "Q_RES","I159": #LOCATION = "R6108" !CDS_LOCATION = "R6108" &SEC = "1" #&CDS_SEC = "1";
"A":   PN = "1"  !CDS_PN = "1";
"B":   PN = "2"  !CDS_PN = "2";
BODY = "Q_RES","I160": #LOCATION = "R6111" !CDS_LOCATION = "R6111" &SEC = "1" #&CDS_SEC = "1";
"A":   PN = "1"  !CDS_PN = "1";
"B":   PN = "2"  !CDS_PN = "2";
BODY = "Q_CAP","I161": #LOCATION = "C86" !CDS_LOCATION = "C86" &SEC = "1" #&CDS_SEC = "1";
"A":   PN = "1"  !CDS_PN = "1";
"B":   PN = "2"  !CDS_PN = "2";
BODY = "Q_CAP","I163": #LOCATION = "C8006" !CDS_LOCATION = "C8006" &SEC = "1" #&CDS_SEC = "1";
"A":   PN = "1"  !CDS_PN = "1";
"B":   PN = "2"  !CDS_PN = "2";
DRAWING = "@t6g_mb_lib.t6g(sch_1):page150";
BODY = "SN74AVC4T774PWR","I8": #LOCATION = "U150" !CDS_LOCATION = "U150" &SEC = "1" #&CDS_SEC = "1";
"A1":   PN = "3"  !CDS_PN = "3";
"A2":   PN = "4"  !CDS_PN = "4";
"A3":   PN = "5"  !CDS_PN = "5";
"A4":   PN = "6"  !CDS_PN = "6";
"B1":   PN = "14"  !CDS_PN = "14";
"B2":   PN = "13"  !CDS_PN = "13";
"B3":   PN = "12"  !CDS_PN = "12";
"B4":   PN = "11"  !CDS_PN = "11";
"DIR1":   PN = "1"  !CDS_PN = "1";
"DIR2":   PN = "2"  !CDS_PN = "2";
"DIR3":   PN = "7"  !CDS_PN = "7";
"DIR4":   PN = "8"  !CDS_PN = "8";
"GND":   PN = "10"  !CDS_PN = "10";
"OE":   PN = "9"  !CDS_PN = "9";
"VCCA":   PN = "16"  !CDS_PN = "16";
"VCCB":   PN = "15"  !CDS_PN = "15";
BODY = "Q_CAP","I14": #LOCATION = "C1516" !CDS_LOCATION = "C1516" &SEC = "1" #&CDS_SEC = "1";
"A":   PN = "1"  !CDS_PN = "1";
"B":   PN = "2"  !CDS_PN = "2";
BODY = "Q_CAP","I19": #LOCATION = "C1514" !CDS_LOCATION = "C1514" &SEC = "1" #&CDS_SEC = "1";
"A":   PN = "1"  !CDS_PN = "1";
"B":   PN = "2"  !CDS_PN = "2";
BODY = "Q_RES","I24": #LOCATION = "R1641" !CDS_LOCATION = "R1641" &SEC = "1" #&CDS_SEC = "1";
"A":   PN = "1"  !CDS_PN = "1";
"B":   PN = "2"  !CDS_PN = "2";
BODY = "Q_RES","I25": #LOCATION = "R1639" !CDS_LOCATION = "R1639" &SEC = "1" #&CDS_SEC = "1";
"A":   PN = "1"  !CDS_PN = "1";
"B":   PN = "2"  !CDS_PN = "2";
BODY = "Q_RES","I26": #LOCATION = "R1640" !CDS_LOCATION = "R1640" &SEC = "1" #&CDS_SEC = "1";
"A":   PN = "1"  !CDS_PN = "1";
"B":   PN = "2"  !CDS_PN = "2";
BODY = "Q_RES","I27": #LOCATION = "R1638" !CDS_LOCATION = "R1638" &SEC = "1" #&CDS_SEC = "1";
"A":   PN = "1"  !CDS_PN = "1";
"B":   PN = "2"  !CDS_PN = "2";
BODY = "SN74AVC4T774PWR","I28": #LOCATION = "U151" !CDS_LOCATION = "U151" &SEC = "1" #&CDS_SEC = "1";
"A1":   PN = "3"  !CDS_PN = "3";
"A2":   PN = "4"  !CDS_PN = "4";
"A3":   PN = "5"  !CDS_PN = "5";
"A4":   PN = "6"  !CDS_PN = "6";
"B1":   PN = "14"  !CDS_PN = "14";
"B2":   PN = "13"  !CDS_PN = "13";
"B3":   PN = "12"  !CDS_PN = "12";
"B4":   PN = "11"  !CDS_PN = "11";
"DIR1":   PN = "1"  !CDS_PN = "1";
"DIR2":   PN = "2"  !CDS_PN = "2";
"DIR3":   PN = "7"  !CDS_PN = "7";
"DIR4":   PN = "8"  !CDS_PN = "8";
"GND":   PN = "10"  !CDS_PN = "10";
"OE":   PN = "9"  !CDS_PN = "9";
"VCCA":   PN = "16"  !CDS_PN = "16";
"VCCB":   PN = "15"  !CDS_PN = "15";
BODY = "Q_RES","I33": #LOCATION = "R1642" !CDS_LOCATION = "R1642" &SEC = "1" #&CDS_SEC = "1";
"A":   PN = "1"  !CDS_PN = "1";
"B":   PN = "2"  !CDS_PN = "2";
BODY = "Q_RES","I34": #LOCATION = "R1643" !CDS_LOCATION = "R1643" &SEC = "1" #&CDS_SEC = "1";
"A":   PN = "1"  !CDS_PN = "1";
"B":   PN = "2"  !CDS_PN = "2";
BODY = "Q_RES","I35": #LOCATION = "R1644" !CDS_LOCATION = "R1644" &SEC = "1" #&CDS_SEC = "1";
"A":   PN = "1"  !CDS_PN = "1";
"B":   PN = "2"  !CDS_PN = "2";
BODY = "Q_RES","I36": #LOCATION = "R1645" !CDS_LOCATION = "R1645" &SEC = "1" #&CDS_SEC = "1";
"A":   PN = "1"  !CDS_PN = "1";
"B":   PN = "2"  !CDS_PN = "2";
BODY = "Q_CAP","I40": #LOCATION = "C1517" !CDS_LOCATION = "C1517" &SEC = "1" #&CDS_SEC = "1";
"A":   PN = "1"  !CDS_PN = "1";
"B":   PN = "2"  !CDS_PN = "2";
BODY = "Q_CAP","I43": #LOCATION = "C1515" !CDS_LOCATION = "C1515" &SEC = "1" #&CDS_SEC = "1";
"A":   PN = "1"  !CDS_PN = "1";
"B":   PN = "2"  !CDS_PN = "2";
BODY = "SN74AVC2T245RSWR","I60": #LOCATION = "U152" !CDS_LOCATION = "U152" &SEC = "1" #&CDS_SEC = "1";
"A1":   PN = "8"  !CDS_PN = "8";
"A2":   PN = "9"  !CDS_PN = "9";
"B1":   PN = "5"  !CDS_PN = "5";
"B2":   PN = "4"  !CDS_PN = "4";
"DIR1":   PN = "10"  !CDS_PN = "10";
"DIR2":   PN = "1"  !CDS_PN = "1";
"GND":   PN = "3"  !CDS_PN = "3";
"OE_#":   PN = "2"  !CDS_PN = "2";
"VCCA":   PN = "7"  !CDS_PN = "7";
"VCCB":   PN = "6"  !CDS_PN = "6";
BODY = "Q_CAP","I66": #LOCATION = "C1518" !CDS_LOCATION = "C1518" &SEC = "1" #&CDS_SEC = "1";
"A":   PN = "1"  !CDS_PN = "1";
"B":   PN = "2"  !CDS_PN = "2";
BODY = "Q_CAP","I69": #LOCATION = "C1513" !CDS_LOCATION = "C1513" &SEC = "1" #&CDS_SEC = "1";
"A":   PN = "1"  !CDS_PN = "1";
"B":   PN = "2"  !CDS_PN = "2";
BODY = "Q_RES","I71": #LOCATION = "R1637" !CDS_LOCATION = "R1637" &SEC = "1" #&CDS_SEC = "1";
"A":   PN = "1"  !CDS_PN = "1";
"B":   PN = "2"  !CDS_PN = "2";
BODY = "Q_RES","I76": #LOCATION = "R6103" !CDS_LOCATION = "R6103" &SEC = "1" #&CDS_SEC = "1";
"A":   PN = "1"  !CDS_PN = "1";
"B":   PN = "2"  !CDS_PN = "2";
BODY = "Q_RES","I78": #LOCATION = "R6109" !CDS_LOCATION = "R6109" &SEC = "1" #&CDS_SEC = "1";
"A":   PN = "1"  !CDS_PN = "1";
"B":   PN = "2"  !CDS_PN = "2";
DRAWING = "@t6g_mb_lib.t6g(sch_1):page151";
BODY = "SN74AUC2G66DCTR","I1": #LOCATION = "U153" !CDS_LOCATION = "U153" &SEC = "1" #&CDS_SEC = "1";
"1A":   PN = "1"  !CDS_PN = "1";
"1B":   PN = "2"  !CDS_PN = "2";
"1C":   PN = "7"  !CDS_PN = "7";
"2A":   PN = "5"  !CDS_PN = "5";
"2B":   PN = "6"  !CDS_PN = "6";
"2C":   PN = "3"  !CDS_PN = "3";
"GND":   PN = "4"  !CDS_PN = "4";
"VCC":   PN = "8"  !CDS_PN = "8";
BODY = "Q_RES","I2": #LOCATION = "R1648" !CDS_LOCATION = "R1648" &SEC = "1" #&CDS_SEC = "1";
"A":   PN = "1"  !CDS_PN = "1";
"B":   PN = "2"  !CDS_PN = "2";
BODY = "Q_CAP","I4": #LOCATION = "C1520" !CDS_LOCATION = "C1520" &SEC = "1" #&CDS_SEC = "1";
"A":   PN = "1"  !CDS_PN = "1";
"B":   PN = "2"  !CDS_PN = "2";
BODY = "Q_RES","I10": #LOCATION = "R1646" !CDS_LOCATION = "R1646" &SEC = "1" #&CDS_SEC = "1";
"A":   PN = "1"  !CDS_PN = "1";
"B":   PN = "2"  !CDS_PN = "2";
BODY = "Q_RES","I11": #LOCATION = "R1647" !CDS_LOCATION = "R1647" &SEC = "1" #&CDS_SEC = "1";
"A":   PN = "1"  !CDS_PN = "1";
"B":   PN = "2"  !CDS_PN = "2";
BODY = "Q_CAP","I15": #LOCATION = "C1519" !CDS_LOCATION = "C1519" &SEC = "1" #&CDS_SEC = "1";
"A":   PN = "1"  !CDS_PN = "1";
"B":   PN = "2"  !CDS_PN = "2";
BODY = "SN74AUC2G66DCTR","I17": #LOCATION = "U13" !CDS_LOCATION = "U13" #SEC = "1" !CDS_SEC = "1";
"1A":   PN = "1"  !CDS_PN = "1";
"1B":   PN = "2"  !CDS_PN = "2";
"1C":   PN = "7"  !CDS_PN = "7";
"2A":   PN = "5"  !CDS_PN = "5";
"2B":   PN = "6"  !CDS_PN = "6";
"2C":   PN = "3"  !CDS_PN = "3";
"GND":   PN = "4"  !CDS_PN = "4";
"VCC":   PN = "8"  !CDS_PN = "8";
BODY = "Q_CAP","I22": #LOCATION = "C1521" !CDS_LOCATION = "C1521" &SEC = "1" #&CDS_SEC = "1";
"A":   PN = "1"  !CDS_PN = "1";
"B":   PN = "2"  !CDS_PN = "2";
BODY = "SN74AUC2G66DCTR","I23": #LOCATION = "U14" !CDS_LOCATION = "U14" #SEC = "1" !CDS_SEC = "1";
"1A":   PN = "1"  !CDS_PN = "1";
"1B":   PN = "2"  !CDS_PN = "2";
"1C":   PN = "7"  !CDS_PN = "7";
"2A":   PN = "5"  !CDS_PN = "5";
"2B":   PN = "6"  !CDS_PN = "6";
"2C":   PN = "3"  !CDS_PN = "3";
"GND":   PN = "4"  !CDS_PN = "4";
"VCC":   PN = "8"  !CDS_PN = "8";
BODY = "Q_RES","I25": #LOCATION = "R1649" !CDS_LOCATION = "R1649" &SEC = "1" #&CDS_SEC = "1";
"A":   PN = "1"  !CDS_PN = "1";
"B":   PN = "2"  !CDS_PN = "2";
BODY = "Q_RES","I27": #LOCATION = "R1650" !CDS_LOCATION = "R1650" &SEC = "1" #&CDS_SEC = "1";
"A":   PN = "1"  !CDS_PN = "1";
"B":   PN = "2"  !CDS_PN = "2";
BODY = "SN74AUC2G66DCTR","I31": #LOCATION = "U154" !CDS_LOCATION = "U154" &SEC = "1" #&CDS_SEC = "1";
"1A":   PN = "1"  !CDS_PN = "1";
"1B":   PN = "2"  !CDS_PN = "2";
"1C":   PN = "7"  !CDS_PN = "7";
"2A":   PN = "5"  !CDS_PN = "5";
"2B":   PN = "6"  !CDS_PN = "6";
"2C":   PN = "3"  !CDS_PN = "3";
"GND":   PN = "4"  !CDS_PN = "4";
"VCC":   PN = "8"  !CDS_PN = "8";
BODY = "Q_RES","I34": #LOCATION = "R1651" !CDS_LOCATION = "R1651" &SEC = "1" #&CDS_SEC = "1";
"A":   PN = "1"  !CDS_PN = "1";
"B":   PN = "2"  !CDS_PN = "2";
BODY = "Q_CAP","I36": #LOCATION = "C1522" !CDS_LOCATION = "C1522" &SEC = "1" #&CDS_SEC = "1";
"A":   PN = "1"  !CDS_PN = "1";
"B":   PN = "2"  !CDS_PN = "2";
BODY = "Q_CAP","I42": #LOCATION = "C1523" !CDS_LOCATION = "C1523" &SEC = "1" #&CDS_SEC = "1";
"A":   PN = "1"  !CDS_PN = "1";
"B":   PN = "2"  !CDS_PN = "2";
BODY = "MOSFET_N","I45": #LOCATION = "Q63" !CDS_LOCATION = "Q63" &SEC = "1" #&CDS_SEC = "1";
"DRAIN":   PN = "D"  !CDS_PN = "D";
"GATE":   PN = "G"  !CDS_PN = "G";
"SOURCE":   PN = "S"  !CDS_PN = "S";
BODY = "MOSFET_N","I46": #LOCATION = "Q64" !CDS_LOCATION = "Q64" &SEC = "1" #&CDS_SEC = "1";
"DRAIN":   PN = "D"  !CDS_PN = "D";
"GATE":   PN = "G"  !CDS_PN = "G";
"SOURCE":   PN = "S"  !CDS_PN = "S";
BODY = "Q_RES","I48": #LOCATION = "R6104" !CDS_LOCATION = "R6104" &SEC = "1" #&CDS_SEC = "1";
"A":   PN = "1"  !CDS_PN = "1";
"B":   PN = "2"  !CDS_PN = "2";
BODY = "Q_RES","I49": #LOCATION = "R6105" !CDS_LOCATION = "R6105" &SEC = "1" #&CDS_SEC = "1";
"A":   PN = "1"  !CDS_PN = "1";
"B":   PN = "2"  !CDS_PN = "2";
BODY = "Q_RES","I50": #LOCATION = "R6110" !CDS_LOCATION = "R6110" &SEC = "1" #&CDS_SEC = "1";
"A":   PN = "1"  !CDS_PN = "1";
"B":   PN = "2"  !CDS_PN = "2";
DRAWING = "@t6g_mb_lib.t6g(sch_1):page142";
BODY = "Q_LED","I79": #LOCATION = "D9" !CDS_LOCATION = "D9" &SEC = "1" #&CDS_SEC = "1";
"A":   PN = "A"  !CDS_PN = "A";
"C":   PN = "C"  !CDS_PN = "C";
BODY = "MOSFET_N_GSD","I80": #LOCATION = "Q29" !CDS_LOCATION = "Q29" &SEC = "1" #&CDS_SEC = "1";
"DRAIN":   PN = "D"  !CDS_PN = "D";
"GATE":   PN = "G"  !CDS_PN = "G";
"SOURCE":   PN = "S"  !CDS_PN = "S";
BODY = "MOSFET_N_GSD","I81": #LOCATION = "Q30" !CDS_LOCATION = "Q30" &SEC = "1" #&CDS_SEC = "1";
"DRAIN":   PN = "D"  !CDS_PN = "D";
"GATE":   PN = "G"  !CDS_PN = "G";
"SOURCE":   PN = "S"  !CDS_PN = "S";
BODY = "Q_RES","I82": #LOCATION = "R1444" !CDS_LOCATION = "R1444" &SEC = "1" #&CDS_SEC = "1";
"A":   PN = "1"  !CDS_PN = "1";
"B":   PN = "2"  !CDS_PN = "2";
BODY = "Q_RES","I87": #LOCATION = "R1507" !CDS_LOCATION = "R1507" &SEC = "1" #&CDS_SEC = "1";
"A":   PN = "1"  !CDS_PN = "1";
"B":   PN = "2"  !CDS_PN = "2";
DRAWING = "@t6g_mb_lib.t6g(sch_1):page84";
BODY = "Q_RES","I36": #LOCATION = "R14" !CDS_LOCATION = "R14" &SEC = "1" #&CDS_SEC = "1";
"A":   PN = "1"  !CDS_PN = "1";
"B":   PN = "2"  !CDS_PN = "2";
BODY = "Q_RES","I5": #LOCATION = "R1303" !CDS_LOCATION = "R1303" &SEC = "1" #&CDS_SEC = "1";
"A":   PN = "1"  !CDS_PN = "1";
"B":   PN = "2"  !CDS_PN = "2";
BODY = "Q_RES","I37": #LOCATION = "R9" !CDS_LOCATION = "R9" &SEC = "1" #&CDS_SEC = "1";
"A":   PN = "1"  !CDS_PN = "1";
"B":   PN = "2"  !CDS_PN = "2";
BODY = "Q_RES","I38": #LOCATION = "R13" !CDS_LOCATION = "R13" &SEC = "1" #&CDS_SEC = "1";
"A":   PN = "1"  !CDS_PN = "1";
"B":   PN = "2"  !CDS_PN = "2";
BODY = "CONN8_HBB1081L200D8H","I41": #LOCATION = "J57" !CDS_LOCATION = "J57" &SEC = "1" #&CDS_SEC = "1";
"1":   PN = "1"  !CDS_PN = "1";
"2":   PN = "2"  !CDS_PN = "2";
"3":   PN = "3"  !CDS_PN = "3";
"4":   PN = "4"  !CDS_PN = "4";
"5":   PN = "5"  !CDS_PN = "5";
"6":   PN = "6"  !CDS_PN = "6";
"7":   PN = "7"  !CDS_PN = "7";
"8":   PN = "8"  !CDS_PN = "8";
BODY = "Q_CAP","I42": #LOCATION = "C20" !CDS_LOCATION = "C20" &SEC = "1" #&CDS_SEC = "1";
"A":   PN = "1"  !CDS_PN = "1";
"B":   PN = "2"  !CDS_PN = "2";
BODY = "Q_RES","I6": #LOCATION = "R1036" !CDS_LOCATION = "R1036" &SEC = "1" #&CDS_SEC = "1";
"A":   PN = "1"  !CDS_PN = "1";
"B":   PN = "2"  !CDS_PN = "2";
BODY = "Q_RES","I27": #LOCATION = "R530" !CDS_LOCATION = "R530" &SEC = "1" #&CDS_SEC = "1";
"A":   PN = "1"  !CDS_PN = "1";
"B":   PN = "2"  !CDS_PN = "2";
BODY = "Q_RES","I35": #LOCATION = "R15" !CDS_LOCATION = "R15" &SEC = "1" #&CDS_SEC = "1";
"A":   PN = "1"  !CDS_PN = "1";
"B":   PN = "2"  !CDS_PN = "2";
BODY = "Q_RES","I45": #LOCATION = "R1266" !CDS_LOCATION = "R1266" &SEC = "1" #&CDS_SEC = "1";
"A":   PN = "1"  !CDS_PN = "1";
"B":   PN = "2"  !CDS_PN = "2";
BODY = "Q_RES","I46": #LOCATION = "R1194" !CDS_LOCATION = "R1194" &SEC = "1" #&CDS_SEC = "1";
"A":   PN = "1"  !CDS_PN = "1";
"B":   PN = "2"  !CDS_PN = "2";
BODY = "MOSFET_DUAL_6P","I48": #LOCATION = "Q28" !CDS_LOCATION = "Q28" &SEC = "1" #&CDS_SEC = "1";
"D1":   PN = "6"  !CDS_PN = "6";
"D2":   PN = "3"  !CDS_PN = "3";
"G1":   PN = "2"  !CDS_PN = "2";
"G2":   PN = "5"  !CDS_PN = "5";
"S1":   PN = "1"  !CDS_PN = "1";
"S2":   PN = "4"  !CDS_PN = "4";
BODY = "Q_RES","I53": #LOCATION = "R6074" !CDS_LOCATION = "R6074" &SEC = "1" #&CDS_SEC = "1";
"A":   PN = "1"  !CDS_PN = "1";
"B":   PN = "2"  !CDS_PN = "2";
BODY = "Q_RES","I57": #LOCATION = "R6075" !CDS_LOCATION = "R6075" &SEC = "1" #&CDS_SEC = "1";
"A":   PN = "1"  !CDS_PN = "1";
"B":   PN = "2"  !CDS_PN = "2";
BODY = "Q_RES","I61": #LOCATION = "R6078" !CDS_LOCATION = "R6078" &SEC = "1" #&CDS_SEC = "1";
"A":   PN = "1"  !CDS_PN = "1";
"B":   PN = "2"  !CDS_PN = "2";
BODY = "Q_RES","I63": #LOCATION = "R2343" !CDS_LOCATION = "R2343" &SEC = "1" #&CDS_SEC = "1";
"A":   PN = "1"  !CDS_PN = "1";
"B":   PN = "2"  !CDS_PN = "2";
BODY = "MOSFET_NCH_DUAL","I65": #LOCATION = "Q50" !CDS_LOCATION = "Q50" &SEC = "1" #&CDS_SEC = "1";
"D1":   PN = "6"  !CDS_PN = "6";
"G1":   PN = "2"  !CDS_PN = "2";
"S1":   PN = "1"  !CDS_PN = "1";
BODY = "Q_RES","I67": #LOCATION = "R2344" !CDS_LOCATION = "R2344" &SEC = "1" #&CDS_SEC = "1";
"A":   PN = "1"  !CDS_PN = "1";
"B":   PN = "2"  !CDS_PN = "2";
BODY = "Q_RES","I70": #LOCATION = "R2346" !CDS_LOCATION = "R2346" &SEC = "1" #&CDS_SEC = "1";
"A":   PN = "1"  !CDS_PN = "1";
"B":   PN = "2"  !CDS_PN = "2";
BODY = "MOSFET_NCH_DUAL","I73": #LOCATION = "Q50" !CDS_LOCATION = "Q50" &SEC = "2" #&CDS_SEC = "2";
"D2":   PN = "3"  !CDS_PN = "3";
"G2":   PN = "5"  !CDS_PN = "5";
"S2":   PN = "4"  !CDS_PN = "4";
BODY = "Q_RES","I75": #LOCATION = "R6113" !CDS_LOCATION = "R6113" &SEC = "1" #&CDS_SEC = "1";
"A":   PN = "1"  !CDS_PN = "1";
"B":   PN = "2"  !CDS_PN = "2";
BODY = "Q_RES","I77": #LOCATION = "R6090" !CDS_LOCATION = "R6090" &SEC = "1" #&CDS_SEC = "1";
"A":   PN = "1"  !CDS_PN = "1";
"B":   PN = "2"  !CDS_PN = "2";
BODY = "Q_RES","I82": #LOCATION = "R6092" !CDS_LOCATION = "R6092" &SEC = "1" #&CDS_SEC = "1";
"A":   PN = "1"  !CDS_PN = "1";
"B":   PN = "2"  !CDS_PN = "2";
BODY = "Q_RES","I84": #LOCATION = "R6093" !CDS_LOCATION = "R6093" &SEC = "1" #&CDS_SEC = "1";
"A":   PN = "1"  !CDS_PN = "1";
"B":   PN = "2"  !CDS_PN = "2";
BODY = "Q_CAP","I88": #LOCATION = "C1209" !CDS_LOCATION = "C1209" &SEC = "1" #&CDS_SEC = "1";
"A":   PN = "1"  !CDS_PN = "1";
"B":   PN = "2"  !CDS_PN = "2";
BODY = "Q_RES","I91": #LOCATION = "R6112" !CDS_LOCATION = "R6112" &SEC = "1" #&CDS_SEC = "1";
"A":   PN = "1"  !CDS_PN = "1";
"B":   PN = "2"  !CDS_PN = "2";
BODY = "Q_RES","I94": #LOCATION = "R2" !CDS_LOCATION = "R2" &SEC = "1" #&CDS_SEC = "1";
"A":   PN = "1"  !CDS_PN = "1";
"B":   PN = "2"  !CDS_PN = "2";
BODY = "Q_LED","I96": #LOCATION = "D7" !CDS_LOCATION = "D7" &SEC = "1" #&CDS_SEC = "1";
"A":   PN = "A"  !CDS_PN = "A";
"C":   PN = "C"  !CDS_PN = "C";
BODY = "Q_LED","I97": #LOCATION = "D8" !CDS_LOCATION = "D8" &SEC = "1" #&CDS_SEC = "1";
"A":   PN = "A"  !CDS_PN = "A";
"C":   PN = "C"  !CDS_PN = "C";
BODY = "Q_CAP","I101": #LOCATION = "C8005" !CDS_LOCATION = "C8005" &SEC = "1" #&CDS_SEC = "1";
"A":   PN = "1"  !CDS_PN = "1";
"B":   PN = "2"  !CDS_PN = "2";
BODY = "Q_RES","I103": #LOCATION = "R6118" !CDS_LOCATION = "R6118" &SEC = "1" #&CDS_SEC = "1";
"A":   PN = "1"  !CDS_PN = "1";
"B":   PN = "2"  !CDS_PN = "2";
BODY = "Q_RES","I104": #LOCATION = "R1422" !CDS_LOCATION = "R1422" &SEC = "1" #&CDS_SEC = "1";
"A":   PN = "1"  !CDS_PN = "1";
"B":   PN = "2"  !CDS_PN = "2";
BODY = "Q_RES","I106": #LOCATION = "R9025" !CDS_LOCATION = "R9025" &SEC = "1" #&CDS_SEC = "1";
"A":   PN = "1"  !CDS_PN = "1";
"B":   PN = "2"  !CDS_PN = "2";
BODY = "MOSFET_NCH_DUAL","I111": #LOCATION = "Q9003" !CDS_LOCATION = "Q9003" &SEC = "1" #&CDS_SEC = "1";
"D1":   PN = "6"  !CDS_PN = "6";
"G1":   PN = "2"  !CDS_PN = "2";
"S1":   PN = "1"  !CDS_PN = "1";
BODY = "Q_RES","I112": #LOCATION = "R9026" !CDS_LOCATION = "R9026" &SEC = "1" #&CDS_SEC = "1";
"A":   PN = "1"  !CDS_PN = "1";
"B":   PN = "2"  !CDS_PN = "2";
BODY = "Q_RES","I114": #LOCATION = "R9027" !CDS_LOCATION = "R9027" &SEC = "1" #&CDS_SEC = "1";
"A":   PN = "1"  !CDS_PN = "1";
"B":   PN = "2"  !CDS_PN = "2";
BODY = "Q_CAP","I116": #LOCATION = "C9005" !CDS_LOCATION = "C9005" &SEC = "1" #&CDS_SEC = "1";
"A":   PN = "1"  !CDS_PN = "1";
"B":   PN = "2"  !CDS_PN = "2";
BODY = "Q_RES","I118": #LOCATION = "R9028" !CDS_LOCATION = "R9028" &SEC = "1" #&CDS_SEC = "1";
"A":   PN = "1"  !CDS_PN = "1";
"B":   PN = "2"  !CDS_PN = "2";
BODY = "MOSFET_NCH_DUAL","I121": #LOCATION = "Q9003" !CDS_LOCATION = "Q9003" &SEC = "2" #&CDS_SEC = "2";
"D2":   PN = "3"  !CDS_PN = "3";
"G2":   PN = "5"  !CDS_PN = "5";
"S2":   PN = "4"  !CDS_PN = "4";
DRAWING = "@t6g_mb_lib.t6g(sch_1):page201";
BODY = "Q_CAP","I3": #LOCATION = "PC6002" !CDS_LOCATION = "PC6002" &SEC = "1" #&CDS_SEC = "1";
"A":   PN = "1"  !CDS_PN = "1";
"B":   PN = "2"  !CDS_PN = "2";
BODY = "Q_CAP","I6": #LOCATION = "C675" !CDS_LOCATION = "C675" &SEC = "1" #&CDS_SEC = "1";
"A":   PN = "1"  !CDS_PN = "1";
"B":   PN = "2"  !CDS_PN = "2";
BODY = "Q_RES","I11": #LOCATION = "PR8" !CDS_LOCATION = "PR8" #SEC = "1" !CDS_SEC = "1";
"A":   PN = "1"  !CDS_PN = "1";
"B":   PN = "2"  !CDS_PN = "2";
BODY = "Q_RES","I12": #LOCATION = "PR397" !CDS_LOCATION = "PR397" &SEC = "1" #&CDS_SEC = "1";
"A":   PN = "1"  !CDS_PN = "1";
"B":   PN = "2"  !CDS_PN = "2";
BODY = "MPQ8633BGLEC838Z","I15": #LOCATION = "PU3" !CDS_LOCATION = "PU3" &SEC = "1" #&CDS_SEC = "1";
"AGND":   PN = "2"  !CDS_PN = "2";
"BST":   PN = "1"  !CDS_PN = "1";
"CS":   PN = "3"  !CDS_PN = "3";
"EN":   PN = "8"  !CDS_PN = "8";
"FB":   PN = "7"  !CDS_PN = "7";
"MODE":   PN = "4"  !CDS_PN = "4";
"PGND":   PN = "11_18"  !CDS_PN = "11_18";
"PGOOD":   PN = "9"  !CDS_PN = "9";
"RGND":   PN = "6"  !CDS_PN = "6";
"SW":   PN = "20"  !CDS_PN = "20";
"TRK_REF":   PN = "5"  !CDS_PN = "5";
"VCC":   PN = "19"  !CDS_PN = "19";
"VIN1":   PN = "10"  !CDS_PN = "10";
"VIN2":   PN = "21"  !CDS_PN = "21";
BODY = "Q_CAP","I18": #LOCATION = "PC153" !CDS_LOCATION = "PC153" &SEC = "1" #&CDS_SEC = "1";
"A":   PN = "1"  !CDS_PN = "1";
"B":   PN = "2"  !CDS_PN = "2";
BODY = "Q_CAP","I19": #LOCATION = "PC62" !CDS_LOCATION = "PC62" &SEC = "1" #&CDS_SEC = "1";
"A":   PN = "1"  !CDS_PN = "1";
"B":   PN = "2"  !CDS_PN = "2";
BODY = "Q_CAP","I21": #LOCATION = "PC61" !CDS_LOCATION = "PC61" &SEC = "1" #&CDS_SEC = "1";
"A":   PN = "1"  !CDS_PN = "1";
"B":   PN = "2"  !CDS_PN = "2";
BODY = "Q_CAP","I22": #LOCATION = "PC150" !CDS_LOCATION = "PC150" &SEC = "1" #&CDS_SEC = "1";
"A":   PN = "1"  !CDS_PN = "1";
"B":   PN = "2"  !CDS_PN = "2";
BODY = "Q_CAP","I23": #LOCATION = "PC152" !CDS_LOCATION = "PC152" &SEC = "1" #&CDS_SEC = "1";
"A":   PN = "1"  !CDS_PN = "1";
"B":   PN = "2"  !CDS_PN = "2";
BODY = "Q_CAP","I24": #LOCATION = "PC22" !CDS_LOCATION = "PC22" &SEC = "1" #&CDS_SEC = "1";
"A":   PN = "1"  !CDS_PN = "1";
"B":   PN = "2"  !CDS_PN = "2";
BODY = "Q_RES","I26": #LOCATION = "R8009" !CDS_LOCATION = "R8009" #SEC = "1" !CDS_SEC = "1";
"A":   PN = "1"  !CDS_PN = "1";
"B":   PN = "2"  !CDS_PN = "2";
BODY = "Q_CAP","I37": #LOCATION = "PC65" !CDS_LOCATION = "PC65" &SEC = "1" #&CDS_SEC = "1";
"A":   PN = "1"  !CDS_PN = "1";
"B":   PN = "2"  !CDS_PN = "2";
BODY = "Q_CAP","I38": #LOCATION = "PC83" !CDS_LOCATION = "PC83" &SEC = "1" #&CDS_SEC = "1";
"A":   PN = "1"  !CDS_PN = "1";
"B":   PN = "2"  !CDS_PN = "2";
BODY = "Q_RES","I39": #LOCATION = "PR402" !CDS_LOCATION = "PR402" &SEC = "1" #&CDS_SEC = "1";
"A":   PN = "1"  !CDS_PN = "1";
"B":   PN = "2"  !CDS_PN = "2";
BODY = "Q_CAP","I42": #LOCATION = "PC88" !CDS_LOCATION = "PC88" &SEC = "1" #&CDS_SEC = "1";
"A":   PN = "1"  !CDS_PN = "1";
"B":   PN = "2"  !CDS_PN = "2";
BODY = "Q_CAPP","I43": #LOCATION = "PC89" !CDS_LOCATION = "PC89" &SEC = "1" #&CDS_SEC = "1";
"A":   PN = "1"  !CDS_PN = "1";
"B":   PN = "2"  !CDS_PN = "2";
BODY = "Q_RES","I48": #LOCATION = "R259" !CDS_LOCATION = "R259" &SEC = "1" #&CDS_SEC = "1";
"A":   PN = "1"  !CDS_PN = "1";
"B":   PN = "2"  !CDS_PN = "2";
BODY = "Q_RES","I50": #LOCATION = "PR403" !CDS_LOCATION = "PR403" &SEC = "1" #&CDS_SEC = "1";
"A":   PN = "1"  !CDS_PN = "1";
"B":   PN = "2"  !CDS_PN = "2";
BODY = "Q_CAP","I53": #LOCATION = "PC20" !CDS_LOCATION = "PC20" #SEC = "1" !CDS_SEC = "1";
"A":   PN = "1"  !CDS_PN = "1";
"B":   PN = "2"  !CDS_PN = "2";
BODY = "Q_INDUCTOR","I4": #LOCATION = "PL26" !CDS_LOCATION = "PL26" &SEC = "1" #&CDS_SEC = "1";
"1":   PN = "1"  !CDS_PN = "1";
"2":   PN = "2"  !CDS_PN = "2";
BODY = "Q_RES","I14": #LOCATION = "PR398" !CDS_LOCATION = "PR398" &SEC = "1" #&CDS_SEC = "1";
"A":   PN = "1"  !CDS_PN = "1";
"B":   PN = "2"  !CDS_PN = "2";
BODY = "Q_CAP","I25": #LOCATION = "PC19" !CDS_LOCATION = "PC19" #SEC = "1" !CDS_SEC = "1";
"A":   PN = "1"  !CDS_PN = "1";
"B":   PN = "2"  !CDS_PN = "2";
BODY = "Q_RES","I29": #LOCATION = "PR399" !CDS_LOCATION = "PR399" &SEC = "1" #&CDS_SEC = "1";
"A":   PN = "1"  !CDS_PN = "1";
"B":   PN = "2"  !CDS_PN = "2";
BODY = "Q_RES","I30": #LOCATION = "PR147" !CDS_LOCATION = "PR147" &SEC = "1" #&CDS_SEC = "1";
"A":   PN = "1"  !CDS_PN = "1";
"B":   PN = "2"  !CDS_PN = "2";
BODY = "Q_CAP","I31": #LOCATION = "PC64" !CDS_LOCATION = "PC64" &SEC = "1" #&CDS_SEC = "1";
"A":   PN = "1"  !CDS_PN = "1";
"B":   PN = "2"  !CDS_PN = "2";
BODY = "Q_RES","I32": #LOCATION = "PR148" !CDS_LOCATION = "PR148" &SEC = "1" #&CDS_SEC = "1";
"A":   PN = "1"  !CDS_PN = "1";
"B":   PN = "2"  !CDS_PN = "2";
BODY = "Q_INDUCTOR","I33": #LOCATION = "PL57" !CDS_LOCATION = "PL57" &SEC = "1" #&CDS_SEC = "1";
"1":   PN = "1"  !CDS_PN = "1";
"2":   PN = "2"  !CDS_PN = "2";
BODY = "Q_CAP","I34": #LOCATION = "PC6006" !CDS_LOCATION = "PC6006" &SEC = "1" #&CDS_SEC = "1";
"A":   PN = "1"  !CDS_PN = "1";
"B":   PN = "2"  !CDS_PN = "2";
BODY = "Q_RES","I35": #LOCATION = "PR401" !CDS_LOCATION = "PR401" &SEC = "1" #&CDS_SEC = "1";
"A":   PN = "1"  !CDS_PN = "1";
"B":   PN = "2"  !CDS_PN = "2";
BODY = "Q_RES","I36": #LOCATION = "PR400" !CDS_LOCATION = "PR400" &SEC = "1" #&CDS_SEC = "1";
"A":   PN = "1"  !CDS_PN = "1";
"B":   PN = "2"  !CDS_PN = "2";
BODY = "Q_CAP","I40": #LOCATION = "PC84" !CDS_LOCATION = "PC84" &SEC = "1" #&CDS_SEC = "1";
"A":   PN = "1"  !CDS_PN = "1";
"B":   PN = "2"  !CDS_PN = "2";
BODY = "Q_CAP","I41": #LOCATION = "PC87" !CDS_LOCATION = "PC87" &SEC = "1" #&CDS_SEC = "1";
"A":   PN = "1"  !CDS_PN = "1";
"B":   PN = "2"  !CDS_PN = "2";
BODY = "Q_CAP","I47": #LOCATION = "PC21" !CDS_LOCATION = "PC21" &SEC = "1" #&CDS_SEC = "1";
"A":   PN = "1"  !CDS_PN = "1";
"B":   PN = "2"  !CDS_PN = "2";
BODY = "Q_CAP","I54": #LOCATION = "PC60" !CDS_LOCATION = "PC60" &SEC = "1" #&CDS_SEC = "1";
"A":   PN = "1"  !CDS_PN = "1";
"B":   PN = "2"  !CDS_PN = "2";
BODY = "Q_CAP","I55": #LOCATION = "C5016" !CDS_LOCATION = "C5016" &SEC = "1" #&CDS_SEC = "1";
"A":   PN = "1"  !CDS_PN = "1";
"B":   PN = "2"  !CDS_PN = "2";
BODY = "Q_CAP","I57": #LOCATION = "PC8003" !CDS_LOCATION = "PC8003" &SEC = "1" #&CDS_SEC = "1";
"A":   PN = "1"  !CDS_PN = "1";
"B":   PN = "2"  !CDS_PN = "2";
BODY = "Q_RES","I58": #LOCATION = "PR8002" !CDS_LOCATION = "PR8002" #SEC = "1" !CDS_SEC = "1";
"A":   PN = "1"  !CDS_PN = "1";
"B":   PN = "2"  !CDS_PN = "2";
DRAWING = "@t6g_mb_lib.t6g(sch_1):page200";
BODY = "Q_RES","I25": #LOCATION = "PR519" !CDS_LOCATION = "PR519" &SEC = "1" #&CDS_SEC = "1";
"A":   PN = "1"  !CDS_PN = "1";
"B":   PN = "2"  !CDS_PN = "2";
BODY = "Q_RES","I26": #LOCATION = "PR331" !CDS_LOCATION = "PR331" &SEC = "1" #&CDS_SEC = "1";
"A":   PN = "1"  !CDS_PN = "1";
"B":   PN = "2"  !CDS_PN = "2";
BODY = "Q_CAP","I29": #LOCATION = "PC510_2" !CDS_LOCATION = "PC510_2" &SEC = "1" #&CDS_SEC = "1";
"A":   PN = "1"  !CDS_PN = "1";
"B":   PN = "2"  !CDS_PN = "2";
BODY = "Q_CAP","I34": #LOCATION = "PC503_1" !CDS_LOCATION = "PC503_1" &SEC = "1" #&CDS_SEC = "1";
"A":   PN = "1"  !CDS_PN = "1";
"B":   PN = "2"  !CDS_PN = "2";
BODY = "Q_RES","I37": #LOCATION = "PR328" !CDS_LOCATION = "PR328" &SEC = "1" #&CDS_SEC = "1";
"A":   PN = "1"  !CDS_PN = "1";
"B":   PN = "2"  !CDS_PN = "2";
BODY = "Q_CAP","I43": #LOCATION = "PC507_11P1_1" !CDS_LOCATION = "PC507_11P1_1" &SEC = "1" #&CDS_SEC = "1";
"A":   PN = "1"  !CDS_PN = "1";
"B":   PN = "2"  !CDS_PN = "2";
BODY = "Q_CAP","I48": #LOCATION = "PC509_1" !CDS_LOCATION = "PC509_1" &SEC = "1" #&CDS_SEC = "1";
"A":   PN = "1"  !CDS_PN = "1";
"B":   PN = "2"  !CDS_PN = "2";
BODY = "Q_CAP","I52": #LOCATION = "PC518_2" !CDS_LOCATION = "PC518_2" &SEC = "1" #&CDS_SEC = "1";
"A":   PN = "1"  !CDS_PN = "1";
"B":   PN = "2"  !CDS_PN = "2";
BODY = "Q_CAPP","I63": #LOCATION = "PC528" !CDS_LOCATION = "PC528" &SEC = "1" #&CDS_SEC = "1";
"A":   PN = "1"  !CDS_PN = "1";
"B":   PN = "2"  !CDS_PN = "2";
BODY = "Q_CAP","I67": #LOCATION = "PC527_2" !CDS_LOCATION = "PC527_2" &SEC = "1" #&CDS_SEC = "1";
"A":   PN = "1"  !CDS_PN = "1";
"B":   PN = "2"  !CDS_PN = "2";
BODY = "Q_CAPP","I69": #LOCATION = "PC530" !CDS_LOCATION = "PC530" &SEC = "1" #&CDS_SEC = "1";
"A":   PN = "1"  !CDS_PN = "1";
"B":   PN = "2"  !CDS_PN = "2";
BODY = "Q_CAPP","I81": #LOCATION = "PC522" !CDS_LOCATION = "PC522" &SEC = "1" #&CDS_SEC = "1";
"A":   PN = "1"  !CDS_PN = "1";
"B":   PN = "2"  !CDS_PN = "2";
BODY = "Q_INDUCTOR","I84": #LOCATION = "PL56" !CDS_LOCATION = "PL56" &SEC = "1" #&CDS_SEC = "1";
"1":   PN = "1"  !CDS_PN = "1";
"2":   PN = "2"  !CDS_PN = "2";
BODY = "Q_RES","I3": #LOCATION = "PR387" !CDS_LOCATION = "PR387" &SEC = "1" #&CDS_SEC = "1";
"A":   PN = "1"  !CDS_PN = "1";
"B":   PN = "2"  !CDS_PN = "2";
BODY = "Q_CAP","I8": #LOCATION = "PC504_2" !CDS_LOCATION = "PC504_2" &SEC = "1" #&CDS_SEC = "1";
"A":   PN = "1"  !CDS_PN = "1";
"B":   PN = "2"  !CDS_PN = "2";
BODY = "Q_CAP","I10": #LOCATION = "PC506" !CDS_LOCATION = "PC506" &SEC = "1" #&CDS_SEC = "1";
"A":   PN = "1"  !CDS_PN = "1";
"B":   PN = "2"  !CDS_PN = "2";
BODY = "Q_RES","I12": #LOCATION = "PR329" !CDS_LOCATION = "PR329" &SEC = "1" #&CDS_SEC = "1";
"A":   PN = "1"  !CDS_PN = "1";
"B":   PN = "2"  !CDS_PN = "2";
BODY = "Q_RES","I14": #LOCATION = "PR327" !CDS_LOCATION = "PR327" &SEC = "1" #&CDS_SEC = "1";
"A":   PN = "1"  !CDS_PN = "1";
"B":   PN = "2"  !CDS_PN = "2";
BODY = "Q_CAP","I17": #LOCATION = "PC508_11P1_2" !CDS_LOCATION = "PC508_11P1_2" &SEC = "1" #&CDS_SEC = "1";
"A":   PN = "1"  !CDS_PN = "1";
"B":   PN = "2"  !CDS_PN = "2";
BODY = "ISL99390FRZTR5935","I22": #LOCATION = "PU44" !CDS_LOCATION = "PU44" &SEC = "1" #&CDS_SEC = "1";
"AGND":   PN = "2"  !CDS_PN = "2";
"BOOT":   PN = "33"  !CDS_PN = "33";
"DNC":   PN = "31"  !CDS_PN = "31";
"EN":   PN = "35"  !CDS_PN = "35";
"GL1":   PN = "6"  !CDS_PN = "6";
"GL2":   PN = "41"  !CDS_PN = "41";
"IOUT":   PN = "38"  !CDS_PN = "38";
"LSET":   PN = "37"  !CDS_PN = "37";
"PGND1":   PN = "5"  !CDS_PN = "5";
"PGND2":   PN = "7_9-20_24"  !CDS_PN = "7_9-20_24";
"PGND3":   PN = "40"  !CDS_PN = "40";
"PHASE":   PN = "32"  !CDS_PN = "32";
"PVCC":   PN = "4"  !CDS_PN = "4";
"PWM":   PN = "34"  !CDS_PN = "34";
"REFIN":   PN = "39"  !CDS_PN = "39";
"SW":   PN = "10_19"  !CDS_PN = "10_19";
"TOUT_FLT":   PN = "36"  !CDS_PN = "36";
"VCC":   PN = "3"  !CDS_PN = "3";
"VIN1":   PN = "25_29"  !CDS_PN = "25_29";
"VIN2":   PN = "30"  !CDS_PN = "30";
"VOS":   PN = "1"  !CDS_PN = "1";
BODY = "Q_CAP","I27": #LOCATION = "PC255" !CDS_LOCATION = "PC255" &SEC = "1" #&CDS_SEC = "1";
"A":   PN = "1"  !CDS_PN = "1";
"B":   PN = "2"  !CDS_PN = "2";
BODY = "Q_CAP","I30": #LOCATION = "PC514_2" !CDS_LOCATION = "PC514_2" &SEC = "1" #&CDS_SEC = "1";
"A":   PN = "1"  !CDS_PN = "1";
"B":   PN = "2"  !CDS_PN = "2";
BODY = "Q_CAP","I31": #LOCATION = "PC516_2" !CDS_LOCATION = "PC516_2" &SEC = "1" #&CDS_SEC = "1";
"A":   PN = "1"  !CDS_PN = "1";
"B":   PN = "2"  !CDS_PN = "2";
BODY = "Q_RES","I33": #LOCATION = "PR520" !CDS_LOCATION = "PR520" &SEC = "1" #&CDS_SEC = "1";
"A":   PN = "1"  !CDS_PN = "1";
"B":   PN = "2"  !CDS_PN = "2";
BODY = "Q_CAP","I36": #LOCATION = "PC505" !CDS_LOCATION = "PC505" &SEC = "1" #&CDS_SEC = "1";
"A":   PN = "1"  !CDS_PN = "1";
"B":   PN = "2"  !CDS_PN = "2";
BODY = "Q_RES","I40": #LOCATION = "PR326" !CDS_LOCATION = "PR326" &SEC = "1" #&CDS_SEC = "1";
"A":   PN = "1"  !CDS_PN = "1";
"B":   PN = "2"  !CDS_PN = "2";
BODY = "Q_RES","I41": #LOCATION = "PR394" !CDS_LOCATION = "PR394" &SEC = "1" #&CDS_SEC = "1";
"A":   PN = "1"  !CDS_PN = "1";
"B":   PN = "2"  !CDS_PN = "2";
BODY = "Q_CAP","I45": #LOCATION = "PC511_1" !CDS_LOCATION = "PC511_1" &SEC = "1" #&CDS_SEC = "1";
"A":   PN = "1"  !CDS_PN = "1";
"B":   PN = "2"  !CDS_PN = "2";
BODY = "Q_CAP","I46": #LOCATION = "PC315" !CDS_LOCATION = "PC315" &SEC = "1" #&CDS_SEC = "1";
"A":   PN = "1"  !CDS_PN = "1";
"B":   PN = "2"  !CDS_PN = "2";
BODY = "Q_RES","I47": #LOCATION = "PR330" !CDS_LOCATION = "PR330" &SEC = "1" #&CDS_SEC = "1";
"A":   PN = "1"  !CDS_PN = "1";
"B":   PN = "2"  !CDS_PN = "2";
BODY = "Q_CAP","I49": #LOCATION = "PC513_1" !CDS_LOCATION = "PC513_1" &SEC = "1" #&CDS_SEC = "1";
"A":   PN = "1"  !CDS_PN = "1";
"B":   PN = "2"  !CDS_PN = "2";
BODY = "Q_CAP","I50": #LOCATION = "PC515_1" !CDS_LOCATION = "PC515_1" &SEC = "1" #&CDS_SEC = "1";
"A":   PN = "1"  !CDS_PN = "1";
"B":   PN = "2"  !CDS_PN = "2";
BODY = "Q_CAP","I51": #LOCATION = "PC517_1" !CDS_LOCATION = "PC517_1" &SEC = "1" #&CDS_SEC = "1";
"A":   PN = "1"  !CDS_PN = "1";
"B":   PN = "2"  !CDS_PN = "2";
BODY = "Q_RES","I53": #LOCATION = "PR333" !CDS_LOCATION = "PR333" &SEC = "1" #&CDS_SEC = "1";
"A":   PN = "1"  !CDS_PN = "1";
"B":   PN = "2"  !CDS_PN = "2";
BODY = "Q_CAP","I54": #LOCATION = "PC520" !CDS_LOCATION = "PC520" &SEC = "1" #&CDS_SEC = "1";
"A":   PN = "1"  !CDS_PN = "1";
"B":   PN = "2"  !CDS_PN = "2";
BODY = "Q_INDUCTOR","I55": #LOCATION = "PL55" !CDS_LOCATION = "PL55" &SEC = "1" #&CDS_SEC = "1";
"1":   PN = "1"  !CDS_PN = "1";
"2":   PN = "2"  !CDS_PN = "2";
BODY = "Q_CAP","I56": #LOCATION = "PC523_2" !CDS_LOCATION = "PC523_2" &SEC = "1" #&CDS_SEC = "1";
"A":   PN = "1"  !CDS_PN = "1";
"B":   PN = "2"  !CDS_PN = "2";
BODY = "Q_CAP","I58": #LOCATION = "PC27" !CDS_LOCATION = "PC27" &SEC = "1" #&CDS_SEC = "1";
"A":   PN = "1"  !CDS_PN = "1";
"B":   PN = "2"  !CDS_PN = "2";
BODY = "Q_RES","I60": #LOCATION = "PR332" !CDS_LOCATION = "PR332" &SEC = "1" #&CDS_SEC = "1";
"A":   PN = "1"  !CDS_PN = "1";
"B":   PN = "2"  !CDS_PN = "2";
BODY = "Q_CAPP","I62": #LOCATION = "PC525" !CDS_LOCATION = "PC525" &SEC = "1" #&CDS_SEC = "1";
"A":   PN = "1"  !CDS_PN = "1";
"B":   PN = "2"  !CDS_PN = "2";
BODY = "Q_CAPP","I65": #LOCATION = "PC802" !CDS_LOCATION = "PC802" &SEC = "1" #&CDS_SEC = "1";
"A":   PN = "1"  !CDS_PN = "1";
"B":   PN = "2"  !CDS_PN = "2";
BODY = "Q_CAPP","I72": #LOCATION = "PC531" !CDS_LOCATION = "PC531" &SEC = "1" #&CDS_SEC = "1";
"A":   PN = "1"  !CDS_PN = "1";
"B":   PN = "2"  !CDS_PN = "2";
BODY = "Q_CAPP","I73": #LOCATION = "PC532" !CDS_LOCATION = "PC532" &SEC = "1" #&CDS_SEC = "1";
"A":   PN = "1"  !CDS_PN = "1";
"B":   PN = "2"  !CDS_PN = "2";
BODY = "Q_CAPP","I75": #LOCATION = "PC803" !CDS_LOCATION = "PC803" &SEC = "1" #&CDS_SEC = "1";
"A":   PN = "1"  !CDS_PN = "1";
"B":   PN = "2"  !CDS_PN = "2";
BODY = "Q_CAP","I76": #LOCATION = "PC519" !CDS_LOCATION = "PC519" &SEC = "1" #&CDS_SEC = "1";
"A":   PN = "1"  !CDS_PN = "1";
"B":   PN = "2"  !CDS_PN = "2";
BODY = "Q_INDUCTOR","I78": #LOCATION = "PL54" !CDS_LOCATION = "PL54" &SEC = "1" #&CDS_SEC = "1";
"1":   PN = "1"  !CDS_PN = "1";
"2":   PN = "2"  !CDS_PN = "2";
BODY = "Q_CAP","I80": #LOCATION = "PC521_1" !CDS_LOCATION = "PC521_1" &SEC = "1" #&CDS_SEC = "1";
"A":   PN = "1"  !CDS_PN = "1";
"B":   PN = "2"  !CDS_PN = "2";
BODY = "Q_CAP","I82": #LOCATION = "PC524" !CDS_LOCATION = "PC524" &SEC = "1" #&CDS_SEC = "1";
"A":   PN = "1"  !CDS_PN = "1";
"B":   PN = "2"  !CDS_PN = "2";
BODY = "Q_CAP","I85": #LOCATION = "PC511" !CDS_LOCATION = "PC511" &SEC = "1" #&CDS_SEC = "1";
"A":   PN = "1"  !CDS_PN = "1";
"B":   PN = "2"  !CDS_PN = "2";
BODY = "Q_CAP","I87": #LOCATION = "PC526_1" !CDS_LOCATION = "PC526_1" &SEC = "1" #&CDS_SEC = "1";
"A":   PN = "1"  !CDS_PN = "1";
"B":   PN = "2"  !CDS_PN = "2";
BODY = "Q_CAP","I88": #LOCATION = "PC529_1" !CDS_LOCATION = "PC529_1" &SEC = "1" #&CDS_SEC = "1";
"A":   PN = "1"  !CDS_PN = "1";
"B":   PN = "2"  !CDS_PN = "2";
BODY = "Q_RES","I89": #LOCATION = "PR395" !CDS_LOCATION = "PR395" &SEC = "1" #&CDS_SEC = "1";
"A":   PN = "1"  !CDS_PN = "1";
"B":   PN = "2"  !CDS_PN = "2";
BODY = "Q_CAP","I91": #LOCATION = "PC512_2" !CDS_LOCATION = "PC512_2" &SEC = "1" #&CDS_SEC = "1";
"A":   PN = "1"  !CDS_PN = "1";
"B":   PN = "2"  !CDS_PN = "2";
BODY = "ISL99390FRZTR5935","I92": #LOCATION = "PU45" !CDS_LOCATION = "PU45" &SEC = "1" #&CDS_SEC = "1";
"AGND":   PN = "2"  !CDS_PN = "2";
"BOOT":   PN = "33"  !CDS_PN = "33";
"DNC":   PN = "31"  !CDS_PN = "31";
"EN":   PN = "35"  !CDS_PN = "35";
"GL1":   PN = "6"  !CDS_PN = "6";
"GL2":   PN = "41"  !CDS_PN = "41";
"IOUT":   PN = "38"  !CDS_PN = "38";
"LSET":   PN = "37"  !CDS_PN = "37";
"PGND1":   PN = "5"  !CDS_PN = "5";
"PGND2":   PN = "7_9-20_24"  !CDS_PN = "7_9-20_24";
"PGND3":   PN = "40"  !CDS_PN = "40";
"PHASE":   PN = "32"  !CDS_PN = "32";
"PVCC":   PN = "4"  !CDS_PN = "4";
"PWM":   PN = "34"  !CDS_PN = "34";
"REFIN":   PN = "39"  !CDS_PN = "39";
"SW":   PN = "10_19"  !CDS_PN = "10_19";
"TOUT_FLT":   PN = "36"  !CDS_PN = "36";
"VCC":   PN = "3"  !CDS_PN = "3";
"VIN1":   PN = "25_29"  !CDS_PN = "25_29";
"VIN2":   PN = "30"  !CDS_PN = "30";
"VOS":   PN = "1"  !CDS_PN = "1";
BODY = "Q_CAP","I93": #LOCATION = "PC8006" !CDS_LOCATION = "PC8006" &SEC = "1" #&CDS_SEC = "1";
"A":   PN = "1"  !CDS_PN = "1";
"B":   PN = "2"  !CDS_PN = "2";
BODY = "Q_CAP","I94": #LOCATION = "PC8007" !CDS_LOCATION = "PC8007" &SEC = "1" #&CDS_SEC = "1";
"A":   PN = "1"  !CDS_PN = "1";
"B":   PN = "2"  !CDS_PN = "2";
BODY = "Q_CAP","I95": #LOCATION = "PC7003" !CDS_LOCATION = "PC7003" &SEC = "1" #&CDS_SEC = "1";
"A":   PN = "1"  !CDS_PN = "1";
"B":   PN = "2"  !CDS_PN = "2";
DRAWING = "@t6g_mb_lib.t6g(sch_1):page168";
BODY = "Q_RES","I4": #LOCATION = "PR283" !CDS_LOCATION = "PR283" &SEC = "1" #&CDS_SEC = "1";
"A":   PN = "1"  !CDS_PN = "1";
"B":   PN = "2"  !CDS_PN = "2";
BODY = "Q_CAP","I13": #LOCATION = "C461" !CDS_LOCATION = "C461" &SEC = "1" #&CDS_SEC = "1";
"A":   PN = "1"  !CDS_PN = "1";
"B":   PN = "2"  !CDS_PN = "2";
BODY = "Q_RES","I36": #LOCATION = "PR297" !CDS_LOCATION = "PR297" &SEC = "1" #&CDS_SEC = "1";
"A":   PN = "1"  !CDS_PN = "1";
"B":   PN = "2"  !CDS_PN = "2";
BODY = "Q_RES","I42": #LOCATION = "R8317" !CDS_LOCATION = "R8317" &SEC = "1" #&CDS_SEC = "1";
"A":   PN = "1"  !CDS_PN = "1";
"B":   PN = "2"  !CDS_PN = "2";
BODY = "Q_RES","I47": #LOCATION = "PR599" !CDS_LOCATION = "PR599" &SEC = "1" #&CDS_SEC = "1";
"A":   PN = "1"  !CDS_PN = "1";
"B":   PN = "2"  !CDS_PN = "2";
BODY = "Q_RES","I57": #LOCATION = "R315" !CDS_LOCATION = "R315" &SEC = "1" #&CDS_SEC = "1";
"A":   PN = "1"  !CDS_PN = "1";
"B":   PN = "2"  !CDS_PN = "2";
BODY = "Q_RES","I58": #LOCATION = "R8301" !CDS_LOCATION = "R8301" &SEC = "1" #&CDS_SEC = "1";
"A":   PN = "1"  !CDS_PN = "1";
"B":   PN = "2"  !CDS_PN = "2";
BODY = "Q_CAP","I62": #LOCATION = "PC463" !CDS_LOCATION = "PC463" &SEC = "1" #&CDS_SEC = "1";
"A":   PN = "1"  !CDS_PN = "1";
"B":   PN = "2"  !CDS_PN = "2";
BODY = "Q_CAP","I66": #LOCATION = "C299" !CDS_LOCATION = "C299" &SEC = "1" #&CDS_SEC = "1";
"A":   PN = "1"  !CDS_PN = "1";
"B":   PN = "2"  !CDS_PN = "2";
BODY = "Q_CAP","I68": #LOCATION = "C302" !CDS_LOCATION = "C302" &SEC = "1" #&CDS_SEC = "1";
"A":   PN = "1"  !CDS_PN = "1";
"B":   PN = "2"  !CDS_PN = "2";
BODY = "Q_RES","I82": #LOCATION = "R8300" !CDS_LOCATION = "R8300" &SEC = "1" #&CDS_SEC = "1";
"A":   PN = "1"  !CDS_PN = "1";
"B":   PN = "2"  !CDS_PN = "2";
BODY = "Q_RES","I86": #LOCATION = "PR305" !CDS_LOCATION = "PR305" &SEC = "1" #&CDS_SEC = "1";
"A":   PN = "1"  !CDS_PN = "1";
"B":   PN = "2"  !CDS_PN = "2";
BODY = "Q_RES","I87": #LOCATION = "R8304" !CDS_LOCATION = "R8304" &SEC = "1" #&CDS_SEC = "1";
"A":   PN = "1"  !CDS_PN = "1";
"B":   PN = "2"  !CDS_PN = "2";
BODY = "Q_RES","I88": #LOCATION = "R8312" !CDS_LOCATION = "R8312" &SEC = "1" #&CDS_SEC = "1";
"A":   PN = "1"  !CDS_PN = "1";
"B":   PN = "2"  !CDS_PN = "2";
BODY = "Q_CAP","I90": #LOCATION = "C468" !CDS_LOCATION = "C468" &SEC = "1" #&CDS_SEC = "1";
"A":   PN = "1"  !CDS_PN = "1";
"B":   PN = "2"  !CDS_PN = "2";
BODY = "Q_CAP","I118": #LOCATION = "PC13" !CDS_LOCATION = "PC13" &SEC = "1" #&CDS_SEC = "1";
"A":   PN = "1"  !CDS_PN = "1";
"B":   PN = "2"  !CDS_PN = "2";
BODY = "Q_RES","I2": #LOCATION = "R8282" !CDS_LOCATION = "R8282" &SEC = "1" #&CDS_SEC = "1";
"A":   PN = "1"  !CDS_PN = "1";
"B":   PN = "2"  !CDS_PN = "2";
BODY = "Q_RES","I6": #LOCATION = "R8286" !CDS_LOCATION = "R8286" &SEC = "1" #&CDS_SEC = "1";
"A":   PN = "1"  !CDS_PN = "1";
"B":   PN = "2"  !CDS_PN = "2";
BODY = "Q_RES","I10": #LOCATION = "PR284" !CDS_LOCATION = "PR284" &SEC = "1" #&CDS_SEC = "1";
"A":   PN = "1"  !CDS_PN = "1";
"B":   PN = "2"  !CDS_PN = "2";
BODY = "Q_RES","I15": #LOCATION = "PR290" !CDS_LOCATION = "PR290" &SEC = "1" #&CDS_SEC = "1";
"A":   PN = "1"  !CDS_PN = "1";
"B":   PN = "2"  !CDS_PN = "2";
BODY = "MOSFET_N","I17": #LOCATION = "PQ17" !CDS_LOCATION = "PQ17" &SEC = "1" #&CDS_SEC = "1";
"DRAIN":   PN = "D"  !CDS_PN = "D";
"GATE":   PN = "G"  !CDS_PN = "G";
"SOURCE":   PN = "S"  !CDS_PN = "S";
BODY = "Q_RES","I18": #LOCATION = "PR285" !CDS_LOCATION = "PR285" &SEC = "1" #&CDS_SEC = "1";
"A":   PN = "1"  !CDS_PN = "1";
"B":   PN = "2"  !CDS_PN = "2";
BODY = "MOSFET_PCH_GDS_ESD_PROTECTED","I19": #LOCATION = "PQ13" !CDS_LOCATION = "PQ13" &SEC = "1" #&CDS_SEC = "1";
"D":   PN = "D"  !CDS_PN = "D";
"G":   PN = "G"  !CDS_PN = "G";
"S":   PN = "S"  !CDS_PN = "S";
BODY = "Q_RES","I21": #LOCATION = "PR5" !CDS_LOCATION = "PR5" #SEC = "1" !CDS_SEC = "1";
"A":   PN = "1"  !CDS_PN = "1";
"B":   PN = "2"  !CDS_PN = "2";
BODY = "Q_CAP","I23": #LOCATION = "PC462" !CDS_LOCATION = "PC462" &SEC = "1" #&CDS_SEC = "1";
"A":   PN = "1"  !CDS_PN = "1";
"B":   PN = "2"  !CDS_PN = "2";
BODY = "Q_RES","I24": #LOCATION = "R8299" !CDS_LOCATION = "R8299" &SEC = "1" #&CDS_SEC = "1";
"A":   PN = "1"  !CDS_PN = "1";
"B":   PN = "2"  !CDS_PN = "2";
BODY = "Q_RES","I27": #LOCATION = "PR292" !CDS_LOCATION = "PR292" &SEC = "1" #&CDS_SEC = "1";
"A":   PN = "1"  !CDS_PN = "1";
"B":   PN = "2"  !CDS_PN = "2";
BODY = "Q_RES","I28": #LOCATION = "R8298" !CDS_LOCATION = "R8298" &SEC = "1" #&CDS_SEC = "1";
"A":   PN = "1"  !CDS_PN = "1";
"B":   PN = "2"  !CDS_PN = "2";
BODY = "Q_RES","I40": #LOCATION = "PR296" !CDS_LOCATION = "PR296" &SEC = "1" #&CDS_SEC = "1";
"A":   PN = "1"  !CDS_PN = "1";
"B":   PN = "2"  !CDS_PN = "2";
BODY = "Q_RES","I44": #LOCATION = "PR295" !CDS_LOCATION = "PR295" &SEC = "1" #&CDS_SEC = "1";
"A":   PN = "1"  !CDS_PN = "1";
"B":   PN = "2"  !CDS_PN = "2";
BODY = "Q_RES","I48": #LOCATION = "PR314" !CDS_LOCATION = "PR314" &SEC = "1" #&CDS_SEC = "1";
"A":   PN = "1"  !CDS_PN = "1";
"B":   PN = "2"  !CDS_PN = "2";
BODY = "Q_CAP","I50": #LOCATION = "PC7" !CDS_LOCATION = "PC7" #SEC = "1" !CDS_SEC = "1";
"A":   PN = "1"  !CDS_PN = "1";
"B":   PN = "2"  !CDS_PN = "2";
BODY = "Q_CAP","I51": #LOCATION = "C465" !CDS_LOCATION = "C465" &SEC = "1" #&CDS_SEC = "1";
"A":   PN = "1"  !CDS_PN = "1";
"B":   PN = "2"  !CDS_PN = "2";
BODY = "Q_CAP","I52": #LOCATION = "PC466" !CDS_LOCATION = "PC466" &SEC = "1" #&CDS_SEC = "1";
"A":   PN = "1"  !CDS_PN = "1";
"B":   PN = "2"  !CDS_PN = "2";
BODY = "Q_RES","I54": #LOCATION = "R8313" !CDS_LOCATION = "R8313" &SEC = "1" #&CDS_SEC = "1";
"A":   PN = "1"  !CDS_PN = "1";
"B":   PN = "2"  !CDS_PN = "2";
BODY = "Q_RES","I59": #LOCATION = "PR307" !CDS_LOCATION = "PR307" &SEC = "1" #&CDS_SEC = "1";
"A":   PN = "1"  !CDS_PN = "1";
"B":   PN = "2"  !CDS_PN = "2";
BODY = "Q_CAP","I60": #LOCATION = "PC464" !CDS_LOCATION = "PC464" &SEC = "1" #&CDS_SEC = "1";
"A":   PN = "1"  !CDS_PN = "1";
"B":   PN = "2"  !CDS_PN = "2";
BODY = "Q_RES","I61": #LOCATION = "PR306" !CDS_LOCATION = "PR306" &SEC = "1" #&CDS_SEC = "1";
"A":   PN = "1"  !CDS_PN = "1";
"B":   PN = "2"  !CDS_PN = "2";
BODY = "Q_CAP","I64": #LOCATION = "C298" !CDS_LOCATION = "C298" &SEC = "1" #&CDS_SEC = "1";
"A":   PN = "1"  !CDS_PN = "1";
"B":   PN = "2"  !CDS_PN = "2";
BODY = "Q_RES","I69": #LOCATION = "R8287" !CDS_LOCATION = "R8287" &SEC = "1" #&CDS_SEC = "1";
"A":   PN = "1"  !CDS_PN = "1";
"B":   PN = "2"  !CDS_PN = "2";
BODY = "Q_RES","I70": #LOCATION = "R8289" !CDS_LOCATION = "R8289" &SEC = "1" #&CDS_SEC = "1";
"A":   PN = "1"  !CDS_PN = "1";
"B":   PN = "2"  !CDS_PN = "2";
BODY = "Q_RES","I71": #LOCATION = "R8293" !CDS_LOCATION = "R8293" &SEC = "1" #&CDS_SEC = "1";
"A":   PN = "1"  !CDS_PN = "1";
"B":   PN = "2"  !CDS_PN = "2";
BODY = "Q_RES","I72": #LOCATION = "PR294" !CDS_LOCATION = "PR294" &SEC = "1" #&CDS_SEC = "1";
"A":   PN = "1"  !CDS_PN = "1";
"B":   PN = "2"  !CDS_PN = "2";
BODY = "Q_RES","I83": #LOCATION = "R8310" !CDS_LOCATION = "R8310" &SEC = "1" #&CDS_SEC = "1";
"A":   PN = "1"  !CDS_PN = "1";
"B":   PN = "2"  !CDS_PN = "2";
BODY = "Q_RES","I84": #LOCATION = "R8309" !CDS_LOCATION = "R8309" &SEC = "1" #&CDS_SEC = "1";
"A":   PN = "1"  !CDS_PN = "1";
"B":   PN = "2"  !CDS_PN = "2";
BODY = "Q_RES","I85": #LOCATION = "R8308" !CDS_LOCATION = "R8308" &SEC = "1" #&CDS_SEC = "1";
"A":   PN = "1"  !CDS_PN = "1";
"B":   PN = "2"  !CDS_PN = "2";
BODY = "Q_RES","I89": #LOCATION = "R8311" !CDS_LOCATION = "R8311" &SEC = "1" #&CDS_SEC = "1";
"A":   PN = "1"  !CDS_PN = "1";
"B":   PN = "2"  !CDS_PN = "2";
BODY = "Q_CAP","I92": #LOCATION = "C467" !CDS_LOCATION = "C467" &SEC = "1" #&CDS_SEC = "1";
"A":   PN = "1"  !CDS_PN = "1";
"B":   PN = "2"  !CDS_PN = "2";
BODY = "Q_CAP","I95": #LOCATION = "PC469" !CDS_LOCATION = "PC469" &SEC = "1" #&CDS_SEC = "1";
"A":   PN = "1"  !CDS_PN = "1";
"B":   PN = "2"  !CDS_PN = "2";
BODY = "Q_CAP","I98": #LOCATION = "PC472" !CDS_LOCATION = "PC472" &SEC = "1" #&CDS_SEC = "1";
"A":   PN = "1"  !CDS_PN = "1";
"B":   PN = "2"  !CDS_PN = "2";
BODY = "Q_RES","I107": #LOCATION = "PR441" !CDS_LOCATION = "PR441" &SEC = "1" #&CDS_SEC = "1";
"A":   PN = "1"  !CDS_PN = "1";
"B":   PN = "2"  !CDS_PN = "2";
BODY = "Q_RES","I108": #LOCATION = "PR440" !CDS_LOCATION = "PR440" &SEC = "1" #&CDS_SEC = "1";
"A":   PN = "1"  !CDS_PN = "1";
"B":   PN = "2"  !CDS_PN = "2";
BODY = "Q_RES","I111": #LOCATION = "PR531" !CDS_LOCATION = "PR531" &SEC = "1" #&CDS_SEC = "1";
"A":   PN = "1"  !CDS_PN = "1";
"B":   PN = "2"  !CDS_PN = "2";
BODY = "Q_CAP","I120": #LOCATION = "PC12" !CDS_LOCATION = "PC12" &SEC = "1" #&CDS_SEC = "1";
"A":   PN = "1"  !CDS_PN = "1";
"B":   PN = "2"  !CDS_PN = "2";
BODY = "Q_CAP","I129": #LOCATION = "PC470" !CDS_LOCATION = "PC470" &SEC = "1" #&CDS_SEC = "1";
"A":   PN = "1"  !CDS_PN = "1";
"B":   PN = "2"  !CDS_PN = "2";
BODY = "Q_CAP","I131": #LOCATION = "PC471" !CDS_LOCATION = "PC471" &SEC = "1" #&CDS_SEC = "1";
"A":   PN = "1"  !CDS_PN = "1";
"B":   PN = "2"  !CDS_PN = "2";
BODY = "Q_RES","I133": #LOCATION = "PR316" !CDS_LOCATION = "PR316" &SEC = "1" #&CDS_SEC = "1";
"A":   PN = "1"  !CDS_PN = "1";
"B":   PN = "2"  !CDS_PN = "2";
BODY = "RAA229620GNPHA0","I135": #LOCATION = "PU42" !CDS_LOCATION = "PU42" #SEC = "1" !CDS_SEC = "1";
"CS0":   PN = "38"  !CDS_PN = "38";
"CS1":   PN = "37"  !CDS_PN = "37";
"CS2":   PN = "36"  !CDS_PN = "36";
"CS3":   PN = "35"  !CDS_PN = "35";
"CS4":   PN = "34"  !CDS_PN = "34";
"CS5":   PN = "33"  !CDS_PN = "33";
"CS6":   PN = "32"  !CDS_PN = "32";
"CS7":   PN = "31"  !CDS_PN = "31";
"CS8":   PN = "30"  !CDS_PN = "30";
"CS9":   PN = "29"  !CDS_PN = "29";
"CS10":   PN = "28"  !CDS_PN = "28";
"CS11":   PN = "27"  !CDS_PN = "27";
"EN0":   PN = "17"  !CDS_PN = "17";
"EN1||ADDR_CFG":   PN = "42"  !CDS_PN = "42";
"NPMALERT":   PN = "15"  !CDS_PN = "15";
"OCP_L":   PN = "41"  !CDS_PN = "41";
"PG0":   PN = "16"  !CDS_PN = "16";
"PG1":   PN = "20"  !CDS_PN = "20";
"PMSCL":   PN = "14"  !CDS_PN = "14";
"PMSDA":   PN = "13"  !CDS_PN = "13";
"PWM0":   PN = "1"  !CDS_PN = "1";
"PWM1":   PN = "2"  !CDS_PN = "2";
"PWM2":   PN = "3"  !CDS_PN = "3";
"PWM3":   PN = "4"  !CDS_PN = "4";
"PWM4":   PN = "5"  !CDS_PN = "5";
"PWM5":   PN = "6"  !CDS_PN = "6";
"PWM6":   PN = "7"  !CDS_PN = "7";
"PWM7":   PN = "8"  !CDS_PN = "8";
"PWM8":   PN = "9"  !CDS_PN = "9";
"PWM9":   PN = "10"  !CDS_PN = "10";
"PWM10":   PN = "11"  !CDS_PN = "11";
"PWM11":   PN = "12"  !CDS_PN = "12";
"RESET_L":   PN = "18"  !CDS_PN = "18";
"RGND0":   PN = "26"  !CDS_PN = "26";
"RGND1":   PN = "39"  !CDS_PN = "39";
"SVC":   PN = "22"  !CDS_PN = "22";
"SVD":   PN = "21"  !CDS_PN = "21";
"SVTI":   PN = "24"  !CDS_PN = "24";
"SVTO":   PN = "23"  !CDS_PN = "23";
"TEMP0":   PN = "44"  !CDS_PN = "44";
"TEMP1":   PN = "43"  !CDS_PN = "43";
"TH_GND":   PN = "TH"  !CDS_PN = "TH";
"VCC":   PN = "47"  !CDS_PN = "47";
"VCCS":   PN = "48"  !CDS_PN = "48";
"VDDIO":   PN = "19"  !CDS_PN = "19";
"VINSEN":   PN = "46"  !CDS_PN = "46";
"VMON||IINSEN":   PN = "45"  !CDS_PN = "45";
"VSEN0":   PN = "25"  !CDS_PN = "25";
"VSEN1":   PN = "40"  !CDS_PN = "40";
BODY = "Q_RES","I136": #LOCATION = "R6089" !CDS_LOCATION = "R6089" &SEC = "1" #&CDS_SEC = "1";
"A":   PN = "1"  !CDS_PN = "1";
"B":   PN = "2"  !CDS_PN = "2";
BODY = "Q_CAP","I138": #LOCATION = "C5018" !CDS_LOCATION = "C5018" &SEC = "1" #&CDS_SEC = "1";
"A":   PN = "1"  !CDS_PN = "1";
"B":   PN = "2"  !CDS_PN = "2";
BODY = "Q_CAP","I139": #LOCATION = "C5017" !CDS_LOCATION = "C5017" &SEC = "1" #&CDS_SEC = "1";
"A":   PN = "1"  !CDS_PN = "1";
"B":   PN = "2"  !CDS_PN = "2";
BODY = "Q_CAP","I142": #LOCATION = "C5011" !CDS_LOCATION = "C5011" &SEC = "1" #&CDS_SEC = "1";
"A":   PN = "1"  !CDS_PN = "1";
"B":   PN = "2"  !CDS_PN = "2";
BODY = "CONN3_210HP1030BR1","I143": #LOCATION = "PJ1" !CDS_LOCATION = "PJ1" &SEC = "1" #&CDS_SEC = "1";
"1":   PN = "1"  !CDS_PN = "1";
"2":   PN = "2"  !CDS_PN = "2";
"3":   PN = "3"  !CDS_PN = "3";
BODY = "Q_RES","I147": #LOCATION = "PR8005" !CDS_LOCATION = "PR8005" &SEC = "1" #&CDS_SEC = "1";
"A":   PN = "1"  !CDS_PN = "1";
"B":   PN = "2"  !CDS_PN = "2";
BODY = "Q_RES","I148": #LOCATION = "PR8006" !CDS_LOCATION = "PR8006" &SEC = "1" #&CDS_SEC = "1";
"A":   PN = "1"  !CDS_PN = "1";
"B":   PN = "2"  !CDS_PN = "2";
DRAWING = "@t6g_mb_lib.t6g(sch_1):page169";
BODY = "Q_RES","I3": #LOCATION = "PR445" !CDS_LOCATION = "PR445" &SEC = "1" #&CDS_SEC = "1";
"A":   PN = "1"  !CDS_PN = "1";
"B":   PN = "2"  !CDS_PN = "2";
BODY = "Q_RES","I4": #LOCATION = "PR446" !CDS_LOCATION = "PR446" &SEC = "1" #&CDS_SEC = "1";
"A":   PN = "1"  !CDS_PN = "1";
"B":   PN = "2"  !CDS_PN = "2";
BODY = "ISL99390FRZTR5935","I16": #LOCATION = "PU43" !CDS_LOCATION = "PU43" &SEC = "1" #&CDS_SEC = "1";
"AGND":   PN = "2"  !CDS_PN = "2";
"BOOT":   PN = "33"  !CDS_PN = "33";
"DNC":   PN = "31"  !CDS_PN = "31";
"EN":   PN = "35"  !CDS_PN = "35";
"GL1":   PN = "6"  !CDS_PN = "6";
"GL2":   PN = "41"  !CDS_PN = "41";
"IOUT":   PN = "38"  !CDS_PN = "38";
"LSET":   PN = "37"  !CDS_PN = "37";
"PGND1":   PN = "5"  !CDS_PN = "5";
"PGND2":   PN = "7_9-20_24"  !CDS_PN = "7_9-20_24";
"PGND3":   PN = "40"  !CDS_PN = "40";
"PHASE":   PN = "32"  !CDS_PN = "32";
"PVCC":   PN = "4"  !CDS_PN = "4";
"PWM":   PN = "34"  !CDS_PN = "34";
"REFIN":   PN = "39"  !CDS_PN = "39";
"SW":   PN = "10_19"  !CDS_PN = "10_19";
"TOUT_FLT":   PN = "36"  !CDS_PN = "36";
"VCC":   PN = "3"  !CDS_PN = "3";
"VIN1":   PN = "25_29"  !CDS_PN = "25_29";
"VIN2":   PN = "30"  !CDS_PN = "30";
"VOS":   PN = "1"  !CDS_PN = "1";
BODY = "Q_RES","I17": #LOCATION = "PR319" !CDS_LOCATION = "PR319" &SEC = "1" #&CDS_SEC = "1";
"A":   PN = "1"  !CDS_PN = "1";
"B":   PN = "2"  !CDS_PN = "2";
BODY = "Q_CAP","I19": #LOCATION = "PC478_C0P0_2" !CDS_LOCATION = "PC478_C0P0_2" &SEC = "1" #&CDS_SEC = "1";
"A":   PN = "1"  !CDS_PN = "1";
"B":   PN = "2"  !CDS_PN = "2";
BODY = "ISL99390FRZTR5935","I26": #LOCATION = "PU6" !CDS_LOCATION = "PU6" &SEC = "1" #&CDS_SEC = "1";
"AGND":   PN = "2"  !CDS_PN = "2";
"BOOT":   PN = "33"  !CDS_PN = "33";
"DNC":   PN = "31"  !CDS_PN = "31";
"EN":   PN = "35"  !CDS_PN = "35";
"GL1":   PN = "6"  !CDS_PN = "6";
"GL2":   PN = "41"  !CDS_PN = "41";
"IOUT":   PN = "38"  !CDS_PN = "38";
"LSET":   PN = "37"  !CDS_PN = "37";
"PGND1":   PN = "5"  !CDS_PN = "5";
"PGND2":   PN = "7_9-20_24"  !CDS_PN = "7_9-20_24";
"PGND3":   PN = "40"  !CDS_PN = "40";
"PHASE":   PN = "32"  !CDS_PN = "32";
"PVCC":   PN = "4"  !CDS_PN = "4";
"PWM":   PN = "34"  !CDS_PN = "34";
"REFIN":   PN = "39"  !CDS_PN = "39";
"SW":   PN = "10_19"  !CDS_PN = "10_19";
"TOUT_FLT":   PN = "36"  !CDS_PN = "36";
"VCC":   PN = "3"  !CDS_PN = "3";
"VIN1":   PN = "25_29"  !CDS_PN = "25_29";
"VIN2":   PN = "30"  !CDS_PN = "30";
"VOS":   PN = "1"  !CDS_PN = "1";
BODY = "Q_CAP","I31": #LOCATION = "PC179" !CDS_LOCATION = "PC179" &SEC = "1" #&CDS_SEC = "1";
"A":   PN = "1"  !CDS_PN = "1";
"B":   PN = "2"  !CDS_PN = "2";
BODY = "Q_RES","I32": #LOCATION = "PR323" !CDS_LOCATION = "PR323" &SEC = "1" #&CDS_SEC = "1";
"A":   PN = "1"  !CDS_PN = "1";
"B":   PN = "2"  !CDS_PN = "2";
BODY = "Q_CAP","I33": #LOCATION = "PC482_2" !CDS_LOCATION = "PC482_2" &SEC = "1" #&CDS_SEC = "1";
"A":   PN = "1"  !CDS_PN = "1";
"B":   PN = "2"  !CDS_PN = "2";
BODY = "Q_INDUCTOR4P_14","I62": #LOCATION = "PL52" !CDS_LOCATION = "PL52" &SEC = "1" #&CDS_SEC = "1";
"1":   PN = "1"  !CDS_PN = "1";
"2":   PN = "2"  !CDS_PN = "2";
"3":   PN = "3"  !CDS_PN = "3";
"4":   PN = "4"  !CDS_PN = "4";
BODY = "Q_CAPP","I64": #LOCATION = "PC108" !CDS_LOCATION = "PC108" &SEC = "1" #&CDS_SEC = "1";
"A":   PN = "1"  !CDS_PN = "1";
"B":   PN = "2"  !CDS_PN = "2";
BODY = "Q_CAPP","I65": #LOCATION = "PC494" !CDS_LOCATION = "PC494" &SEC = "1" #&CDS_SEC = "1";
"A":   PN = "1"  !CDS_PN = "1";
"B":   PN = "2"  !CDS_PN = "2";
BODY = "Q_CAPP","I66": #LOCATION = "PC495" !CDS_LOCATION = "PC495" &SEC = "1" #&CDS_SEC = "1";
"A":   PN = "1"  !CDS_PN = "1";
"B":   PN = "2"  !CDS_PN = "2";
BODY = "Q_CAPP","I67": #LOCATION = "PC496" !CDS_LOCATION = "PC496" &SEC = "1" #&CDS_SEC = "1";
"A":   PN = "1"  !CDS_PN = "1";
"B":   PN = "2"  !CDS_PN = "2";
BODY = "Q_CAP","I68": #LOCATION = "PC499_2" !CDS_LOCATION = "PC499_2" &SEC = "1" #&CDS_SEC = "1";
"A":   PN = "1"  !CDS_PN = "1";
"B":   PN = "2"  !CDS_PN = "2";
BODY = "Q_CAP","I8": #LOCATION = "PC474_2" !CDS_LOCATION = "PC474_2" &SEC = "1" #&CDS_SEC = "1";
"A":   PN = "1"  !CDS_PN = "1";
"B":   PN = "2"  !CDS_PN = "2";
BODY = "Q_RES","I10": #LOCATION = "PR321" !CDS_LOCATION = "PR321" &SEC = "1" #&CDS_SEC = "1";
"A":   PN = "1"  !CDS_PN = "1";
"B":   PN = "2"  !CDS_PN = "2";
BODY = "Q_CAP","I14": #LOCATION = "PC476" !CDS_LOCATION = "PC476" &SEC = "1" #&CDS_SEC = "1";
"A":   PN = "1"  !CDS_PN = "1";
"B":   PN = "2"  !CDS_PN = "2";
BODY = "Q_CAP","I22": #LOCATION = "PC473_1" !CDS_LOCATION = "PC473_1" &SEC = "1" #&CDS_SEC = "1";
"A":   PN = "1"  !CDS_PN = "1";
"B":   PN = "2"  !CDS_PN = "2";
BODY = "Q_RES","I28": #LOCATION = "PR496" !CDS_LOCATION = "PR496" &SEC = "1" #&CDS_SEC = "1";
"A":   PN = "1"  !CDS_PN = "1";
"B":   PN = "2"  !CDS_PN = "2";
BODY = "Q_RES","I30": #LOCATION = "PR325" !CDS_LOCATION = "PR325" &SEC = "1" #&CDS_SEC = "1";
"A":   PN = "1"  !CDS_PN = "1";
"B":   PN = "2"  !CDS_PN = "2";
BODY = "Q_CAP","I34": #LOCATION = "PC480_2" !CDS_LOCATION = "PC480_2" &SEC = "1" #&CDS_SEC = "1";
"A":   PN = "1"  !CDS_PN = "1";
"B":   PN = "2"  !CDS_PN = "2";
BODY = "Q_CAP","I36": #LOCATION = "PC484_2" !CDS_LOCATION = "PC484_2" &SEC = "1" #&CDS_SEC = "1";
"A":   PN = "1"  !CDS_PN = "1";
"B":   PN = "2"  !CDS_PN = "2";
BODY = "Q_CAP","I37": #LOCATION = "PC486_2" !CDS_LOCATION = "PC486_2" &SEC = "1" #&CDS_SEC = "1";
"A":   PN = "1"  !CDS_PN = "1";
"B":   PN = "2"  !CDS_PN = "2";
BODY = "Q_CAP","I39": #LOCATION = "PC488_2" !CDS_LOCATION = "PC488_2" &SEC = "1" #&CDS_SEC = "1";
"A":   PN = "1"  !CDS_PN = "1";
"B":   PN = "2"  !CDS_PN = "2";
BODY = "Q_RES","I42": #LOCATION = "PR495" !CDS_LOCATION = "PR495" &SEC = "1" #&CDS_SEC = "1";
"A":   PN = "1"  !CDS_PN = "1";
"B":   PN = "2"  !CDS_PN = "2";
BODY = "Q_RES","I43": #LOCATION = "PR324" !CDS_LOCATION = "PR324" &SEC = "1" #&CDS_SEC = "1";
"A":   PN = "1"  !CDS_PN = "1";
"B":   PN = "2"  !CDS_PN = "2";
BODY = "Q_CAP","I45": #LOCATION = "PC475" !CDS_LOCATION = "PC475" &SEC = "1" #&CDS_SEC = "1";
"A":   PN = "1"  !CDS_PN = "1";
"B":   PN = "2"  !CDS_PN = "2";
BODY = "Q_RES","I46": #LOCATION = "PR320" !CDS_LOCATION = "PR320" &SEC = "1" #&CDS_SEC = "1";
"A":   PN = "1"  !CDS_PN = "1";
"B":   PN = "2"  !CDS_PN = "2";
BODY = "Q_RES","I49": #LOCATION = "PR318" !CDS_LOCATION = "PR318" &SEC = "1" #&CDS_SEC = "1";
"A":   PN = "1"  !CDS_PN = "1";
"B":   PN = "2"  !CDS_PN = "2";
BODY = "Q_CAP","I51": #LOCATION = "PC477_C0P0_1" !CDS_LOCATION = "PC477_C0P0_1" &SEC = "1" #&CDS_SEC = "1";
"A":   PN = "1"  !CDS_PN = "1";
"B":   PN = "2"  !CDS_PN = "2";
BODY = "Q_CAP","I52": #LOCATION = "PC479_1" !CDS_LOCATION = "PC479_1" &SEC = "1" #&CDS_SEC = "1";
"A":   PN = "1"  !CDS_PN = "1";
"B":   PN = "2"  !CDS_PN = "2";
BODY = "Q_CAP","I53": #LOCATION = "PC481_1" !CDS_LOCATION = "PC481_1" &SEC = "1" #&CDS_SEC = "1";
"A":   PN = "1"  !CDS_PN = "1";
"B":   PN = "2"  !CDS_PN = "2";
BODY = "Q_CAP","I54": #LOCATION = "PC178" !CDS_LOCATION = "PC178" &SEC = "1" #&CDS_SEC = "1";
"A":   PN = "1"  !CDS_PN = "1";
"B":   PN = "2"  !CDS_PN = "2";
BODY = "Q_RES","I55": #LOCATION = "PR322" !CDS_LOCATION = "PR322" &SEC = "1" #&CDS_SEC = "1";
"A":   PN = "1"  !CDS_PN = "1";
"B":   PN = "2"  !CDS_PN = "2";
BODY = "Q_CAP","I57": #LOCATION = "PC483_1" !CDS_LOCATION = "PC483_1" &SEC = "1" #&CDS_SEC = "1";
"A":   PN = "1"  !CDS_PN = "1";
"B":   PN = "2"  !CDS_PN = "2";
BODY = "Q_CAP","I58": #LOCATION = "PC485_1" !CDS_LOCATION = "PC485_1" &SEC = "1" #&CDS_SEC = "1";
"A":   PN = "1"  !CDS_PN = "1";
"B":   PN = "2"  !CDS_PN = "2";
BODY = "Q_CAP","I59": #LOCATION = "PC487_1" !CDS_LOCATION = "PC487_1" &SEC = "1" #&CDS_SEC = "1";
"A":   PN = "1"  !CDS_PN = "1";
"B":   PN = "2"  !CDS_PN = "2";
BODY = "Q_CAP","I61": #LOCATION = "PC490" !CDS_LOCATION = "PC490" &SEC = "1" #&CDS_SEC = "1";
"A":   PN = "1"  !CDS_PN = "1";
"B":   PN = "2"  !CDS_PN = "2";
BODY = "Q_CAP","I70": #LOCATION = "PC501_2" !CDS_LOCATION = "PC501_2" &SEC = "1" #&CDS_SEC = "1";
"A":   PN = "1"  !CDS_PN = "1";
"B":   PN = "2"  !CDS_PN = "2";
BODY = "Q_CAPP","I73": #LOCATION = "PC498" !CDS_LOCATION = "PC498" &SEC = "1" #&CDS_SEC = "1";
"A":   PN = "1"  !CDS_PN = "1";
"B":   PN = "2"  !CDS_PN = "2";
BODY = "Q_CAP","I76": #LOCATION = "PC489" !CDS_LOCATION = "PC489" &SEC = "1" #&CDS_SEC = "1";
"A":   PN = "1"  !CDS_PN = "1";
"B":   PN = "2"  !CDS_PN = "2";
BODY = "Q_INDUCTOR4P_14","I77": #LOCATION = "PL51" !CDS_LOCATION = "PL51" &SEC = "1" #&CDS_SEC = "1";
"1":   PN = "1"  !CDS_PN = "1";
"2":   PN = "2"  !CDS_PN = "2";
"3":   PN = "3"  !CDS_PN = "3";
"4":   PN = "4"  !CDS_PN = "4";
BODY = "Q_CAPP","I79": #LOCATION = "PC491" !CDS_LOCATION = "PC491" &SEC = "1" #&CDS_SEC = "1";
"A":   PN = "1"  !CDS_PN = "1";
"B":   PN = "2"  !CDS_PN = "2";
BODY = "Q_CAPP","I81": #LOCATION = "PC492" !CDS_LOCATION = "PC492" &SEC = "1" #&CDS_SEC = "1";
"A":   PN = "1"  !CDS_PN = "1";
"B":   PN = "2"  !CDS_PN = "2";
BODY = "Q_INDUCTOR","I82": #LOCATION = "PL53" !CDS_LOCATION = "PL53" &SEC = "1" #&CDS_SEC = "1";
"1":   PN = "1"  !CDS_PN = "1";
"2":   PN = "2"  !CDS_PN = "2";
BODY = "Q_CAP","I85": #LOCATION = "PC479" !CDS_LOCATION = "PC479" &SEC = "1" #&CDS_SEC = "1";
"A":   PN = "1"  !CDS_PN = "1";
"B":   PN = "2"  !CDS_PN = "2";
BODY = "Q_CAP","I87": #LOCATION = "PC497" !CDS_LOCATION = "PC497" &SEC = "1" #&CDS_SEC = "1";
"A":   PN = "1"  !CDS_PN = "1";
"B":   PN = "2"  !CDS_PN = "2";
BODY = "Q_CAP","I88": #LOCATION = "PC500_1" !CDS_LOCATION = "PC500_1" &SEC = "1" #&CDS_SEC = "1";
"A":   PN = "1"  !CDS_PN = "1";
"B":   PN = "2"  !CDS_PN = "2";
BODY = "Q_CAP","I89": #LOCATION = "PC502_1" !CDS_LOCATION = "PC502_1" &SEC = "1" #&CDS_SEC = "1";
"A":   PN = "1"  !CDS_PN = "1";
"B":   PN = "2"  !CDS_PN = "2";
BODY = "Q_RES","I90": #LOCATION = "PR447" !CDS_LOCATION = "PR447" &SEC = "1" #&CDS_SEC = "1";
"A":   PN = "1"  !CDS_PN = "1";
"B":   PN = "2"  !CDS_PN = "2";
DRAWING = "@t6g_mb_lib.t6g(sch_1):page170";
BODY = "Q_RES","I18": #LOCATION = "PR499" !CDS_LOCATION = "PR499" &SEC = "1" #&CDS_SEC = "1";
"A":   PN = "1"  !CDS_PN = "1";
"B":   PN = "2"  !CDS_PN = "2";
BODY = "Q_CAP","I19": #LOCATION = "PC181" !CDS_LOCATION = "PC181" &SEC = "1" #&CDS_SEC = "1";
"A":   PN = "1"  !CDS_PN = "1";
"B":   PN = "2"  !CDS_PN = "2";
BODY = "Q_RES","I20": #LOCATION = "PR349" !CDS_LOCATION = "PR349" &SEC = "1" #&CDS_SEC = "1";
"A":   PN = "1"  !CDS_PN = "1";
"B":   PN = "2"  !CDS_PN = "2";
BODY = "Q_CAP","I21": #LOCATION = "PC551_4" !CDS_LOCATION = "PC551_4" &SEC = "1" #&CDS_SEC = "1";
"A":   PN = "1"  !CDS_PN = "1";
"B":   PN = "2"  !CDS_PN = "2";
BODY = "Q_CAP","I23": #LOCATION = "PC555_4" !CDS_LOCATION = "PC555_4" &SEC = "1" #&CDS_SEC = "1";
"A":   PN = "1"  !CDS_PN = "1";
"B":   PN = "2"  !CDS_PN = "2";
BODY = "Q_RES","I26": #LOCATION = "PR350" !CDS_LOCATION = "PR350" &SEC = "1" #&CDS_SEC = "1";
"A":   PN = "1"  !CDS_PN = "1";
"B":   PN = "2"  !CDS_PN = "2";
BODY = "Q_RES","I33": #LOCATION = "PR346" !CDS_LOCATION = "PR346" &SEC = "1" #&CDS_SEC = "1";
"A":   PN = "1"  !CDS_PN = "1";
"B":   PN = "2"  !CDS_PN = "2";
BODY = "Q_CAP","I2": #LOCATION = "PC545_4" !CDS_LOCATION = "PC545_4" &SEC = "1" #&CDS_SEC = "1";
"A":   PN = "1"  !CDS_PN = "1";
"B":   PN = "2"  !CDS_PN = "2";
BODY = "Q_CAP","I6": #LOCATION = "PC547" !CDS_LOCATION = "PC547" &SEC = "1" #&CDS_SEC = "1";
"A":   PN = "1"  !CDS_PN = "1";
"B":   PN = "2"  !CDS_PN = "2";
BODY = "ISL99390FRZTR5935","I9": #LOCATION = "PU47" !CDS_LOCATION = "PU47" &SEC = "1" #&CDS_SEC = "1";
"AGND":   PN = "2"  !CDS_PN = "2";
"BOOT":   PN = "33"  !CDS_PN = "33";
"DNC":   PN = "31"  !CDS_PN = "31";
"EN":   PN = "35"  !CDS_PN = "35";
"GL1":   PN = "6"  !CDS_PN = "6";
"GL2":   PN = "41"  !CDS_PN = "41";
"IOUT":   PN = "38"  !CDS_PN = "38";
"LSET":   PN = "37"  !CDS_PN = "37";
"PGND1":   PN = "5"  !CDS_PN = "5";
"PGND2":   PN = "7_9-20_24"  !CDS_PN = "7_9-20_24";
"PGND3":   PN = "40"  !CDS_PN = "40";
"PHASE":   PN = "32"  !CDS_PN = "32";
"PVCC":   PN = "4"  !CDS_PN = "4";
"PWM":   PN = "34"  !CDS_PN = "34";
"REFIN":   PN = "39"  !CDS_PN = "39";
"SW":   PN = "10_19"  !CDS_PN = "10_19";
"TOUT_FLT":   PN = "36"  !CDS_PN = "36";
"VCC":   PN = "3"  !CDS_PN = "3";
"VIN1":   PN = "25_29"  !CDS_PN = "25_29";
"VIN2":   PN = "30"  !CDS_PN = "30";
"VOS":   PN = "1"  !CDS_PN = "1";
BODY = "Q_RES","I11": #LOCATION = "PR347" !CDS_LOCATION = "PR347" &SEC = "1" #&CDS_SEC = "1";
"A":   PN = "1"  !CDS_PN = "1";
"B":   PN = "2"  !CDS_PN = "2";
BODY = "Q_RES","I12": #LOCATION = "PR345" !CDS_LOCATION = "PR345" &SEC = "1" #&CDS_SEC = "1";
"A":   PN = "1"  !CDS_PN = "1";
"B":   PN = "2"  !CDS_PN = "2";
BODY = "Q_CAP","I15": #LOCATION = "PC549_C0P0_4" !CDS_LOCATION = "PC549_C0P0_4" &SEC = "1" #&CDS_SEC = "1";
"A":   PN = "1"  !CDS_PN = "1";
"B":   PN = "2"  !CDS_PN = "2";
BODY = "Q_CAP","I22": #LOCATION = "PC553_4" !CDS_LOCATION = "PC553_4" &SEC = "1" #&CDS_SEC = "1";
"A":   PN = "1"  !CDS_PN = "1";
"B":   PN = "2"  !CDS_PN = "2";
BODY = "Q_CAP","I24": #LOCATION = "PC557_4" !CDS_LOCATION = "PC557_4" &SEC = "1" #&CDS_SEC = "1";
"A":   PN = "1"  !CDS_PN = "1";
"B":   PN = "2"  !CDS_PN = "2";
BODY = "Q_CAP","I27": #LOCATION = "PC544_3" !CDS_LOCATION = "PC544_3" &SEC = "1" #&CDS_SEC = "1";
"A":   PN = "1"  !CDS_PN = "1";
"B":   PN = "2"  !CDS_PN = "2";
BODY = "Q_CAP","I36": #LOCATION = "PC546" !CDS_LOCATION = "PC546" &SEC = "1" #&CDS_SEC = "1";
"A":   PN = "1"  !CDS_PN = "1";
"B":   PN = "2"  !CDS_PN = "2";
BODY = "Q_RES","I37": #LOCATION = "PR344" !CDS_LOCATION = "PR344" &SEC = "1" #&CDS_SEC = "1";
"A":   PN = "1"  !CDS_PN = "1";
"B":   PN = "2"  !CDS_PN = "2";
BODY = "ISL99390FRZTR5935","I38": #LOCATION = "PU46" !CDS_LOCATION = "PU46" &SEC = "1" #&CDS_SEC = "1";
"AGND":   PN = "2"  !CDS_PN = "2";
"BOOT":   PN = "33"  !CDS_PN = "33";
"DNC":   PN = "31"  !CDS_PN = "31";
"EN":   PN = "35"  !CDS_PN = "35";
"GL1":   PN = "6"  !CDS_PN = "6";
"GL2":   PN = "41"  !CDS_PN = "41";
"IOUT":   PN = "38"  !CDS_PN = "38";
"LSET":   PN = "37"  !CDS_PN = "37";
"PGND1":   PN = "5"  !CDS_PN = "5";
"PGND2":   PN = "7_9-20_24"  !CDS_PN = "7_9-20_24";
"PGND3":   PN = "40"  !CDS_PN = "40";
"PHASE":   PN = "32"  !CDS_PN = "32";
"PVCC":   PN = "4"  !CDS_PN = "4";
"PWM":   PN = "34"  !CDS_PN = "34";
"REFIN":   PN = "39"  !CDS_PN = "39";
"SW":   PN = "10_19"  !CDS_PN = "10_19";
"TOUT_FLT":   PN = "36"  !CDS_PN = "36";
"VCC":   PN = "3"  !CDS_PN = "3";
"VIN1":   PN = "25_29"  !CDS_PN = "25_29";
"VIN2":   PN = "30"  !CDS_PN = "30";
"VOS":   PN = "1"  !CDS_PN = "1";
BODY = "Q_CAP","I40": #LOCATION = "PC548_C0P0_3" !CDS_LOCATION = "PC548_C0P0_3" &SEC = "1" #&CDS_SEC = "1";
"A":   PN = "1"  !CDS_PN = "1";
"B":   PN = "2"  !CDS_PN = "2";
BODY = "Q_CAP","I43": #LOCATION = "PC552_3" !CDS_LOCATION = "PC552_3" &SEC = "1" #&CDS_SEC = "1";
"A":   PN = "1"  !CDS_PN = "1";
"B":   PN = "2"  !CDS_PN = "2";
BODY = "Q_RES","I44": #LOCATION = "PR498" !CDS_LOCATION = "PR498" &SEC = "1" #&CDS_SEC = "1";
"A":   PN = "1"  !CDS_PN = "1";
"B":   PN = "2"  !CDS_PN = "2";
BODY = "Q_CAP","I45": #LOCATION = "PC180" !CDS_LOCATION = "PC180" &SEC = "1" #&CDS_SEC = "1";
"A":   PN = "1"  !CDS_PN = "1";
"B":   PN = "2"  !CDS_PN = "2";
BODY = "Q_RES","I46": #LOCATION = "PR348" !CDS_LOCATION = "PR348" &SEC = "1" #&CDS_SEC = "1";
"A":   PN = "1"  !CDS_PN = "1";
"B":   PN = "2"  !CDS_PN = "2";
BODY = "Q_CAP","I47": #LOCATION = "PC550_3" !CDS_LOCATION = "PC550_3" &SEC = "1" #&CDS_SEC = "1";
"A":   PN = "1"  !CDS_PN = "1";
"B":   PN = "2"  !CDS_PN = "2";
BODY = "Q_CAP","I48": #LOCATION = "PC554_3" !CDS_LOCATION = "PC554_3" &SEC = "1" #&CDS_SEC = "1";
"A":   PN = "1"  !CDS_PN = "1";
"B":   PN = "2"  !CDS_PN = "2";
BODY = "Q_CAP","I49": #LOCATION = "PC556_3" !CDS_LOCATION = "PC556_3" &SEC = "1" #&CDS_SEC = "1";
"A":   PN = "1"  !CDS_PN = "1";
"B":   PN = "2"  !CDS_PN = "2";
BODY = "Q_RES","I50": #LOCATION = "PR351" !CDS_LOCATION = "PR351" &SEC = "1" #&CDS_SEC = "1";
"A":   PN = "1"  !CDS_PN = "1";
"B":   PN = "2"  !CDS_PN = "2";
BODY = "Q_INDUCTOR4P_14","I52": #LOCATION = "PL60" !CDS_LOCATION = "PL60" &SEC = "1" #&CDS_SEC = "1";
"1":   PN = "1"  !CDS_PN = "1";
"2":   PN = "2"  !CDS_PN = "2";
"3":   PN = "3"  !CDS_PN = "3";
"4":   PN = "4"  !CDS_PN = "4";
BODY = "Q_CAP","I53": #LOCATION = "PC561" !CDS_LOCATION = "PC561" &SEC = "1" #&CDS_SEC = "1";
"A":   PN = "1"  !CDS_PN = "1";
"B":   PN = "2"  !CDS_PN = "2";
BODY = "Q_CAP","I55": #LOCATION = "PC559_4" !CDS_LOCATION = "PC559_4" &SEC = "1" #&CDS_SEC = "1";
"A":   PN = "1"  !CDS_PN = "1";
"B":   PN = "2"  !CDS_PN = "2";
BODY = "Q_CAP","I58": #LOCATION = "PC563_4" !CDS_LOCATION = "PC563_4" &SEC = "1" #&CDS_SEC = "1";
"A":   PN = "1"  !CDS_PN = "1";
"B":   PN = "2"  !CDS_PN = "2";
BODY = "Q_CAP","I60": #LOCATION = "PC565_4" !CDS_LOCATION = "PC565_4" &SEC = "1" #&CDS_SEC = "1";
"A":   PN = "1"  !CDS_PN = "1";
"B":   PN = "2"  !CDS_PN = "2";
BODY = "Q_CAP","I63": #LOCATION = "PC560" !CDS_LOCATION = "PC560" &SEC = "1" #&CDS_SEC = "1";
"A":   PN = "1"  !CDS_PN = "1";
"B":   PN = "2"  !CDS_PN = "2";
BODY = "Q_INDUCTOR4P_14","I64": #LOCATION = "PL59" !CDS_LOCATION = "PL59" &SEC = "1" #&CDS_SEC = "1";
"1":   PN = "1"  !CDS_PN = "1";
"2":   PN = "2"  !CDS_PN = "2";
"3":   PN = "3"  !CDS_PN = "3";
"4":   PN = "4"  !CDS_PN = "4";
BODY = "Q_CAP","I66": #LOCATION = "PC558_3" !CDS_LOCATION = "PC558_3" &SEC = "1" #&CDS_SEC = "1";
"A":   PN = "1"  !CDS_PN = "1";
"B":   PN = "2"  !CDS_PN = "2";
BODY = "Q_CAP","I70": #LOCATION = "PC562_3" !CDS_LOCATION = "PC562_3" &SEC = "1" #&CDS_SEC = "1";
"A":   PN = "1"  !CDS_PN = "1";
"B":   PN = "2"  !CDS_PN = "2";
BODY = "Q_CAP","I71": #LOCATION = "PC564_3" !CDS_LOCATION = "PC564_3" &SEC = "1" #&CDS_SEC = "1";
"A":   PN = "1"  !CDS_PN = "1";
"B":   PN = "2"  !CDS_PN = "2";
DRAWING = "@t6g_mb_lib.t6g(sch_1):page173";
BODY = "Q_CAP","I4": #LOCATION = "PC578_8" !CDS_LOCATION = "PC578_8" &SEC = "1" #&CDS_SEC = "1";
"A":   PN = "1"  !CDS_PN = "1";
"B":   PN = "2"  !CDS_PN = "2";
BODY = "Q_RES","I19": #LOCATION = "PR503" !CDS_LOCATION = "PR503" &SEC = "1" #&CDS_SEC = "1";
"A":   PN = "1"  !CDS_PN = "1";
"B":   PN = "2"  !CDS_PN = "2";
BODY = "Q_RES","I22": #LOCATION = "PR361" !CDS_LOCATION = "PR361" &SEC = "1" #&CDS_SEC = "1";
"A":   PN = "1"  !CDS_PN = "1";
"B":   PN = "2"  !CDS_PN = "2";
BODY = "Q_CAP","I23": #LOCATION = "PC584_2" !CDS_LOCATION = "PC584_2" &SEC = "1" #&CDS_SEC = "1";
"A":   PN = "1"  !CDS_PN = "1";
"B":   PN = "2"  !CDS_PN = "2";
BODY = "Q_CAP","I24": #LOCATION = "PC588_2" !CDS_LOCATION = "PC588_2" &SEC = "1" #&CDS_SEC = "1";
"A":   PN = "1"  !CDS_PN = "1";
"B":   PN = "2"  !CDS_PN = "2";
BODY = "Q_CAP","I25": #LOCATION = "PC590_2" !CDS_LOCATION = "PC590_2" &SEC = "1" #&CDS_SEC = "1";
"A":   PN = "1"  !CDS_PN = "1";
"B":   PN = "2"  !CDS_PN = "2";
BODY = "Q_CAP","I29": #LOCATION = "PC577_7" !CDS_LOCATION = "PC577_7" &SEC = "1" #&CDS_SEC = "1";
"A":   PN = "1"  !CDS_PN = "1";
"B":   PN = "2"  !CDS_PN = "2";
BODY = "Q_CAP","I43": #LOCATION = "PC583_1" !CDS_LOCATION = "PC583_1" &SEC = "1" #&CDS_SEC = "1";
"A":   PN = "1"  !CDS_PN = "1";
"B":   PN = "2"  !CDS_PN = "2";
BODY = "Q_RES","I48": #LOCATION = "PR360" !CDS_LOCATION = "PR360" &SEC = "1" #&CDS_SEC = "1";
"A":   PN = "1"  !CDS_PN = "1";
"B":   PN = "2"  !CDS_PN = "2";
BODY = "Q_CAP","I52": #LOCATION = "PC594" !CDS_LOCATION = "PC594" &SEC = "1" #&CDS_SEC = "1";
"A":   PN = "1"  !CDS_PN = "1";
"B":   PN = "2"  !CDS_PN = "2";
BODY = "Q_CAPP","I63": #LOCATION = "PC597" !CDS_LOCATION = "PC597" &SEC = "1" #&CDS_SEC = "1";
"A":   PN = "1"  !CDS_PN = "1";
"B":   PN = "2"  !CDS_PN = "2";
BODY = "Q_CAPP","I66": #LOCATION = "PC601" !CDS_LOCATION = "PC601" &SEC = "1" #&CDS_SEC = "1";
"A":   PN = "1"  !CDS_PN = "1";
"B":   PN = "2"  !CDS_PN = "2";
BODY = "Q_CAP","I68": #LOCATION = "PC593" !CDS_LOCATION = "PC593" &SEC = "1" #&CDS_SEC = "1";
"A":   PN = "1"  !CDS_PN = "1";
"B":   PN = "2"  !CDS_PN = "2";
BODY = "Q_INDUCTOR4P_14","I69": #LOCATION = "PL63" !CDS_LOCATION = "PL63" &SEC = "1" #&CDS_SEC = "1";
"1":   PN = "1"  !CDS_PN = "1";
"2":   PN = "2"  !CDS_PN = "2";
"3":   PN = "3"  !CDS_PN = "3";
"4":   PN = "4"  !CDS_PN = "4";
BODY = "Q_CAP","I79": #LOCATION = "PC599" !CDS_LOCATION = "PC599" &SEC = "1" #&CDS_SEC = "1";
"A":   PN = "1"  !CDS_PN = "1";
"B":   PN = "2"  !CDS_PN = "2";
BODY = "Q_CAP","I83": #LOCATION = "PC604_1" !CDS_LOCATION = "PC604_1" &SEC = "1" #&CDS_SEC = "1";
"A":   PN = "1"  !CDS_PN = "1";
"B":   PN = "2"  !CDS_PN = "2";
BODY = "Q_RES","I8": #LOCATION = "PR359" !CDS_LOCATION = "PR359" &SEC = "1" #&CDS_SEC = "1";
"A":   PN = "1"  !CDS_PN = "1";
"B":   PN = "2"  !CDS_PN = "2";
BODY = "Q_CAP","I11": #LOCATION = "PC580" !CDS_LOCATION = "PC580" &SEC = "1" #&CDS_SEC = "1";
"A":   PN = "1"  !CDS_PN = "1";
"B":   PN = "2"  !CDS_PN = "2";
BODY = "Q_RES","I12": #LOCATION = "PR357" !CDS_LOCATION = "PR357" &SEC = "1" #&CDS_SEC = "1";
"A":   PN = "1"  !CDS_PN = "1";
"B":   PN = "2"  !CDS_PN = "2";
BODY = "Q_CAP","I14": #LOCATION = "PC582_SOP0_2" !CDS_LOCATION = "PC582_SOP0_2" &SEC = "1" #&CDS_SEC = "1";
"A":   PN = "1"  !CDS_PN = "1";
"B":   PN = "2"  !CDS_PN = "2";
BODY = "Q_RES","I18": #LOCATION = "PR363" !CDS_LOCATION = "PR363" &SEC = "1" #&CDS_SEC = "1";
"A":   PN = "1"  !CDS_PN = "1";
"B":   PN = "2"  !CDS_PN = "2";
BODY = "Q_CAP","I21": #LOCATION = "PC586_2" !CDS_LOCATION = "PC586_2" &SEC = "1" #&CDS_SEC = "1";
"A":   PN = "1"  !CDS_PN = "1";
"B":   PN = "2"  !CDS_PN = "2";
BODY = "Q_RES","I27": #LOCATION = "PR362" !CDS_LOCATION = "PR362" &SEC = "1" #&CDS_SEC = "1";
"A":   PN = "1"  !CDS_PN = "1";
"B":   PN = "2"  !CDS_PN = "2";
BODY = "Q_RES","I32": #LOCATION = "PR358" !CDS_LOCATION = "PR358" &SEC = "1" #&CDS_SEC = "1";
"A":   PN = "1"  !CDS_PN = "1";
"B":   PN = "2"  !CDS_PN = "2";
BODY = "Q_CAP","I36": #LOCATION = "PC579" !CDS_LOCATION = "PC579" &SEC = "1" #&CDS_SEC = "1";
"A":   PN = "1"  !CDS_PN = "1";
"B":   PN = "2"  !CDS_PN = "2";
BODY = "Q_RES","I38": #LOCATION = "PR356" !CDS_LOCATION = "PR356" &SEC = "1" #&CDS_SEC = "1";
"A":   PN = "1"  !CDS_PN = "1";
"B":   PN = "2"  !CDS_PN = "2";
BODY = "Q_CAP","I40": #LOCATION = "PC581_SOP0_1" !CDS_LOCATION = "PC581_SOP0_1" &SEC = "1" #&CDS_SEC = "1";
"A":   PN = "1"  !CDS_PN = "1";
"B":   PN = "2"  !CDS_PN = "2";
BODY = "ISL99390FRZTR5935","I41": #LOCATION = "PU49" !CDS_LOCATION = "PU49" &SEC = "1" #&CDS_SEC = "1";
"AGND":   PN = "2"  !CDS_PN = "2";
"BOOT":   PN = "33"  !CDS_PN = "33";
"DNC":   PN = "31"  !CDS_PN = "31";
"EN":   PN = "35"  !CDS_PN = "35";
"GL1":   PN = "6"  !CDS_PN = "6";
"GL2":   PN = "41"  !CDS_PN = "41";
"IOUT":   PN = "38"  !CDS_PN = "38";
"LSET":   PN = "37"  !CDS_PN = "37";
"PGND1":   PN = "5"  !CDS_PN = "5";
"PGND2":   PN = "7_9-20_24"  !CDS_PN = "7_9-20_24";
"PGND3":   PN = "40"  !CDS_PN = "40";
"PHASE":   PN = "32"  !CDS_PN = "32";
"PVCC":   PN = "4"  !CDS_PN = "4";
"PWM":   PN = "34"  !CDS_PN = "34";
"REFIN":   PN = "39"  !CDS_PN = "39";
"SW":   PN = "10_19"  !CDS_PN = "10_19";
"TOUT_FLT":   PN = "36"  !CDS_PN = "36";
"VCC":   PN = "3"  !CDS_PN = "3";
"VIN1":   PN = "25_29"  !CDS_PN = "25_29";
"VIN2":   PN = "30"  !CDS_PN = "30";
"VOS":   PN = "1"  !CDS_PN = "1";
BODY = "Q_CAP","I44": #LOCATION = "PC585_1" !CDS_LOCATION = "PC585_1" &SEC = "1" #&CDS_SEC = "1";
"A":   PN = "1"  !CDS_PN = "1";
"B":   PN = "2"  !CDS_PN = "2";
BODY = "Q_RES","I45": #LOCATION = "PR502" !CDS_LOCATION = "PR502" &SEC = "1" #&CDS_SEC = "1";
"A":   PN = "1"  !CDS_PN = "1";
"B":   PN = "2"  !CDS_PN = "2";
BODY = "Q_CAP","I46": #LOCATION = "PC185" !CDS_LOCATION = "PC185" &SEC = "1" #&CDS_SEC = "1";
"A":   PN = "1"  !CDS_PN = "1";
"B":   PN = "2"  !CDS_PN = "2";
BODY = "Q_CAP","I49": #LOCATION = "PC587_1" !CDS_LOCATION = "PC587_1" &SEC = "1" #&CDS_SEC = "1";
"A":   PN = "1"  !CDS_PN = "1";
"B":   PN = "2"  !CDS_PN = "2";
BODY = "Q_CAP","I50": #LOCATION = "PC589_1" !CDS_LOCATION = "PC589_1" &SEC = "1" #&CDS_SEC = "1";
"A":   PN = "1"  !CDS_PN = "1";
"B":   PN = "2"  !CDS_PN = "2";
BODY = "Q_CAP","I51": #LOCATION = "PC591_1" !CDS_LOCATION = "PC591_1" &SEC = "1" #&CDS_SEC = "1";
"A":   PN = "1"  !CDS_PN = "1";
"B":   PN = "2"  !CDS_PN = "2";
BODY = "Q_INDUCTOR4P_14","I53": #LOCATION = "PL64" !CDS_LOCATION = "PL64" &SEC = "1" #&CDS_SEC = "1";
"1":   PN = "1"  !CDS_PN = "1";
"2":   PN = "2"  !CDS_PN = "2";
"3":   PN = "3"  !CDS_PN = "3";
"4":   PN = "4"  !CDS_PN = "4";
BODY = "Q_CAP","I56": #LOCATION = "PC592_2" !CDS_LOCATION = "PC592_2" &SEC = "1" #&CDS_SEC = "1";
"A":   PN = "1"  !CDS_PN = "1";
"B":   PN = "2"  !CDS_PN = "2";
BODY = "Q_CAP","I57": #LOCATION = "PC595_2" !CDS_LOCATION = "PC595_2" &SEC = "1" #&CDS_SEC = "1";
"A":   PN = "1"  !CDS_PN = "1";
"B":   PN = "2"  !CDS_PN = "2";
BODY = "Q_CAP","I59": #LOCATION = "PC600_2" !CDS_LOCATION = "PC600_2" &SEC = "1" #&CDS_SEC = "1";
"A":   PN = "1"  !CDS_PN = "1";
"B":   PN = "2"  !CDS_PN = "2";
BODY = "Q_CAP","I61": #LOCATION = "PC603_2" !CDS_LOCATION = "PC603_2" &SEC = "1" #&CDS_SEC = "1";
"A":   PN = "1"  !CDS_PN = "1";
"B":   PN = "2"  !CDS_PN = "2";
BODY = "Q_CAPP","I64": #LOCATION = "PC598" !CDS_LOCATION = "PC598" &SEC = "1" #&CDS_SEC = "1";
"A":   PN = "1"  !CDS_PN = "1";
"B":   PN = "2"  !CDS_PN = "2";
BODY = "Q_CAP","I72": #LOCATION = "PC593_1" !CDS_LOCATION = "PC593_1" &SEC = "1" #&CDS_SEC = "1";
"A":   PN = "1"  !CDS_PN = "1";
"B":   PN = "2"  !CDS_PN = "2";
BODY = "Q_CAPP","I73": #LOCATION = "PC596" !CDS_LOCATION = "PC596" &SEC = "1" #&CDS_SEC = "1";
"A":   PN = "1"  !CDS_PN = "1";
"B":   PN = "2"  !CDS_PN = "2";
BODY = "Q_INDUCTOR","I74": #LOCATION = "PL65" !CDS_LOCATION = "PL65" &SEC = "1" #&CDS_SEC = "1";
"1":   PN = "1"  !CDS_PN = "1";
"2":   PN = "2"  !CDS_PN = "2";
BODY = "Q_CAP","I77": #LOCATION = "PC583" !CDS_LOCATION = "PC583" &SEC = "1" #&CDS_SEC = "1";
"A":   PN = "1"  !CDS_PN = "1";
"B":   PN = "2"  !CDS_PN = "2";
BODY = "Q_CAP","I80": #LOCATION = "PC602_1" !CDS_LOCATION = "PC602_1" &SEC = "1" #&CDS_SEC = "1";
"A":   PN = "1"  !CDS_PN = "1";
"B":   PN = "2"  !CDS_PN = "2";
BODY = "Q_RES","I82": #LOCATION = "PR334" !CDS_LOCATION = "PR334" &SEC = "1" #&CDS_SEC = "1";
"A":   PN = "1"  !CDS_PN = "1";
"B":   PN = "2"  !CDS_PN = "2";
BODY = "Q_CAP","I85": #LOCATION = "PC187" !CDS_LOCATION = "PC187" &SEC = "1" #&CDS_SEC = "1";
"A":   PN = "1"  !CDS_PN = "1";
"B":   PN = "2"  !CDS_PN = "2";
BODY = "ISL99390FRZTR5935","I86": #LOCATION = "PU50" !CDS_LOCATION = "PU50" &SEC = "1" #&CDS_SEC = "1";
"AGND":   PN = "2"  !CDS_PN = "2";
"BOOT":   PN = "33"  !CDS_PN = "33";
"DNC":   PN = "31"  !CDS_PN = "31";
"EN":   PN = "35"  !CDS_PN = "35";
"GL1":   PN = "6"  !CDS_PN = "6";
"GL2":   PN = "41"  !CDS_PN = "41";
"IOUT":   PN = "38"  !CDS_PN = "38";
"LSET":   PN = "37"  !CDS_PN = "37";
"PGND1":   PN = "5"  !CDS_PN = "5";
"PGND2":   PN = "7_9-20_24"  !CDS_PN = "7_9-20_24";
"PGND3":   PN = "40"  !CDS_PN = "40";
"PHASE":   PN = "32"  !CDS_PN = "32";
"PVCC":   PN = "4"  !CDS_PN = "4";
"PWM":   PN = "34"  !CDS_PN = "34";
"REFIN":   PN = "39"  !CDS_PN = "39";
"SW":   PN = "10_19"  !CDS_PN = "10_19";
"TOUT_FLT":   PN = "36"  !CDS_PN = "36";
"VCC":   PN = "3"  !CDS_PN = "3";
"VIN1":   PN = "25_29"  !CDS_PN = "25_29";
"VIN2":   PN = "30"  !CDS_PN = "30";
"VOS":   PN = "1"  !CDS_PN = "1";
BODY = "Q_CAP","I87": #LOCATION = "PC8009" !CDS_LOCATION = "PC8009" &SEC = "1" #&CDS_SEC = "1";
"A":   PN = "1"  !CDS_PN = "1";
"B":   PN = "2"  !CDS_PN = "2";
BODY = "Q_CAP","I88": #LOCATION = "PC8010" !CDS_LOCATION = "PC8010" &SEC = "1" #&CDS_SEC = "1";
"A":   PN = "1"  !CDS_PN = "1";
"B":   PN = "2"  !CDS_PN = "2";
DRAWING = "@t6g_mb_lib.t6g(sch_1):page174";
BODY = "Q_RES","I7": #LOCATION = "PR365" !CDS_LOCATION = "PR365" &SEC = "1" #&CDS_SEC = "1";
"A":   PN = "1"  !CDS_PN = "1";
"B":   PN = "2"  !CDS_PN = "2";
BODY = "Q_RES","I20": #LOCATION = "PR366" !CDS_LOCATION = "PR366" &SEC = "1" #&CDS_SEC = "1";
"A":   PN = "1"  !CDS_PN = "1";
"B":   PN = "2"  !CDS_PN = "2";
BODY = "Q_CAP","I21": #LOCATION = "PC608_3" !CDS_LOCATION = "PC608_3" &SEC = "1" #&CDS_SEC = "1";
"A":   PN = "1"  !CDS_PN = "1";
"B":   PN = "2"  !CDS_PN = "2";
BODY = "Q_CAP","I22": #LOCATION = "PC610_3" !CDS_LOCATION = "PC610_3" &SEC = "1" #&CDS_SEC = "1";
"A":   PN = "1"  !CDS_PN = "1";
"B":   PN = "2"  !CDS_PN = "2";
BODY = "Q_INDUCTOR4P_14","I25": #LOCATION = "PL66" !CDS_LOCATION = "PL66" &SEC = "1" #&CDS_SEC = "1";
"1":   PN = "1"  !CDS_PN = "1";
"2":   PN = "2"  !CDS_PN = "2";
"3":   PN = "3"  !CDS_PN = "3";
"4":   PN = "4"  !CDS_PN = "4";
BODY = "Q_CAP","I29": #LOCATION = "PC615_3" !CDS_LOCATION = "PC615_3" &SEC = "1" #&CDS_SEC = "1";
"A":   PN = "1"  !CDS_PN = "1";
"B":   PN = "2"  !CDS_PN = "2";
BODY = "Q_CAP","I31": #LOCATION = "PC611_3" !CDS_LOCATION = "PC611_3" &SEC = "1" #&CDS_SEC = "1";
"A":   PN = "1"  !CDS_PN = "1";
"B":   PN = "2"  !CDS_PN = "2";
BODY = "Q_CAP","I32": #LOCATION = "PC613_3" !CDS_LOCATION = "PC613_3" &SEC = "1" #&CDS_SEC = "1";
"A":   PN = "1"  !CDS_PN = "1";
"B":   PN = "2"  !CDS_PN = "2";
BODY = "Q_CAP","I37": #LOCATION = "PC609_3" !CDS_LOCATION = "PC609_3" &SEC = "1" #&CDS_SEC = "1";
"A":   PN = "1"  !CDS_PN = "1";
"B":   PN = "2"  !CDS_PN = "2";
BODY = "ISL99390FRZTR5935","I38": #LOCATION = "PU51" !CDS_LOCATION = "PU51" &SEC = "1" #&CDS_SEC = "1";
"AGND":   PN = "2"  !CDS_PN = "2";
"BOOT":   PN = "33"  !CDS_PN = "33";
"DNC":   PN = "31"  !CDS_PN = "31";
"EN":   PN = "35"  !CDS_PN = "35";
"GL1":   PN = "6"  !CDS_PN = "6";
"GL2":   PN = "41"  !CDS_PN = "41";
"IOUT":   PN = "38"  !CDS_PN = "38";
"LSET":   PN = "37"  !CDS_PN = "37";
"PGND1":   PN = "5"  !CDS_PN = "5";
"PGND2":   PN = "7_9-20_24"  !CDS_PN = "7_9-20_24";
"PGND3":   PN = "40"  !CDS_PN = "40";
"PHASE":   PN = "32"  !CDS_PN = "32";
"PVCC":   PN = "4"  !CDS_PN = "4";
"PWM":   PN = "34"  !CDS_PN = "34";
"REFIN":   PN = "39"  !CDS_PN = "39";
"SW":   PN = "10_19"  !CDS_PN = "10_19";
"TOUT_FLT":   PN = "36"  !CDS_PN = "36";
"VCC":   PN = "3"  !CDS_PN = "3";
"VIN1":   PN = "25_29"  !CDS_PN = "25_29";
"VIN2":   PN = "30"  !CDS_PN = "30";
"VOS":   PN = "1"  !CDS_PN = "1";
BODY = "Q_CAP","I2": #LOCATION = "PC605_9" !CDS_LOCATION = "PC605_9" &SEC = "1" #&CDS_SEC = "1";
"A":   PN = "1"  !CDS_PN = "1";
"B":   PN = "2"  !CDS_PN = "2";
BODY = "Q_RES","I10": #LOCATION = "PR505" !CDS_LOCATION = "PR505" &SEC = "1" #&CDS_SEC = "1";
"A":   PN = "1"  !CDS_PN = "1";
"B":   PN = "2"  !CDS_PN = "2";
BODY = "Q_RES","I11": #LOCATION = "PR367" !CDS_LOCATION = "PR367" &SEC = "1" #&CDS_SEC = "1";
"A":   PN = "1"  !CDS_PN = "1";
"B":   PN = "2"  !CDS_PN = "2";
BODY = "Q_CAP","I12": #LOCATION = "PC188" !CDS_LOCATION = "PC188" &SEC = "1" #&CDS_SEC = "1";
"A":   PN = "1"  !CDS_PN = "1";
"B":   PN = "2"  !CDS_PN = "2";
BODY = "Q_CAP","I14": #LOCATION = "PC606" !CDS_LOCATION = "PC606" &SEC = "1" #&CDS_SEC = "1";
"A":   PN = "1"  !CDS_PN = "1";
"B":   PN = "2"  !CDS_PN = "2";
BODY = "Q_RES","I15": #LOCATION = "PR364" !CDS_LOCATION = "PR364" &SEC = "1" #&CDS_SEC = "1";
"A":   PN = "1"  !CDS_PN = "1";
"B":   PN = "2"  !CDS_PN = "2";
BODY = "Q_CAP","I19": #LOCATION = "PC607_SOP0_3" !CDS_LOCATION = "PC607_SOP0_3" &SEC = "1" #&CDS_SEC = "1";
"A":   PN = "1"  !CDS_PN = "1";
"B":   PN = "2"  !CDS_PN = "2";
BODY = "Q_INDUCTOR","I24": #LOCATION = "PL62" !CDS_LOCATION = "PL62" &SEC = "1" #&CDS_SEC = "1";
"1":   PN = "1"  !CDS_PN = "1";
"2":   PN = "2"  !CDS_PN = "2";
BODY = "Q_CAP","I27": #LOCATION = "PC614_3" !CDS_LOCATION = "PC614_3" &SEC = "1" #&CDS_SEC = "1";
"A":   PN = "1"  !CDS_PN = "1";
"B":   PN = "2"  !CDS_PN = "2";
BODY = "Q_CAP","I30": #LOCATION = "PC612" !CDS_LOCATION = "PC612" &SEC = "1" #&CDS_SEC = "1";
"A":   PN = "1"  !CDS_PN = "1";
"B":   PN = "2"  !CDS_PN = "2";
BODY = "Q_CAP","I34": #LOCATION = "PC612_3" !CDS_LOCATION = "PC612_3" &SEC = "1" #&CDS_SEC = "1";
"A":   PN = "1"  !CDS_PN = "1";
"B":   PN = "2"  !CDS_PN = "2";
DRAWING = "@t6g_mb_lib.t6g(sch_1):page176";
BODY = "Q_CAP","I2": #LOCATION = "PC83_2" !CDS_LOCATION = "PC83_2" &SEC = "1" #&CDS_SEC = "1";
"A":   PN = "1"  !CDS_PN = "1";
"B":   PN = "2"  !CDS_PN = "2";
BODY = "Q_RES","I21": #LOCATION = "PR442" !CDS_LOCATION = "PR442" &SEC = "1" #&CDS_SEC = "1";
"A":   PN = "1"  !CDS_PN = "1";
"B":   PN = "2"  !CDS_PN = "2";
BODY = "Q_CAP","I24": #LOCATION = "PC79" !CDS_LOCATION = "PC79" &SEC = "1" #&CDS_SEC = "1";
"A":   PN = "1"  !CDS_PN = "1";
"B":   PN = "2"  !CDS_PN = "2";
BODY = "Q_CAP","I41": #LOCATION = "PC190" !CDS_LOCATION = "PC190" &SEC = "1" #&CDS_SEC = "1";
"A":   PN = "1"  !CDS_PN = "1";
"B":   PN = "2"  !CDS_PN = "2";
BODY = "Q_INDUCTOR4P_14","I46": #LOCATION = "PL11" !CDS_LOCATION = "PL11" &SEC = "1" #&CDS_SEC = "1";
"1":   PN = "1"  !CDS_PN = "1";
"2":   PN = "2"  !CDS_PN = "2";
"3":   PN = "3"  !CDS_PN = "3";
"4":   PN = "4"  !CDS_PN = "4";
BODY = "Q_CAP","I47": #LOCATION = "PC88_2" !CDS_LOCATION = "PC88_2" &SEC = "1" #&CDS_SEC = "1";
"A":   PN = "1"  !CDS_PN = "1";
"B":   PN = "2"  !CDS_PN = "2";
BODY = "Q_CAP","I65": #LOCATION = "PC95_1" !CDS_LOCATION = "PC95_1" &SEC = "1" #&CDS_SEC = "1";
"A":   PN = "1"  !CDS_PN = "1";
"B":   PN = "2"  !CDS_PN = "2";
BODY = "Q_CAPP","I66": #LOCATION = "PC101" !CDS_LOCATION = "PC101" &SEC = "1" #&CDS_SEC = "1";
"A":   PN = "1"  !CDS_PN = "1";
"B":   PN = "2"  !CDS_PN = "2";
BODY = "Q_CAPP","I75": #LOCATION = "PC103" !CDS_LOCATION = "PC103" &SEC = "1" #&CDS_SEC = "1";
"A":   PN = "1"  !CDS_PN = "1";
"B":   PN = "2"  !CDS_PN = "2";
BODY = "Q_CAP","I87": #LOCATION = "PC85" !CDS_LOCATION = "PC85" &SEC = "1" #&CDS_SEC = "1";
"A":   PN = "1"  !CDS_PN = "1";
"B":   PN = "2"  !CDS_PN = "2";
BODY = "Q_RES","I4": #LOCATION = "PR77" !CDS_LOCATION = "PR77" &SEC = "1" #&CDS_SEC = "1";
"A":   PN = "1"  !CDS_PN = "1";
"B":   PN = "2"  !CDS_PN = "2";
BODY = "Q_CAP","I10": #LOCATION = "PC80" !CDS_LOCATION = "PC80" &SEC = "1" #&CDS_SEC = "1";
"A":   PN = "1"  !CDS_PN = "1";
"B":   PN = "2"  !CDS_PN = "2";
BODY = "Q_CAP","I12": #LOCATION = "PC84_1" !CDS_LOCATION = "PC84_1" &SEC = "1" #&CDS_SEC = "1";
"A":   PN = "1"  !CDS_PN = "1";
"B":   PN = "2"  !CDS_PN = "2";
BODY = "Q_RES","I13": #LOCATION = "PR80" !CDS_LOCATION = "PR80" &SEC = "1" #&CDS_SEC = "1";
"A":   PN = "1"  !CDS_PN = "1";
"B":   PN = "2"  !CDS_PN = "2";
BODY = "Q_CAP","I15": #LOCATION = "PC82_C1P0_2" !CDS_LOCATION = "PC82_C1P0_2" &SEC = "1" #&CDS_SEC = "1";
"A":   PN = "1"  !CDS_PN = "1";
"B":   PN = "2"  !CDS_PN = "2";
BODY = "Q_RES","I18": #LOCATION = "PR78" !CDS_LOCATION = "PR78" &SEC = "1" #&CDS_SEC = "1";
"A":   PN = "1"  !CDS_PN = "1";
"B":   PN = "2"  !CDS_PN = "2";
BODY = "Q_RES","I27": #LOCATION = "PR443" !CDS_LOCATION = "PR443" &SEC = "1" #&CDS_SEC = "1";
"A":   PN = "1"  !CDS_PN = "1";
"B":   PN = "2"  !CDS_PN = "2";
BODY = "Q_RES","I29": #LOCATION = "PR79" !CDS_LOCATION = "PR79" &SEC = "1" #&CDS_SEC = "1";
"A":   PN = "1"  !CDS_PN = "1";
"B":   PN = "2"  !CDS_PN = "2";
BODY = "Q_CAP","I30": #LOCATION = "PC81_C1P0_1" !CDS_LOCATION = "PC81_C1P0_1" &SEC = "1" #&CDS_SEC = "1";
"A":   PN = "1"  !CDS_PN = "1";
"B":   PN = "2"  !CDS_PN = "2";
BODY = "ISL99390FRZTR5935","I33": #LOCATION = "PU2" !CDS_LOCATION = "PU2" &SEC = "1" #&CDS_SEC = "1";
"AGND":   PN = "2"  !CDS_PN = "2";
"BOOT":   PN = "33"  !CDS_PN = "33";
"DNC":   PN = "31"  !CDS_PN = "31";
"EN":   PN = "35"  !CDS_PN = "35";
"GL1":   PN = "6"  !CDS_PN = "6";
"GL2":   PN = "41"  !CDS_PN = "41";
"IOUT":   PN = "38"  !CDS_PN = "38";
"LSET":   PN = "37"  !CDS_PN = "37";
"PGND1":   PN = "5"  !CDS_PN = "5";
"PGND2":   PN = "7_9-20_24"  !CDS_PN = "7_9-20_24";
"PGND3":   PN = "40"  !CDS_PN = "40";
"PHASE":   PN = "32"  !CDS_PN = "32";
"PVCC":   PN = "4"  !CDS_PN = "4";
"PWM":   PN = "34"  !CDS_PN = "34";
"REFIN":   PN = "39"  !CDS_PN = "39";
"SW":   PN = "10_19"  !CDS_PN = "10_19";
"TOUT_FLT":   PN = "36"  !CDS_PN = "36";
"VCC":   PN = "3"  !CDS_PN = "3";
"VIN1":   PN = "25_29"  !CDS_PN = "25_29";
"VIN2":   PN = "30"  !CDS_PN = "30";
"VOS":   PN = "1"  !CDS_PN = "1";
BODY = "ISL99390FRZTR5935","I35": #LOCATION = "PU13" !CDS_LOCATION = "PU13" &SEC = "1" #&CDS_SEC = "1";
"AGND":   PN = "2"  !CDS_PN = "2";
"BOOT":   PN = "33"  !CDS_PN = "33";
"DNC":   PN = "31"  !CDS_PN = "31";
"EN":   PN = "35"  !CDS_PN = "35";
"GL1":   PN = "6"  !CDS_PN = "6";
"GL2":   PN = "41"  !CDS_PN = "41";
"IOUT":   PN = "38"  !CDS_PN = "38";
"LSET":   PN = "37"  !CDS_PN = "37";
"PGND1":   PN = "5"  !CDS_PN = "5";
"PGND2":   PN = "7_9-20_24"  !CDS_PN = "7_9-20_24";
"PGND3":   PN = "40"  !CDS_PN = "40";
"PHASE":   PN = "32"  !CDS_PN = "32";
"PVCC":   PN = "4"  !CDS_PN = "4";
"PWM":   PN = "34"  !CDS_PN = "34";
"REFIN":   PN = "39"  !CDS_PN = "39";
"SW":   PN = "10_19"  !CDS_PN = "10_19";
"TOUT_FLT":   PN = "36"  !CDS_PN = "36";
"VCC":   PN = "3"  !CDS_PN = "3";
"VIN1":   PN = "25_29"  !CDS_PN = "25_29";
"VIN2":   PN = "30"  !CDS_PN = "30";
"VOS":   PN = "1"  !CDS_PN = "1";
BODY = "Q_CAP","I37": #LOCATION = "PC86_2" !CDS_LOCATION = "PC86_2" &SEC = "1" #&CDS_SEC = "1";
"A":   PN = "1"  !CDS_PN = "1";
"B":   PN = "2"  !CDS_PN = "2";
BODY = "Q_RES","I39": #LOCATION = "PR507" !CDS_LOCATION = "PR507" &SEC = "1" #&CDS_SEC = "1";
"A":   PN = "1"  !CDS_PN = "1";
"B":   PN = "2"  !CDS_PN = "2";
BODY = "Q_RES","I40": #LOCATION = "PR81" !CDS_LOCATION = "PR81" &SEC = "1" #&CDS_SEC = "1";
"A":   PN = "1"  !CDS_PN = "1";
"B":   PN = "2"  !CDS_PN = "2";
BODY = "Q_RES","I42": #LOCATION = "PR83" !CDS_LOCATION = "PR83" &SEC = "1" #&CDS_SEC = "1";
"A":   PN = "1"  !CDS_PN = "1";
"B":   PN = "2"  !CDS_PN = "2";
BODY = "Q_CAP","I44": #LOCATION = "PC94" !CDS_LOCATION = "PC94" &SEC = "1" #&CDS_SEC = "1";
"A":   PN = "1"  !CDS_PN = "1";
"B":   PN = "2"  !CDS_PN = "2";
BODY = "Q_CAP","I48": #LOCATION = "PC90_2" !CDS_LOCATION = "PC90_2" &SEC = "1" #&CDS_SEC = "1";
"A":   PN = "1"  !CDS_PN = "1";
"B":   PN = "2"  !CDS_PN = "2";
BODY = "Q_RES","I50": #LOCATION = "PR506" !CDS_LOCATION = "PR506" &SEC = "1" #&CDS_SEC = "1";
"A":   PN = "1"  !CDS_PN = "1";
"B":   PN = "2"  !CDS_PN = "2";
BODY = "Q_CAP","I51": #LOCATION = "PC93_2" !CDS_LOCATION = "PC93_2" &SEC = "1" #&CDS_SEC = "1";
"A":   PN = "1"  !CDS_PN = "1";
"B":   PN = "2"  !CDS_PN = "2";
BODY = "Q_CAP","I52": #LOCATION = "PC96_2" !CDS_LOCATION = "PC96_2" &SEC = "1" #&CDS_SEC = "1";
"A":   PN = "1"  !CDS_PN = "1";
"B":   PN = "2"  !CDS_PN = "2";
BODY = "Q_RES","I54": #LOCATION = "PR84" !CDS_LOCATION = "PR84" &SEC = "1" #&CDS_SEC = "1";
"A":   PN = "1"  !CDS_PN = "1";
"B":   PN = "2"  !CDS_PN = "2";
BODY = "Q_CAP","I55": #LOCATION = "PC85_1" !CDS_LOCATION = "PC85_1" &SEC = "1" #&CDS_SEC = "1";
"A":   PN = "1"  !CDS_PN = "1";
"B":   PN = "2"  !CDS_PN = "2";
BODY = "Q_RES","I56": #LOCATION = "PR82" !CDS_LOCATION = "PR82" &SEC = "1" #&CDS_SEC = "1";
"A":   PN = "1"  !CDS_PN = "1";
"B":   PN = "2"  !CDS_PN = "2";
BODY = "Q_CAP","I57": #LOCATION = "PC189" !CDS_LOCATION = "PC189" &SEC = "1" #&CDS_SEC = "1";
"A":   PN = "1"  !CDS_PN = "1";
"B":   PN = "2"  !CDS_PN = "2";
BODY = "Q_CAP","I59": #LOCATION = "PC87_1" !CDS_LOCATION = "PC87_1" &SEC = "1" #&CDS_SEC = "1";
"A":   PN = "1"  !CDS_PN = "1";
"B":   PN = "2"  !CDS_PN = "2";
BODY = "Q_CAP","I60": #LOCATION = "PC89_1" !CDS_LOCATION = "PC89_1" &SEC = "1" #&CDS_SEC = "1";
"A":   PN = "1"  !CDS_PN = "1";
"B":   PN = "2"  !CDS_PN = "2";
BODY = "Q_CAP","I61": #LOCATION = "PC92" !CDS_LOCATION = "PC92" &SEC = "1" #&CDS_SEC = "1";
"A":   PN = "1"  !CDS_PN = "1";
"B":   PN = "2"  !CDS_PN = "2";
BODY = "Q_INDUCTOR4P_14","I62": #LOCATION = "PL10" !CDS_LOCATION = "PL10" &SEC = "1" #&CDS_SEC = "1";
"1":   PN = "1"  !CDS_PN = "1";
"2":   PN = "2"  !CDS_PN = "2";
"3":   PN = "3"  !CDS_PN = "3";
"4":   PN = "4"  !CDS_PN = "4";
BODY = "Q_CAP","I64": #LOCATION = "PC91_1" !CDS_LOCATION = "PC91_1" &SEC = "1" #&CDS_SEC = "1";
"A":   PN = "1"  !CDS_PN = "1";
"B":   PN = "2"  !CDS_PN = "2";
BODY = "Q_CAP","I69": #LOCATION = "PC106_2" !CDS_LOCATION = "PC106_2" &SEC = "1" #&CDS_SEC = "1";
"A":   PN = "1"  !CDS_PN = "1";
"B":   PN = "2"  !CDS_PN = "2";
BODY = "Q_CAPP","I70": #LOCATION = "PC102" !CDS_LOCATION = "PC102" &SEC = "1" #&CDS_SEC = "1";
"A":   PN = "1"  !CDS_PN = "1";
"B":   PN = "2"  !CDS_PN = "2";
BODY = "Q_CAPP","I71": #LOCATION = "PC97" !CDS_LOCATION = "PC97" &SEC = "1" #&CDS_SEC = "1";
"A":   PN = "1"  !CDS_PN = "1";
"B":   PN = "2"  !CDS_PN = "2";
BODY = "Q_CAPP","I72": #LOCATION = "PC98" !CDS_LOCATION = "PC98" &SEC = "1" #&CDS_SEC = "1";
"A":   PN = "1"  !CDS_PN = "1";
"B":   PN = "2"  !CDS_PN = "2";
BODY = "Q_CAPP","I73": #LOCATION = "PC100" !CDS_LOCATION = "PC100" &SEC = "1" #&CDS_SEC = "1";
"A":   PN = "1"  !CDS_PN = "1";
"B":   PN = "2"  !CDS_PN = "2";
BODY = "Q_CAP","I77": #LOCATION = "PC108_2" !CDS_LOCATION = "PC108_2" &SEC = "1" #&CDS_SEC = "1";
"A":   PN = "1"  !CDS_PN = "1";
"B":   PN = "2"  !CDS_PN = "2";
BODY = "Q_CAPP","I82": #LOCATION = "PC104" !CDS_LOCATION = "PC104" &SEC = "1" #&CDS_SEC = "1";
"A":   PN = "1"  !CDS_PN = "1";
"B":   PN = "2"  !CDS_PN = "2";
BODY = "Q_INDUCTOR","I83": #LOCATION = "PL12" !CDS_LOCATION = "PL12" &SEC = "1" #&CDS_SEC = "1";
"1":   PN = "1"  !CDS_PN = "1";
"2":   PN = "2"  !CDS_PN = "2";
BODY = "Q_CAP","I84": #LOCATION = "PC99" !CDS_LOCATION = "PC99" &SEC = "1" #&CDS_SEC = "1";
"A":   PN = "1"  !CDS_PN = "1";
"B":   PN = "2"  !CDS_PN = "2";
BODY = "Q_CAP","I86": #LOCATION = "PC102_1" !CDS_LOCATION = "PC102_1" &SEC = "1" #&CDS_SEC = "1";
"A":   PN = "1"  !CDS_PN = "1";
"B":   PN = "2"  !CDS_PN = "2";
BODY = "Q_CAP","I89": #LOCATION = "PC105_1" !CDS_LOCATION = "PC105_1" &SEC = "1" #&CDS_SEC = "1";
"A":   PN = "1"  !CDS_PN = "1";
"B":   PN = "2"  !CDS_PN = "2";
BODY = "Q_RES","I90": #LOCATION = "PR444" !CDS_LOCATION = "PR444" &SEC = "1" #&CDS_SEC = "1";
"A":   PN = "1"  !CDS_PN = "1";
"B":   PN = "2"  !CDS_PN = "2";
DRAWING = "@t6g_mb_lib.t6g(sch_1):page177";
BODY = "Q_CAP","I2": #LOCATION = "PC113_4" !CDS_LOCATION = "PC113_4" &SEC = "1" #&CDS_SEC = "1";
"A":   PN = "1"  !CDS_PN = "1";
"B":   PN = "2"  !CDS_PN = "2";
BODY = "Q_RES","I30": #LOCATION = "PR88" !CDS_LOCATION = "PR88" &SEC = "1" #&CDS_SEC = "1";
"A":   PN = "1"  !CDS_PN = "1";
"B":   PN = "2"  !CDS_PN = "2";
BODY = "Q_RES","I37": #LOCATION = "PR89" !CDS_LOCATION = "PR89" &SEC = "1" #&CDS_SEC = "1";
"A":   PN = "1"  !CDS_PN = "1";
"B":   PN = "2"  !CDS_PN = "2";
BODY = "Q_CAP","I38": #LOCATION = "PC191" !CDS_LOCATION = "PC191" &SEC = "1" #&CDS_SEC = "1";
"A":   PN = "1"  !CDS_PN = "1";
"B":   PN = "2"  !CDS_PN = "2";
BODY = "Q_RES","I40": #LOCATION = "PR91" !CDS_LOCATION = "PR91" &SEC = "1" #&CDS_SEC = "1";
"A":   PN = "1"  !CDS_PN = "1";
"B":   PN = "2"  !CDS_PN = "2";
BODY = "Q_INDUCTOR4P_14","I42": #LOCATION = "PL13" !CDS_LOCATION = "PL13" &SEC = "1" #&CDS_SEC = "1";
"1":   PN = "1"  !CDS_PN = "1";
"2":   PN = "2"  !CDS_PN = "2";
"3":   PN = "3"  !CDS_PN = "3";
"4":   PN = "4"  !CDS_PN = "4";
BODY = "Q_RES","I51": #LOCATION = "PR92" !CDS_LOCATION = "PR92" &SEC = "1" #&CDS_SEC = "1";
"A":   PN = "1"  !CDS_PN = "1";
"B":   PN = "2"  !CDS_PN = "2";
BODY = "Q_CAP","I55": #LOCATION = "PC128_4" !CDS_LOCATION = "PC128_4" &SEC = "1" #&CDS_SEC = "1";
"A":   PN = "1"  !CDS_PN = "1";
"B":   PN = "2"  !CDS_PN = "2";
BODY = "Q_RES","I4": #LOCATION = "PR85" !CDS_LOCATION = "PR85" &SEC = "1" #&CDS_SEC = "1";
"A":   PN = "1"  !CDS_PN = "1";
"B":   PN = "2"  !CDS_PN = "2";
BODY = "Q_CAP","I7": #LOCATION = "PC109" !CDS_LOCATION = "PC109" &SEC = "1" #&CDS_SEC = "1";
"A":   PN = "1"  !CDS_PN = "1";
"B":   PN = "2"  !CDS_PN = "2";
BODY = "Q_CAP","I12": #LOCATION = "PC114_3" !CDS_LOCATION = "PC114_3" &SEC = "1" #&CDS_SEC = "1";
"A":   PN = "1"  !CDS_PN = "1";
"B":   PN = "2"  !CDS_PN = "2";
BODY = "Q_RES","I13": #LOCATION = "PR87" !CDS_LOCATION = "PR87" &SEC = "1" #&CDS_SEC = "1";
"A":   PN = "1"  !CDS_PN = "1";
"B":   PN = "2"  !CDS_PN = "2";
BODY = "Q_CAP","I16": #LOCATION = "PC111_C1P0_4" !CDS_LOCATION = "PC111_C1P0_4" &SEC = "1" #&CDS_SEC = "1";
"A":   PN = "1"  !CDS_PN = "1";
"B":   PN = "2"  !CDS_PN = "2";
BODY = "Q_RES","I18": #LOCATION = "PR86" !CDS_LOCATION = "PR86" &SEC = "1" #&CDS_SEC = "1";
"A":   PN = "1"  !CDS_PN = "1";
"B":   PN = "2"  !CDS_PN = "2";
BODY = "ISL99390FRZTR5935","I21": #LOCATION = "PU14" !CDS_LOCATION = "PU14" &SEC = "1" #&CDS_SEC = "1";
"AGND":   PN = "2"  !CDS_PN = "2";
"BOOT":   PN = "33"  !CDS_PN = "33";
"DNC":   PN = "31"  !CDS_PN = "31";
"EN":   PN = "35"  !CDS_PN = "35";
"GL1":   PN = "6"  !CDS_PN = "6";
"GL2":   PN = "41"  !CDS_PN = "41";
"IOUT":   PN = "38"  !CDS_PN = "38";
"LSET":   PN = "37"  !CDS_PN = "37";
"PGND1":   PN = "5"  !CDS_PN = "5";
"PGND2":   PN = "7_9-20_24"  !CDS_PN = "7_9-20_24";
"PGND3":   PN = "40"  !CDS_PN = "40";
"PHASE":   PN = "32"  !CDS_PN = "32";
"PVCC":   PN = "4"  !CDS_PN = "4";
"PWM":   PN = "34"  !CDS_PN = "34";
"REFIN":   PN = "39"  !CDS_PN = "39";
"SW":   PN = "10_19"  !CDS_PN = "10_19";
"TOUT_FLT":   PN = "36"  !CDS_PN = "36";
"VCC":   PN = "3"  !CDS_PN = "3";
"VIN1":   PN = "25_29"  !CDS_PN = "25_29";
"VIN2":   PN = "30"  !CDS_PN = "30";
"VOS":   PN = "1"  !CDS_PN = "1";
BODY = "ISL99390FRZTR5935","I23": #LOCATION = "PU15" !CDS_LOCATION = "PU15" &SEC = "1" #&CDS_SEC = "1";
"AGND":   PN = "2"  !CDS_PN = "2";
"BOOT":   PN = "33"  !CDS_PN = "33";
"DNC":   PN = "31"  !CDS_PN = "31";
"EN":   PN = "35"  !CDS_PN = "35";
"GL1":   PN = "6"  !CDS_PN = "6";
"GL2":   PN = "41"  !CDS_PN = "41";
"IOUT":   PN = "38"  !CDS_PN = "38";
"LSET":   PN = "37"  !CDS_PN = "37";
"PGND1":   PN = "5"  !CDS_PN = "5";
"PGND2":   PN = "7_9-20_24"  !CDS_PN = "7_9-20_24";
"PGND3":   PN = "40"  !CDS_PN = "40";
"PHASE":   PN = "32"  !CDS_PN = "32";
"PVCC":   PN = "4"  !CDS_PN = "4";
"PWM":   PN = "34"  !CDS_PN = "34";
"REFIN":   PN = "39"  !CDS_PN = "39";
"SW":   PN = "10_19"  !CDS_PN = "10_19";
"TOUT_FLT":   PN = "36"  !CDS_PN = "36";
"VCC":   PN = "3"  !CDS_PN = "3";
"VIN1":   PN = "25_29"  !CDS_PN = "25_29";
"VIN2":   PN = "30"  !CDS_PN = "30";
"VOS":   PN = "1"  !CDS_PN = "1";
BODY = "Q_CAP","I24": #LOCATION = "PC115_4" !CDS_LOCATION = "PC115_4" &SEC = "1" #&CDS_SEC = "1";
"A":   PN = "1"  !CDS_PN = "1";
"B":   PN = "2"  !CDS_PN = "2";
BODY = "Q_CAP","I28": #LOCATION = "PC110" !CDS_LOCATION = "PC110" &SEC = "1" #&CDS_SEC = "1";
"A":   PN = "1"  !CDS_PN = "1";
"B":   PN = "2"  !CDS_PN = "2";
BODY = "Q_CAP","I32": #LOCATION = "PC112_C1P0_3" !CDS_LOCATION = "PC112_C1P0_3" &SEC = "1" #&CDS_SEC = "1";
"A":   PN = "1"  !CDS_PN = "1";
"B":   PN = "2"  !CDS_PN = "2";
BODY = "Q_CAP","I34": #LOCATION = "PC116_3" !CDS_LOCATION = "PC116_3" &SEC = "1" #&CDS_SEC = "1";
"A":   PN = "1"  !CDS_PN = "1";
"B":   PN = "2"  !CDS_PN = "2";
BODY = "Q_RES","I36": #LOCATION = "PR509" !CDS_LOCATION = "PR509" &SEC = "1" #&CDS_SEC = "1";
"A":   PN = "1"  !CDS_PN = "1";
"B":   PN = "2"  !CDS_PN = "2";
BODY = "Q_CAP","I41": #LOCATION = "PC121" !CDS_LOCATION = "PC121" &SEC = "1" #&CDS_SEC = "1";
"A":   PN = "1"  !CDS_PN = "1";
"B":   PN = "2"  !CDS_PN = "2";
BODY = "Q_CAP","I43": #LOCATION = "PC117_4" !CDS_LOCATION = "PC117_4" &SEC = "1" #&CDS_SEC = "1";
"A":   PN = "1"  !CDS_PN = "1";
"B":   PN = "2"  !CDS_PN = "2";
BODY = "Q_CAP","I44": #LOCATION = "PC119_4" !CDS_LOCATION = "PC119_4" &SEC = "1" #&CDS_SEC = "1";
"A":   PN = "1"  !CDS_PN = "1";
"B":   PN = "2"  !CDS_PN = "2";
BODY = "Q_RES","I46": #LOCATION = "PR510" !CDS_LOCATION = "PR510" &SEC = "1" #&CDS_SEC = "1";
"A":   PN = "1"  !CDS_PN = "1";
"B":   PN = "2"  !CDS_PN = "2";
BODY = "Q_CAP","I47": #LOCATION = "PC123_4" !CDS_LOCATION = "PC123_4" &SEC = "1" #&CDS_SEC = "1";
"A":   PN = "1"  !CDS_PN = "1";
"B":   PN = "2"  !CDS_PN = "2";
BODY = "Q_CAP","I49": #LOCATION = "PC125_4" !CDS_LOCATION = "PC125_4" &SEC = "1" #&CDS_SEC = "1";
"A":   PN = "1"  !CDS_PN = "1";
"B":   PN = "2"  !CDS_PN = "2";
BODY = "Q_CAP","I54": #LOCATION = "PC127_4" !CDS_LOCATION = "PC127_4" &SEC = "1" #&CDS_SEC = "1";
"A":   PN = "1"  !CDS_PN = "1";
"B":   PN = "2"  !CDS_PN = "2";
BODY = "Q_RES","I57": #LOCATION = "PR90" !CDS_LOCATION = "PR90" &SEC = "1" #&CDS_SEC = "1";
"A":   PN = "1"  !CDS_PN = "1";
"B":   PN = "2"  !CDS_PN = "2";
BODY = "Q_CAP","I58": #LOCATION = "PC192" !CDS_LOCATION = "PC192" &SEC = "1" #&CDS_SEC = "1";
"A":   PN = "1"  !CDS_PN = "1";
"B":   PN = "2"  !CDS_PN = "2";
BODY = "Q_CAP","I60": #LOCATION = "PC118_3" !CDS_LOCATION = "PC118_3" &SEC = "1" #&CDS_SEC = "1";
"A":   PN = "1"  !CDS_PN = "1";
"B":   PN = "2"  !CDS_PN = "2";
BODY = "Q_CAP","I61": #LOCATION = "PC120_3" !CDS_LOCATION = "PC120_3" &SEC = "1" #&CDS_SEC = "1";
"A":   PN = "1"  !CDS_PN = "1";
"B":   PN = "2"  !CDS_PN = "2";
BODY = "Q_CAP","I62": #LOCATION = "PC122" !CDS_LOCATION = "PC122" &SEC = "1" #&CDS_SEC = "1";
"A":   PN = "1"  !CDS_PN = "1";
"B":   PN = "2"  !CDS_PN = "2";
BODY = "Q_INDUCTOR4P_14","I64": #LOCATION = "PL14" !CDS_LOCATION = "PL14" &SEC = "1" #&CDS_SEC = "1";
"1":   PN = "1"  !CDS_PN = "1";
"2":   PN = "2"  !CDS_PN = "2";
"3":   PN = "3"  !CDS_PN = "3";
"4":   PN = "4"  !CDS_PN = "4";
BODY = "Q_CAP","I65": #LOCATION = "PC124_3" !CDS_LOCATION = "PC124_3" &SEC = "1" #&CDS_SEC = "1";
"A":   PN = "1"  !CDS_PN = "1";
"B":   PN = "2"  !CDS_PN = "2";
BODY = "Q_CAP","I66": #LOCATION = "PC126_3" !CDS_LOCATION = "PC126_3" &SEC = "1" #&CDS_SEC = "1";
"A":   PN = "1"  !CDS_PN = "1";
"B":   PN = "2"  !CDS_PN = "2";
BODY = "Q_CAP","I69": #LOCATION = "PC129_3" !CDS_LOCATION = "PC129_3" &SEC = "1" #&CDS_SEC = "1";
"A":   PN = "1"  !CDS_PN = "1";
"B":   PN = "2"  !CDS_PN = "2";
BODY = "Q_CAP","I71": #LOCATION = "PC130_3" !CDS_LOCATION = "PC130_3" &SEC = "1" #&CDS_SEC = "1";
"A":   PN = "1"  !CDS_PN = "1";
"B":   PN = "2"  !CDS_PN = "2";
DRAWING = "@t6g_mb_lib.t6g(sch_1):page178";
BODY = "Q_CAP","I31": #LOCATION = "PC133_C1P0_5" !CDS_LOCATION = "PC133_C1P0_5" &SEC = "1" #&CDS_SEC = "1";
"A":   PN = "1"  !CDS_PN = "1";
"B":   PN = "2"  !CDS_PN = "2";
BODY = "Q_RES","I39": #LOCATION = "PR420" !CDS_LOCATION = "PR420" &SEC = "1" #&CDS_SEC = "1";
"A":   PN = "1"  !CDS_PN = "1";
"B":   PN = "2"  !CDS_PN = "2";
BODY = "Q_CAP","I40": #LOCATION = "PC114_6" !CDS_LOCATION = "PC114_6" &SEC = "1" #&CDS_SEC = "1";
"A":   PN = "1"  !CDS_PN = "1";
"B":   PN = "2"  !CDS_PN = "2";
BODY = "Q_CAP","I59": #LOCATION = "PC135_5" !CDS_LOCATION = "PC135_5" &SEC = "1" #&CDS_SEC = "1";
"A":   PN = "1"  !CDS_PN = "1";
"B":   PN = "2"  !CDS_PN = "2";
BODY = "Q_CAP","I60": #LOCATION = "PC136_5" !CDS_LOCATION = "PC136_5" &SEC = "1" #&CDS_SEC = "1";
"A":   PN = "1"  !CDS_PN = "1";
"B":   PN = "2"  !CDS_PN = "2";
BODY = "Q_CAP","I2": #LOCATION = "PC111_6" !CDS_LOCATION = "PC111_6" &SEC = "1" #&CDS_SEC = "1";
"A":   PN = "1"  !CDS_PN = "1";
"B":   PN = "2"  !CDS_PN = "2";
BODY = "Q_RES","I4": #LOCATION = "PR7" !CDS_LOCATION = "PR7" &SEC = "1" #&CDS_SEC = "1";
"A":   PN = "1"  !CDS_PN = "1";
"B":   PN = "2"  !CDS_PN = "2";
BODY = "Q_CAP","I10": #LOCATION = "PC132_5" !CDS_LOCATION = "PC132_5" &SEC = "1" #&CDS_SEC = "1";
"A":   PN = "1"  !CDS_PN = "1";
"B":   PN = "2"  !CDS_PN = "2";
BODY = "Q_CAP","I11": #LOCATION = "PC112" !CDS_LOCATION = "PC112" &SEC = "1" #&CDS_SEC = "1";
"A":   PN = "1"  !CDS_PN = "1";
"B":   PN = "2"  !CDS_PN = "2";
BODY = "Q_RES","I13": #LOCATION = "PR416" !CDS_LOCATION = "PR416" &SEC = "1" #&CDS_SEC = "1";
"A":   PN = "1"  !CDS_PN = "1";
"B":   PN = "2"  !CDS_PN = "2";
BODY = "Q_RES","I15": #LOCATION = "PR93" !CDS_LOCATION = "PR93" &SEC = "1" #&CDS_SEC = "1";
"A":   PN = "1"  !CDS_PN = "1";
"B":   PN = "2"  !CDS_PN = "2";
BODY = "Q_CAP","I20": #LOCATION = "PC113_C1P0_6" !CDS_LOCATION = "PC113_C1P0_6" &SEC = "1" #&CDS_SEC = "1";
"A":   PN = "1"  !CDS_PN = "1";
"B":   PN = "2"  !CDS_PN = "2";
BODY = "ISL99390FRZTR5935","I22": #LOCATION = "PU16" !CDS_LOCATION = "PU16" &SEC = "1" #&CDS_SEC = "1";
"AGND":   PN = "2"  !CDS_PN = "2";
"BOOT":   PN = "33"  !CDS_PN = "33";
"DNC":   PN = "31"  !CDS_PN = "31";
"EN":   PN = "35"  !CDS_PN = "35";
"GL1":   PN = "6"  !CDS_PN = "6";
"GL2":   PN = "41"  !CDS_PN = "41";
"IOUT":   PN = "38"  !CDS_PN = "38";
"LSET":   PN = "37"  !CDS_PN = "37";
"PGND1":   PN = "5"  !CDS_PN = "5";
"PGND2":   PN = "7_9-20_24"  !CDS_PN = "7_9-20_24";
"PGND3":   PN = "40"  !CDS_PN = "40";
"PHASE":   PN = "32"  !CDS_PN = "32";
"PVCC":   PN = "4"  !CDS_PN = "4";
"PWM":   PN = "34"  !CDS_PN = "34";
"REFIN":   PN = "39"  !CDS_PN = "39";
"SW":   PN = "10_19"  !CDS_PN = "10_19";
"TOUT_FLT":   PN = "36"  !CDS_PN = "36";
"VCC":   PN = "3"  !CDS_PN = "3";
"VIN1":   PN = "25_29"  !CDS_PN = "25_29";
"VIN2":   PN = "30"  !CDS_PN = "30";
"VOS":   PN = "1"  !CDS_PN = "1";
BODY = "Q_CAP","I27": #LOCATION = "PC131" !CDS_LOCATION = "PC131" &SEC = "1" #&CDS_SEC = "1";
"A":   PN = "1"  !CDS_PN = "1";
"B":   PN = "2"  !CDS_PN = "2";
BODY = "Q_RES","I28": #LOCATION = "PR94" !CDS_LOCATION = "PR94" &SEC = "1" #&CDS_SEC = "1";
"A":   PN = "1"  !CDS_PN = "1";
"B":   PN = "2"  !CDS_PN = "2";
BODY = "Q_RES","I33": #LOCATION = "PR155" !CDS_LOCATION = "PR155" &SEC = "1" #&CDS_SEC = "1";
"A":   PN = "1"  !CDS_PN = "1";
"B":   PN = "2"  !CDS_PN = "2";
BODY = "Q_RES","I35": #LOCATION = "PR421" !CDS_LOCATION = "PR421" &SEC = "1" #&CDS_SEC = "1";
"A":   PN = "1"  !CDS_PN = "1";
"B":   PN = "2"  !CDS_PN = "2";
BODY = "Q_INDUCTOR","I36": #LOCATION = "PL9" !CDS_LOCATION = "PL9" &SEC = "1" #&CDS_SEC = "1";
"1":   PN = "1"  !CDS_PN = "1";
"2":   PN = "2"  !CDS_PN = "2";
BODY = "Q_CAP","I37": #LOCATION = "PC117" !CDS_LOCATION = "PC117" &SEC = "1" #&CDS_SEC = "1";
"A":   PN = "1"  !CDS_PN = "1";
"B":   PN = "2"  !CDS_PN = "2";
BODY = "Q_INDUCTOR4P_14","I38": #LOCATION = "PL7" !CDS_LOCATION = "PL7" &SEC = "1" #&CDS_SEC = "1";
"1":   PN = "1"  !CDS_PN = "1";
"2":   PN = "2"  !CDS_PN = "2";
"3":   PN = "3"  !CDS_PN = "3";
"4":   PN = "4"  !CDS_PN = "4";
BODY = "Q_CAP","I41": #LOCATION = "PC115_6" !CDS_LOCATION = "PC115_6" &SEC = "1" #&CDS_SEC = "1";
"A":   PN = "1"  !CDS_PN = "1";
"B":   PN = "2"  !CDS_PN = "2";
BODY = "Q_CAP","I42": #LOCATION = "PC116_6" !CDS_LOCATION = "PC116_6" &SEC = "1" #&CDS_SEC = "1";
"A":   PN = "1"  !CDS_PN = "1";
"B":   PN = "2"  !CDS_PN = "2";
BODY = "Q_RES","I44": #LOCATION = "PR158" !CDS_LOCATION = "PR158" &SEC = "1" #&CDS_SEC = "1";
"A":   PN = "1"  !CDS_PN = "1";
"B":   PN = "2"  !CDS_PN = "2";
BODY = "Q_CAP","I45": #LOCATION = "PC118_6" !CDS_LOCATION = "PC118_6" &SEC = "1" #&CDS_SEC = "1";
"A":   PN = "1"  !CDS_PN = "1";
"B":   PN = "2"  !CDS_PN = "2";
BODY = "Q_CAP","I47": #LOCATION = "PC119_6" !CDS_LOCATION = "PC119_6" &SEC = "1" #&CDS_SEC = "1";
"A":   PN = "1"  !CDS_PN = "1";
"B":   PN = "2"  !CDS_PN = "2";
BODY = "Q_RES","I49": #LOCATION = "PR96" !CDS_LOCATION = "PR96" &SEC = "1" #&CDS_SEC = "1";
"A":   PN = "1"  !CDS_PN = "1";
"B":   PN = "2"  !CDS_PN = "2";
BODY = "Q_CAP","I51": #LOCATION = "PC120_6" !CDS_LOCATION = "PC120_6" &SEC = "1" #&CDS_SEC = "1";
"A":   PN = "1"  !CDS_PN = "1";
"B":   PN = "2"  !CDS_PN = "2";
BODY = "Q_CAP","I53": #LOCATION = "PC123_6" !CDS_LOCATION = "PC123_6" &SEC = "1" #&CDS_SEC = "1";
"A":   PN = "1"  !CDS_PN = "1";
"B":   PN = "2"  !CDS_PN = "2";
BODY = "Q_RES","I56": #LOCATION = "PR95" !CDS_LOCATION = "PR95" &SEC = "1" #&CDS_SEC = "1";
"A":   PN = "1"  !CDS_PN = "1";
"B":   PN = "2"  !CDS_PN = "2";
BODY = "Q_CAP","I57": #LOCATION = "PC157" !CDS_LOCATION = "PC157" &SEC = "1" #&CDS_SEC = "1";
"A":   PN = "1"  !CDS_PN = "1";
"B":   PN = "2"  !CDS_PN = "2";
BODY = "Q_CAP","I58": #LOCATION = "PC134_5" !CDS_LOCATION = "PC134_5" &SEC = "1" #&CDS_SEC = "1";
"A":   PN = "1"  !CDS_PN = "1";
"B":   PN = "2"  !CDS_PN = "2";
BODY = "Q_CAP","I62": #LOCATION = "PC137" !CDS_LOCATION = "PC137" &SEC = "1" #&CDS_SEC = "1";
"A":   PN = "1"  !CDS_PN = "1";
"B":   PN = "2"  !CDS_PN = "2";
BODY = "Q_INDUCTOR4P_14","I63": #LOCATION = "PL15" !CDS_LOCATION = "PL15" &SEC = "1" #&CDS_SEC = "1";
"1":   PN = "1"  !CDS_PN = "1";
"2":   PN = "2"  !CDS_PN = "2";
"3":   PN = "3"  !CDS_PN = "3";
"4":   PN = "4"  !CDS_PN = "4";
BODY = "Q_CAP","I65": #LOCATION = "PC138_5" !CDS_LOCATION = "PC138_5" &SEC = "1" #&CDS_SEC = "1";
"A":   PN = "1"  !CDS_PN = "1";
"B":   PN = "2"  !CDS_PN = "2";
BODY = "Q_CAP","I66": #LOCATION = "PC139_5" !CDS_LOCATION = "PC139_5" &SEC = "1" #&CDS_SEC = "1";
"A":   PN = "1"  !CDS_PN = "1";
"B":   PN = "2"  !CDS_PN = "2";
BODY = "Q_CAP","I69": #LOCATION = "PC140_5" !CDS_LOCATION = "PC140_5" &SEC = "1" #&CDS_SEC = "1";
"A":   PN = "1"  !CDS_PN = "1";
"B":   PN = "2"  !CDS_PN = "2";
BODY = "Q_CAP","I70": #LOCATION = "PC141_5" !CDS_LOCATION = "PC141_5" &SEC = "1" #&CDS_SEC = "1";
"A":   PN = "1"  !CDS_PN = "1";
"B":   PN = "2"  !CDS_PN = "2";
BODY = "Q_CAP","I72": #LOCATION = "PC154" !CDS_LOCATION = "PC154" &SEC = "1" #&CDS_SEC = "1";
"A":   PN = "1"  !CDS_PN = "1";
"B":   PN = "2"  !CDS_PN = "2";
BODY = "ISL99390FRZTR5935","I73": #LOCATION = "PU11" !CDS_LOCATION = "PU11" &SEC = "1" #&CDS_SEC = "1";
"AGND":   PN = "2"  !CDS_PN = "2";
"BOOT":   PN = "33"  !CDS_PN = "33";
"DNC":   PN = "31"  !CDS_PN = "31";
"EN":   PN = "35"  !CDS_PN = "35";
"GL1":   PN = "6"  !CDS_PN = "6";
"GL2":   PN = "41"  !CDS_PN = "41";
"IOUT":   PN = "38"  !CDS_PN = "38";
"LSET":   PN = "37"  !CDS_PN = "37";
"PGND1":   PN = "5"  !CDS_PN = "5";
"PGND2":   PN = "7_9-20_24"  !CDS_PN = "7_9-20_24";
"PGND3":   PN = "40"  !CDS_PN = "40";
"PHASE":   PN = "32"  !CDS_PN = "32";
"PVCC":   PN = "4"  !CDS_PN = "4";
"PWM":   PN = "34"  !CDS_PN = "34";
"REFIN":   PN = "39"  !CDS_PN = "39";
"SW":   PN = "10_19"  !CDS_PN = "10_19";
"TOUT_FLT":   PN = "36"  !CDS_PN = "36";
"VCC":   PN = "3"  !CDS_PN = "3";
"VIN1":   PN = "25_29"  !CDS_PN = "25_29";
"VIN2":   PN = "30"  !CDS_PN = "30";
"VOS":   PN = "1"  !CDS_PN = "1";
DRAWING = "@t6g_mb_lib.t6g(sch_1):page181";
BODY = "Q_RES","I28": #LOCATION = "PR108" !CDS_LOCATION = "PR108" &SEC = "1" #&CDS_SEC = "1";
"A":   PN = "1"  !CDS_PN = "1";
"B":   PN = "2"  !CDS_PN = "2";
BODY = "Q_CAP","I44": #LOCATION = "PC183" !CDS_LOCATION = "PC183" &SEC = "1" #&CDS_SEC = "1";
"A":   PN = "1"  !CDS_PN = "1";
"B":   PN = "2"  !CDS_PN = "2";
BODY = "Q_CAP","I46": #LOCATION = "PC182_4" !CDS_LOCATION = "PC182_4" &SEC = "1" #&CDS_SEC = "1";
"A":   PN = "1"  !CDS_PN = "1";
"B":   PN = "2"  !CDS_PN = "2";
BODY = "Q_RES","I55": #LOCATION = "PR379" !CDS_LOCATION = "PR379" &SEC = "1" #&CDS_SEC = "1";
"A":   PN = "1"  !CDS_PN = "1";
"B":   PN = "2"  !CDS_PN = "2";
BODY = "Q_CAP","I59": #LOCATION = "PC186" !CDS_LOCATION = "PC186" &SEC = "1" #&CDS_SEC = "1";
"A":   PN = "1"  !CDS_PN = "1";
"B":   PN = "2"  !CDS_PN = "2";
BODY = "Q_CAP","I68": #LOCATION = "PC191_4" !CDS_LOCATION = "PC191_4" &SEC = "1" #&CDS_SEC = "1";
"A":   PN = "1"  !CDS_PN = "1";
"B":   PN = "2"  !CDS_PN = "2";
BODY = "Q_CAP","I71": #LOCATION = "PC192_3" !CDS_LOCATION = "PC192_3" &SEC = "1" #&CDS_SEC = "1";
"A":   PN = "1"  !CDS_PN = "1";
"B":   PN = "2"  !CDS_PN = "2";
BODY = "Q_CAP","I1": #LOCATION = "PC176_10" !CDS_LOCATION = "PC176_10" &SEC = "1" #&CDS_SEC = "1";
"A":   PN = "1"  !CDS_PN = "1";
"B":   PN = "2"  !CDS_PN = "2";
BODY = "Q_RES","I4": #LOCATION = "PR105" !CDS_LOCATION = "PR105" &SEC = "1" #&CDS_SEC = "1";
"A":   PN = "1"  !CDS_PN = "1";
"B":   PN = "2"  !CDS_PN = "2";
BODY = "Q_CAP","I10": #LOCATION = "PC171" !CDS_LOCATION = "PC171" &SEC = "1" #&CDS_SEC = "1";
"A":   PN = "1"  !CDS_PN = "1";
"B":   PN = "2"  !CDS_PN = "2";
BODY = "Q_RES","I12": #LOCATION = "PR107" !CDS_LOCATION = "PR107" &SEC = "1" #&CDS_SEC = "1";
"A":   PN = "1"  !CDS_PN = "1";
"B":   PN = "2"  !CDS_PN = "2";
BODY = "Q_CAP","I13": #LOCATION = "PC173_IOP0_4" !CDS_LOCATION = "PC173_IOP0_4" &SEC = "1" #&CDS_SEC = "1";
"A":   PN = "1"  !CDS_PN = "1";
"B":   PN = "2"  !CDS_PN = "2";
BODY = "Q_RES","I16": #LOCATION = "PR109" !CDS_LOCATION = "PR109" &SEC = "1" #&CDS_SEC = "1";
"A":   PN = "1"  !CDS_PN = "1";
"B":   PN = "2"  !CDS_PN = "2";
BODY = "Q_CAP","I17": #LOCATION = "PC178_4" !CDS_LOCATION = "PC178_4" &SEC = "1" #&CDS_SEC = "1";
"A":   PN = "1"  !CDS_PN = "1";
"B":   PN = "2"  !CDS_PN = "2";
BODY = "Q_CAP","I19": #LOCATION = "PC175_9" !CDS_LOCATION = "PC175_9" &SEC = "1" #&CDS_SEC = "1";
"A":   PN = "1"  !CDS_PN = "1";
"B":   PN = "2"  !CDS_PN = "2";
BODY = "Q_RES","I21": #LOCATION = "PR106" !CDS_LOCATION = "PR106" &SEC = "1" #&CDS_SEC = "1";
"A":   PN = "1"  !CDS_PN = "1";
"B":   PN = "2"  !CDS_PN = "2";
BODY = "Q_CAP","I27": #LOCATION = "PC172" !CDS_LOCATION = "PC172" &SEC = "1" #&CDS_SEC = "1";
"A":   PN = "1"  !CDS_PN = "1";
"B":   PN = "2"  !CDS_PN = "2";
BODY = "Q_CAP","I30": #LOCATION = "PC174_IOP0_3" !CDS_LOCATION = "PC174_IOP0_3" &SEC = "1" #&CDS_SEC = "1";
"A":   PN = "1"  !CDS_PN = "1";
"B":   PN = "2"  !CDS_PN = "2";
BODY = "ISL99390FRZTR5935","I32": #LOCATION = "PU19" !CDS_LOCATION = "PU19" &SEC = "1" #&CDS_SEC = "1";
"AGND":   PN = "2"  !CDS_PN = "2";
"BOOT":   PN = "33"  !CDS_PN = "33";
"DNC":   PN = "31"  !CDS_PN = "31";
"EN":   PN = "35"  !CDS_PN = "35";
"GL1":   PN = "6"  !CDS_PN = "6";
"GL2":   PN = "41"  !CDS_PN = "41";
"IOUT":   PN = "38"  !CDS_PN = "38";
"LSET":   PN = "37"  !CDS_PN = "37";
"PGND1":   PN = "5"  !CDS_PN = "5";
"PGND2":   PN = "7_9-20_24"  !CDS_PN = "7_9-20_24";
"PGND3":   PN = "40"  !CDS_PN = "40";
"PHASE":   PN = "32"  !CDS_PN = "32";
"PVCC":   PN = "4"  !CDS_PN = "4";
"PWM":   PN = "34"  !CDS_PN = "34";
"REFIN":   PN = "39"  !CDS_PN = "39";
"SW":   PN = "10_19"  !CDS_PN = "10_19";
"TOUT_FLT":   PN = "36"  !CDS_PN = "36";
"VCC":   PN = "3"  !CDS_PN = "3";
"VIN1":   PN = "25_29"  !CDS_PN = "25_29";
"VIN2":   PN = "30"  !CDS_PN = "30";
"VOS":   PN = "1"  !CDS_PN = "1";
BODY = "Q_RES","I34": #LOCATION = "PR110" !CDS_LOCATION = "PR110" &SEC = "1" #&CDS_SEC = "1";
"A":   PN = "1"  !CDS_PN = "1";
"B":   PN = "2"  !CDS_PN = "2";
BODY = "Q_CAP","I35": #LOCATION = "PC177_3" !CDS_LOCATION = "PC177_3" &SEC = "1" #&CDS_SEC = "1";
"A":   PN = "1"  !CDS_PN = "1";
"B":   PN = "2"  !CDS_PN = "2";
BODY = "Q_CAP","I36": #LOCATION = "PC179_3" !CDS_LOCATION = "PC179_3" &SEC = "1" #&CDS_SEC = "1";
"A":   PN = "1"  !CDS_PN = "1";
"B":   PN = "2"  !CDS_PN = "2";
BODY = "Q_RES","I38": #LOCATION = "PR291" !CDS_LOCATION = "PR291" &SEC = "1" #&CDS_SEC = "1";
"A":   PN = "1"  !CDS_PN = "1";
"B":   PN = "2"  !CDS_PN = "2";
BODY = "Q_CAP","I39": #LOCATION = "PC163" !CDS_LOCATION = "PC163" &SEC = "1" #&CDS_SEC = "1";
"A":   PN = "1"  !CDS_PN = "1";
"B":   PN = "2"  !CDS_PN = "2";
BODY = "Q_RES","I41": #LOCATION = "PR112" !CDS_LOCATION = "PR112" &SEC = "1" #&CDS_SEC = "1";
"A":   PN = "1"  !CDS_PN = "1";
"B":   PN = "2"  !CDS_PN = "2";
BODY = "Q_INDUCTOR4P_14","I42": #LOCATION = "PL20" !CDS_LOCATION = "PL20" &SEC = "1" #&CDS_SEC = "1";
"1":   PN = "1"  !CDS_PN = "1";
"2":   PN = "2"  !CDS_PN = "2";
"3":   PN = "3"  !CDS_PN = "3";
"4":   PN = "4"  !CDS_PN = "4";
BODY = "Q_INDUCTOR","I43": #LOCATION = "PL16" !CDS_LOCATION = "PL16" &SEC = "1" #&CDS_SEC = "1";
"1":   PN = "1"  !CDS_PN = "1";
"2":   PN = "2"  !CDS_PN = "2";
BODY = "Q_CAP","I45": #LOCATION = "PC180_4" !CDS_LOCATION = "PC180_4" &SEC = "1" #&CDS_SEC = "1";
"A":   PN = "1"  !CDS_PN = "1";
"B":   PN = "2"  !CDS_PN = "2";
BODY = "Q_CAP","I47": #LOCATION = "PC185_4" !CDS_LOCATION = "PC185_4" &SEC = "1" #&CDS_SEC = "1";
"A":   PN = "1"  !CDS_PN = "1";
"B":   PN = "2"  !CDS_PN = "2";
BODY = "Q_CAP","I49": #LOCATION = "PC188_4" !CDS_LOCATION = "PC188_4" &SEC = "1" #&CDS_SEC = "1";
"A":   PN = "1"  !CDS_PN = "1";
"B":   PN = "2"  !CDS_PN = "2";
BODY = "Q_RES","I50": #LOCATION = "PR111" !CDS_LOCATION = "PR111" &SEC = "1" #&CDS_SEC = "1";
"A":   PN = "1"  !CDS_PN = "1";
"B":   PN = "2"  !CDS_PN = "2";
BODY = "Q_CAP","I53": #LOCATION = "PC189_4" !CDS_LOCATION = "PC189_4" &SEC = "1" #&CDS_SEC = "1";
"A":   PN = "1"  !CDS_PN = "1";
"B":   PN = "2"  !CDS_PN = "2";
BODY = "Q_CAP","I56": #LOCATION = "PC166" !CDS_LOCATION = "PC166" &SEC = "1" #&CDS_SEC = "1";
"A":   PN = "1"  !CDS_PN = "1";
"B":   PN = "2"  !CDS_PN = "2";
BODY = "Q_CAP","I58": #LOCATION = "PC181_3" !CDS_LOCATION = "PC181_3" &SEC = "1" #&CDS_SEC = "1";
"A":   PN = "1"  !CDS_PN = "1";
"B":   PN = "2"  !CDS_PN = "2";
BODY = "Q_CAP","I60": #LOCATION = "PC184_3" !CDS_LOCATION = "PC184_3" &SEC = "1" #&CDS_SEC = "1";
"A":   PN = "1"  !CDS_PN = "1";
"B":   PN = "2"  !CDS_PN = "2";
BODY = "Q_INDUCTOR4P_14","I61": #LOCATION = "PL21" !CDS_LOCATION = "PL21" &SEC = "1" #&CDS_SEC = "1";
"1":   PN = "1"  !CDS_PN = "1";
"2":   PN = "2"  !CDS_PN = "2";
"3":   PN = "3"  !CDS_PN = "3";
"4":   PN = "4"  !CDS_PN = "4";
BODY = "Q_CAP","I63": #LOCATION = "PC187_3" !CDS_LOCATION = "PC187_3" &SEC = "1" #&CDS_SEC = "1";
"A":   PN = "1"  !CDS_PN = "1";
"B":   PN = "2"  !CDS_PN = "2";
BODY = "Q_CAP","I66": #LOCATION = "PC190_3" !CDS_LOCATION = "PC190_3" &SEC = "1" #&CDS_SEC = "1";
"A":   PN = "1"  !CDS_PN = "1";
"B":   PN = "2"  !CDS_PN = "2";
BODY = "ISL99390FRZTR5935","I73": #LOCATION = "PU20" !CDS_LOCATION = "PU20" &SEC = "1" #&CDS_SEC = "1";
"AGND":   PN = "2"  !CDS_PN = "2";
"BOOT":   PN = "33"  !CDS_PN = "33";
"DNC":   PN = "31"  !CDS_PN = "31";
"EN":   PN = "35"  !CDS_PN = "35";
"GL1":   PN = "6"  !CDS_PN = "6";
"GL2":   PN = "41"  !CDS_PN = "41";
"IOUT":   PN = "38"  !CDS_PN = "38";
"LSET":   PN = "37"  !CDS_PN = "37";
"PGND1":   PN = "5"  !CDS_PN = "5";
"PGND2":   PN = "7_9-20_24"  !CDS_PN = "7_9-20_24";
"PGND3":   PN = "40"  !CDS_PN = "40";
"PHASE":   PN = "32"  !CDS_PN = "32";
"PVCC":   PN = "4"  !CDS_PN = "4";
"PWM":   PN = "34"  !CDS_PN = "34";
"REFIN":   PN = "39"  !CDS_PN = "39";
"SW":   PN = "10_19"  !CDS_PN = "10_19";
"TOUT_FLT":   PN = "36"  !CDS_PN = "36";
"VCC":   PN = "3"  !CDS_PN = "3";
"VIN1":   PN = "25_29"  !CDS_PN = "25_29";
"VIN2":   PN = "30"  !CDS_PN = "30";
"VOS":   PN = "1"  !CDS_PN = "1";
DRAWING = "@t6g_mb_lib.t6g(sch_1):page182";
BODY = "Q_RES","I13": #LOCATION = "R8116" !CDS_LOCATION = "R8116" &SEC = "1" #&CDS_SEC = "1";
"A":   PN = "1"  !CDS_PN = "1";
"B":   PN = "2"  !CDS_PN = "2";
BODY = "Q_CAP","I47": #LOCATION = "C196" !CDS_LOCATION = "C196" &SEC = "1" #&CDS_SEC = "1";
"A":   PN = "1"  !CDS_PN = "1";
"B":   PN = "2"  !CDS_PN = "2";
BODY = "Q_RES","I67": #LOCATION = "PR129" !CDS_LOCATION = "PR129" &SEC = "1" #&CDS_SEC = "1";
"A":   PN = "1"  !CDS_PN = "1";
"B":   PN = "2"  !CDS_PN = "2";
BODY = "Q_RES","I68": #LOCATION = "PR128" !CDS_LOCATION = "PR128" &SEC = "1" #&CDS_SEC = "1";
"A":   PN = "1"  !CDS_PN = "1";
"B":   PN = "2"  !CDS_PN = "2";
BODY = "Q_CAP","I77": #LOCATION = "PC9" !CDS_LOCATION = "PC9" &SEC = "1" #&CDS_SEC = "1";
"A":   PN = "1"  !CDS_PN = "1";
"B":   PN = "2"  !CDS_PN = "2";
BODY = "Q_CAP","I82": #LOCATION = "PC200" !CDS_LOCATION = "PC200" &SEC = "1" #&CDS_SEC = "1";
"A":   PN = "1"  !CDS_PN = "1";
"B":   PN = "2"  !CDS_PN = "2";
BODY = "Q_RES","I2": #LOCATION = "PR113" !CDS_LOCATION = "PR113" &SEC = "1" #&CDS_SEC = "1";
"A":   PN = "1"  !CDS_PN = "1";
"B":   PN = "2"  !CDS_PN = "2";
BODY = "Q_CAP","I4": #LOCATION = "PC193" !CDS_LOCATION = "PC193" &SEC = "1" #&CDS_SEC = "1";
"A":   PN = "1"  !CDS_PN = "1";
"B":   PN = "2"  !CDS_PN = "2";
BODY = "Q_RES","I6": #LOCATION = "PR3" !CDS_LOCATION = "PR3" #SEC = "1" !CDS_SEC = "1";
"A":   PN = "1"  !CDS_PN = "1";
"B":   PN = "2"  !CDS_PN = "2";
BODY = "Q_RES","I9": #LOCATION = "R8458" !CDS_LOCATION = "R8458" &SEC = "1" #&CDS_SEC = "1";
"A":   PN = "1"  !CDS_PN = "1";
"B":   PN = "2"  !CDS_PN = "2";
BODY = "Q_RES","I15": #LOCATION = "PR115" !CDS_LOCATION = "PR115" &SEC = "1" #&CDS_SEC = "1";
"A":   PN = "1"  !CDS_PN = "1";
"B":   PN = "2"  !CDS_PN = "2";
BODY = "Q_RES","I16": #LOCATION = "PR125" !CDS_LOCATION = "PR125" &SEC = "1" #&CDS_SEC = "1";
"A":   PN = "1"  !CDS_PN = "1";
"B":   PN = "2"  !CDS_PN = "2";
BODY = "Q_RES","I18": #LOCATION = "PR601" !CDS_LOCATION = "PR601" &SEC = "1" #&CDS_SEC = "1";
"A":   PN = "1"  !CDS_PN = "1";
"B":   PN = "2"  !CDS_PN = "2";
BODY = "Q_CAP","I20": #LOCATION = "PC5" !CDS_LOCATION = "PC5" #SEC = "1" !CDS_SEC = "1";
"A":   PN = "1"  !CDS_PN = "1";
"B":   PN = "2"  !CDS_PN = "2";
BODY = "Q_RES","I22": #LOCATION = "PR126" !CDS_LOCATION = "PR126" &SEC = "1" #&CDS_SEC = "1";
"A":   PN = "1"  !CDS_PN = "1";
"B":   PN = "2"  !CDS_PN = "2";
BODY = "RAA229621GNPHA0","I24": #LOCATION = "PU21" !CDS_LOCATION = "PU21" &SEC = "1" #&CDS_SEC = "1";
"CS0":   PN = "30"  !CDS_PN = "30";
"CS1":   PN = "29"  !CDS_PN = "29";
"CS2":   PN = "28"  !CDS_PN = "28";
"CS3":   PN = "27"  !CDS_PN = "27";
"CS4":   PN = "26"  !CDS_PN = "26";
"CS5":   PN = "25"  !CDS_PN = "25";
"CS6":   PN = "24"  !CDS_PN = "24";
"CS7":   PN = "23"  !CDS_PN = "23";
"EN0":   PN = "13"  !CDS_PN = "13";
"EN1||ADDR_CFG":   PN = "34"  !CDS_PN = "34";
"NPMALERT":   PN = "11"  !CDS_PN = "11";
"OCP_L":   PN = "33"  !CDS_PN = "33";
"PG0":   PN = "12"  !CDS_PN = "12";
"PG1":   PN = "16"  !CDS_PN = "16";
"PMSCL":   PN = "10"  !CDS_PN = "10";
"PMSDA":   PN = "9"  !CDS_PN = "9";
"PWM0":   PN = "1"  !CDS_PN = "1";
"PWM1":   PN = "2"  !CDS_PN = "2";
"PWM2":   PN = "3"  !CDS_PN = "3";
"PWM3":   PN = "4"  !CDS_PN = "4";
"PWM4":   PN = "5"  !CDS_PN = "5";
"PWM5":   PN = "6"  !CDS_PN = "6";
"PWM6":   PN = "7"  !CDS_PN = "7";
"PWM7":   PN = "8"  !CDS_PN = "8";
"RESET_L":   PN = "14"  !CDS_PN = "14";
"RGND0":   PN = "22"  !CDS_PN = "22";
"RGND1":   PN = "31"  !CDS_PN = "31";
"SVC":   PN = "18"  !CDS_PN = "18";
"SVD":   PN = "17"  !CDS_PN = "17";
"SVTI":   PN = "20"  !CDS_PN = "20";
"SVTO":   PN = "19"  !CDS_PN = "19";
"TEMP0":   PN = "36"  !CDS_PN = "36";
"TEMP1":   PN = "35"  !CDS_PN = "35";
"TH_GND":   PN = "TH"  !CDS_PN = "TH";
"VCC":   PN = "39"  !CDS_PN = "39";
"VCCS":   PN = "40"  !CDS_PN = "40";
"VDDIO":   PN = "15"  !CDS_PN = "15";
"VINSEN":   PN = "38"  !CDS_PN = "38";
"VMON||IINSEN":   PN = "37"  !CDS_PN = "37";
"VSEN0":   PN = "21"  !CDS_PN = "21";
"VSEN1":   PN = "32"  !CDS_PN = "32";
BODY = "Q_RES","I25": #LOCATION = "R124" !CDS_LOCATION = "R124" &SEC = "1" #&CDS_SEC = "1";
"A":   PN = "1"  !CDS_PN = "1";
"B":   PN = "2"  !CDS_PN = "2";
BODY = "Q_RES","I28": #LOCATION = "PR121" !CDS_LOCATION = "PR121" &SEC = "1" #&CDS_SEC = "1";
"A":   PN = "1"  !CDS_PN = "1";
"B":   PN = "2"  !CDS_PN = "2";
BODY = "Q_CAP","I29": #LOCATION = "PC194" !CDS_LOCATION = "PC194" &SEC = "1" #&CDS_SEC = "1";
"A":   PN = "1"  !CDS_PN = "1";
"B":   PN = "2"  !CDS_PN = "2";
BODY = "Q_RES","I30": #LOCATION = "PR114" !CDS_LOCATION = "PR114" &SEC = "1" #&CDS_SEC = "1";
"A":   PN = "1"  !CDS_PN = "1";
"B":   PN = "2"  !CDS_PN = "2";
BODY = "Q_RES","I38": #LOCATION = "R117" !CDS_LOCATION = "R117" &SEC = "1" #&CDS_SEC = "1";
"A":   PN = "1"  !CDS_PN = "1";
"B":   PN = "2"  !CDS_PN = "2";
BODY = "Q_RES","I39": #LOCATION = "R120" !CDS_LOCATION = "R120" &SEC = "1" #&CDS_SEC = "1";
"A":   PN = "1"  !CDS_PN = "1";
"B":   PN = "2"  !CDS_PN = "2";
BODY = "Q_RES","I40": #LOCATION = "R119" !CDS_LOCATION = "R119" &SEC = "1" #&CDS_SEC = "1";
"A":   PN = "1"  !CDS_PN = "1";
"B":   PN = "2"  !CDS_PN = "2";
BODY = "Q_RES","I41": #LOCATION = "R118" !CDS_LOCATION = "R118" &SEC = "1" #&CDS_SEC = "1";
"A":   PN = "1"  !CDS_PN = "1";
"B":   PN = "2"  !CDS_PN = "2";
BODY = "Q_RES","I43": #LOCATION = "R123" !CDS_LOCATION = "R123" &SEC = "1" #&CDS_SEC = "1";
"A":   PN = "1"  !CDS_PN = "1";
"B":   PN = "2"  !CDS_PN = "2";
BODY = "Q_RES","I44": #LOCATION = "R122" !CDS_LOCATION = "R122" &SEC = "1" #&CDS_SEC = "1";
"A":   PN = "1"  !CDS_PN = "1";
"B":   PN = "2"  !CDS_PN = "2";
BODY = "Q_CAP","I45": #LOCATION = "C197" !CDS_LOCATION = "C197" &SEC = "1" #&CDS_SEC = "1";
"A":   PN = "1"  !CDS_PN = "1";
"B":   PN = "2"  !CDS_PN = "2";
BODY = "Q_CAP","I50": #LOCATION = "PC198" !CDS_LOCATION = "PC198" &SEC = "1" #&CDS_SEC = "1";
"A":   PN = "1"  !CDS_PN = "1";
"B":   PN = "2"  !CDS_PN = "2";
BODY = "Q_RES","I52": #LOCATION = "PR412" !CDS_LOCATION = "PR412" &SEC = "1" #&CDS_SEC = "1";
"A":   PN = "1"  !CDS_PN = "1";
"B":   PN = "2"  !CDS_PN = "2";
BODY = "Q_RES","I53": #LOCATION = "PR36" !CDS_LOCATION = "PR36" &SEC = "1" #&CDS_SEC = "1";
"A":   PN = "1"  !CDS_PN = "1";
"B":   PN = "2"  !CDS_PN = "2";
BODY = "Q_RES","I57": #LOCATION = "PR127" !CDS_LOCATION = "PR127" &SEC = "1" #&CDS_SEC = "1";
"A":   PN = "1"  !CDS_PN = "1";
"B":   PN = "2"  !CDS_PN = "2";
BODY = "Q_RES","I58": #LOCATION = "PR419" !CDS_LOCATION = "PR419" &SEC = "1" #&CDS_SEC = "1";
"A":   PN = "1"  !CDS_PN = "1";
"B":   PN = "2"  !CDS_PN = "2";
BODY = "Q_RES","I59": #LOCATION = "PR35" !CDS_LOCATION = "PR35" &SEC = "1" #&CDS_SEC = "1";
"A":   PN = "1"  !CDS_PN = "1";
"B":   PN = "2"  !CDS_PN = "2";
BODY = "Q_RES","I60": #LOCATION = "PR34" !CDS_LOCATION = "PR34" &SEC = "1" #&CDS_SEC = "1";
"A":   PN = "1"  !CDS_PN = "1";
"B":   PN = "2"  !CDS_PN = "2";
BODY = "Q_RES","I61": #LOCATION = "PR33" !CDS_LOCATION = "PR33" &SEC = "1" #&CDS_SEC = "1";
"A":   PN = "1"  !CDS_PN = "1";
"B":   PN = "2"  !CDS_PN = "2";
BODY = "Q_RES","I71": #LOCATION = "PR37" !CDS_LOCATION = "PR37" &SEC = "1" #&CDS_SEC = "1";
"A":   PN = "1"  !CDS_PN = "1";
"B":   PN = "2"  !CDS_PN = "2";
BODY = "Q_CAP","I79": #LOCATION = "PC4" !CDS_LOCATION = "PC4" &SEC = "1" #&CDS_SEC = "1";
"A":   PN = "1"  !CDS_PN = "1";
"B":   PN = "2"  !CDS_PN = "2";
BODY = "Q_CAP","I80": #LOCATION = "PC199" !CDS_LOCATION = "PC199" &SEC = "1" #&CDS_SEC = "1";
"A":   PN = "1"  !CDS_PN = "1";
"B":   PN = "2"  !CDS_PN = "2";
BODY = "Q_RES","I85": #LOCATION = "PR130" !CDS_LOCATION = "PR130" &SEC = "1" #&CDS_SEC = "1";
"A":   PN = "1"  !CDS_PN = "1";
"B":   PN = "2"  !CDS_PN = "2";
BODY = "Q_CAP","I88": #LOCATION = "C5009" !CDS_LOCATION = "C5009" &SEC = "1" #&CDS_SEC = "1";
"A":   PN = "1"  !CDS_PN = "1";
"B":   PN = "2"  !CDS_PN = "2";
DRAWING = "@t6g_mb_lib.t6g(sch_1):page183";
BODY = "Q_RES","I24": #LOCATION = "PR389" !CDS_LOCATION = "PR389" &SEC = "1" #&CDS_SEC = "1";
"A":   PN = "1"  !CDS_PN = "1";
"B":   PN = "2"  !CDS_PN = "2";
BODY = "Q_RES","I25": #LOCATION = "PR136" !CDS_LOCATION = "PR136" &SEC = "1" #&CDS_SEC = "1";
"A":   PN = "1"  !CDS_PN = "1";
"B":   PN = "2"  !CDS_PN = "2";
BODY = "Q_CAP","I26": #LOCATION = "PC168" !CDS_LOCATION = "PC168" &SEC = "1" #&CDS_SEC = "1";
"A":   PN = "1"  !CDS_PN = "1";
"B":   PN = "2"  !CDS_PN = "2";
BODY = "Q_CAP","I27": #LOCATION = "PC210_2" !CDS_LOCATION = "PC210_2" &SEC = "1" #&CDS_SEC = "1";
"A":   PN = "1"  !CDS_PN = "1";
"B":   PN = "2"  !CDS_PN = "2";
BODY = "Q_CAP","I29": #LOCATION = "PC208_2" !CDS_LOCATION = "PC208_2" &SEC = "1" #&CDS_SEC = "1";
"A":   PN = "1"  !CDS_PN = "1";
"B":   PN = "2"  !CDS_PN = "2";
BODY = "Q_CAP","I34": #LOCATION = "PC201_1" !CDS_LOCATION = "PC201_1" &SEC = "1" #&CDS_SEC = "1";
"A":   PN = "1"  !CDS_PN = "1";
"B":   PN = "2"  !CDS_PN = "2";
BODY = "Q_RES","I37": #LOCATION = "PR133" !CDS_LOCATION = "PR133" &SEC = "1" #&CDS_SEC = "1";
"A":   PN = "1"  !CDS_PN = "1";
"B":   PN = "2"  !CDS_PN = "2";
BODY = "Q_CAP","I44": #LOCATION = "PC209_1" !CDS_LOCATION = "PC209_1" &SEC = "1" #&CDS_SEC = "1";
"A":   PN = "1"  !CDS_PN = "1";
"B":   PN = "2"  !CDS_PN = "2";
BODY = "Q_CAP","I48": #LOCATION = "PC211_1" !CDS_LOCATION = "PC211_1" &SEC = "1" #&CDS_SEC = "1";
"A":   PN = "1"  !CDS_PN = "1";
"B":   PN = "2"  !CDS_PN = "2";
BODY = "Q_INDUCTOR","I52": #LOCATION = "PL22" !CDS_LOCATION = "PL22" &SEC = "1" #&CDS_SEC = "1";
"1":   PN = "1"  !CDS_PN = "1";
"2":   PN = "2"  !CDS_PN = "2";
BODY = "Q_CAPP","I66": #LOCATION = "PC229" !CDS_LOCATION = "PC229" &SEC = "1" #&CDS_SEC = "1";
"A":   PN = "1"  !CDS_PN = "1";
"B":   PN = "2"  !CDS_PN = "2";
BODY = "Q_CAPP","I67": #LOCATION = "PC230" !CDS_LOCATION = "PC230" &SEC = "1" #&CDS_SEC = "1";
"A":   PN = "1"  !CDS_PN = "1";
"B":   PN = "2"  !CDS_PN = "2";
BODY = "Q_CAPP","I70": #LOCATION = "PC801" !CDS_LOCATION = "PC801" &SEC = "1" #&CDS_SEC = "1";
"A":   PN = "1"  !CDS_PN = "1";
"B":   PN = "2"  !CDS_PN = "2";
BODY = "Q_CAP","I79": #LOCATION = "PC6003" !CDS_LOCATION = "PC6003" &SEC = "1" #&CDS_SEC = "1";
"A":   PN = "1"  !CDS_PN = "1";
"B":   PN = "2"  !CDS_PN = "2";
BODY = "Q_CAP","I81": #LOCATION = "PC224_1" !CDS_LOCATION = "PC224_1" &SEC = "1" #&CDS_SEC = "1";
"A":   PN = "1"  !CDS_PN = "1";
"B":   PN = "2"  !CDS_PN = "2";
BODY = "Q_CAP","I7": #LOCATION = "PC202_2" !CDS_LOCATION = "PC202_2" &SEC = "1" #&CDS_SEC = "1";
"A":   PN = "1"  !CDS_PN = "1";
"B":   PN = "2"  !CDS_PN = "2";
BODY = "Q_CAP","I9": #LOCATION = "PC204" !CDS_LOCATION = "PC204" &SEC = "1" #&CDS_SEC = "1";
"A":   PN = "1"  !CDS_PN = "1";
"B":   PN = "2"  !CDS_PN = "2";
BODY = "Q_RES","I11": #LOCATION = "PR134" !CDS_LOCATION = "PR134" &SEC = "1" #&CDS_SEC = "1";
"A":   PN = "1"  !CDS_PN = "1";
"B":   PN = "2"  !CDS_PN = "2";
BODY = "ISL99390FRZTR5935","I13": #LOCATION = "PU23" !CDS_LOCATION = "PU23" &SEC = "1" #&CDS_SEC = "1";
"AGND":   PN = "2"  !CDS_PN = "2";
"BOOT":   PN = "33"  !CDS_PN = "33";
"DNC":   PN = "31"  !CDS_PN = "31";
"EN":   PN = "35"  !CDS_PN = "35";
"GL1":   PN = "6"  !CDS_PN = "6";
"GL2":   PN = "41"  !CDS_PN = "41";
"IOUT":   PN = "38"  !CDS_PN = "38";
"LSET":   PN = "37"  !CDS_PN = "37";
"PGND1":   PN = "5"  !CDS_PN = "5";
"PGND2":   PN = "7_9-20_24"  !CDS_PN = "7_9-20_24";
"PGND3":   PN = "40"  !CDS_PN = "40";
"PHASE":   PN = "32"  !CDS_PN = "32";
"PVCC":   PN = "4"  !CDS_PN = "4";
"PWM":   PN = "34"  !CDS_PN = "34";
"REFIN":   PN = "39"  !CDS_PN = "39";
"SW":   PN = "10_19"  !CDS_PN = "10_19";
"TOUT_FLT":   PN = "36"  !CDS_PN = "36";
"VCC":   PN = "3"  !CDS_PN = "3";
"VIN1":   PN = "25_29"  !CDS_PN = "25_29";
"VIN2":   PN = "30"  !CDS_PN = "30";
"VOS":   PN = "1"  !CDS_PN = "1";
BODY = "Q_RES","I14": #LOCATION = "PR132" !CDS_LOCATION = "PR132" &SEC = "1" #&CDS_SEC = "1";
"A":   PN = "1"  !CDS_PN = "1";
"B":   PN = "2"  !CDS_PN = "2";
BODY = "Q_CAP","I17": #LOCATION = "PC206_11P0_2" !CDS_LOCATION = "PC206_11P0_2" &SEC = "1" #&CDS_SEC = "1";
"A":   PN = "1"  !CDS_PN = "1";
"B":   PN = "2"  !CDS_PN = "2";
BODY = "Q_CAP","I30": #LOCATION = "PC212_2" !CDS_LOCATION = "PC212_2" &SEC = "1" #&CDS_SEC = "1";
"A":   PN = "1"  !CDS_PN = "1";
"B":   PN = "2"  !CDS_PN = "2";
BODY = "Q_CAP","I31": #LOCATION = "PC214_2" !CDS_LOCATION = "PC214_2" &SEC = "1" #&CDS_SEC = "1";
"A":   PN = "1"  !CDS_PN = "1";
"B":   PN = "2"  !CDS_PN = "2";
BODY = "Q_RES","I33": #LOCATION = "PR482" !CDS_LOCATION = "PR482" &SEC = "1" #&CDS_SEC = "1";
"A":   PN = "1"  !CDS_PN = "1";
"B":   PN = "2"  !CDS_PN = "2";
BODY = "Q_CAP","I36": #LOCATION = "PC203" !CDS_LOCATION = "PC203" &SEC = "1" #&CDS_SEC = "1";
"A":   PN = "1"  !CDS_PN = "1";
"B":   PN = "2"  !CDS_PN = "2";
BODY = "Q_RES","I40": #LOCATION = "PR131" !CDS_LOCATION = "PR131" &SEC = "1" #&CDS_SEC = "1";
"A":   PN = "1"  !CDS_PN = "1";
"B":   PN = "2"  !CDS_PN = "2";
BODY = "Q_CAP","I42": #LOCATION = "PC205_11P0_1" !CDS_LOCATION = "PC205_11P0_1" &SEC = "1" #&CDS_SEC = "1";
"A":   PN = "1"  !CDS_PN = "1";
"B":   PN = "2"  !CDS_PN = "2";
BODY = "Q_CAP","I45": #LOCATION = "PC169" !CDS_LOCATION = "PC169" &SEC = "1" #&CDS_SEC = "1";
"A":   PN = "1"  !CDS_PN = "1";
"B":   PN = "2"  !CDS_PN = "2";
BODY = "Q_RES","I46": #LOCATION = "PR135" !CDS_LOCATION = "PR135" &SEC = "1" #&CDS_SEC = "1";
"A":   PN = "1"  !CDS_PN = "1";
"B":   PN = "2"  !CDS_PN = "2";
BODY = "Q_CAP","I47": #LOCATION = "PC207_1" !CDS_LOCATION = "PC207_1" &SEC = "1" #&CDS_SEC = "1";
"A":   PN = "1"  !CDS_PN = "1";
"B":   PN = "2"  !CDS_PN = "2";
BODY = "Q_CAP","I49": #LOCATION = "PC213_1" !CDS_LOCATION = "PC213_1" &SEC = "1" #&CDS_SEC = "1";
"A":   PN = "1"  !CDS_PN = "1";
"B":   PN = "2"  !CDS_PN = "2";
BODY = "Q_CAP","I50": #LOCATION = "PC216_2" !CDS_LOCATION = "PC216_2" &SEC = "1" #&CDS_SEC = "1";
"A":   PN = "1"  !CDS_PN = "1";
"B":   PN = "2"  !CDS_PN = "2";
BODY = "Q_CAP","I51": #LOCATION = "PC218" !CDS_LOCATION = "PC218" &SEC = "1" #&CDS_SEC = "1";
"A":   PN = "1"  !CDS_PN = "1";
"B":   PN = "2"  !CDS_PN = "2";
BODY = "Q_CAP","I54": #LOCATION = "PC218_2" !CDS_LOCATION = "PC218_2" &SEC = "1" #&CDS_SEC = "1";
"A":   PN = "1"  !CDS_PN = "1";
"B":   PN = "2"  !CDS_PN = "2";
BODY = "Q_RES","I56": #LOCATION = "PR137" !CDS_LOCATION = "PR137" &SEC = "1" #&CDS_SEC = "1";
"A":   PN = "1"  !CDS_PN = "1";
"B":   PN = "2"  !CDS_PN = "2";
BODY = "Q_CAPP","I58": #LOCATION = "PC223" !CDS_LOCATION = "PC223" &SEC = "1" #&CDS_SEC = "1";
"A":   PN = "1"  !CDS_PN = "1";
"B":   PN = "2"  !CDS_PN = "2";
BODY = "Q_CAPP","I59": #LOCATION = "PC226" !CDS_LOCATION = "PC226" &SEC = "1" #&CDS_SEC = "1";
"A":   PN = "1"  !CDS_PN = "1";
"B":   PN = "2"  !CDS_PN = "2";
BODY = "Q_CAP","I62": #LOCATION = "PC225_2" !CDS_LOCATION = "PC225_2" &SEC = "1" #&CDS_SEC = "1";
"A":   PN = "1"  !CDS_PN = "1";
"B":   PN = "2"  !CDS_PN = "2";
BODY = "Q_CAPP","I65": #LOCATION = "PC228" !CDS_LOCATION = "PC228" &SEC = "1" #&CDS_SEC = "1";
"A":   PN = "1"  !CDS_PN = "1";
"B":   PN = "2"  !CDS_PN = "2";
BODY = "Q_CAP","I71": #LOCATION = "PC217" !CDS_LOCATION = "PC217" &SEC = "1" #&CDS_SEC = "1";
"A":   PN = "1"  !CDS_PN = "1";
"B":   PN = "2"  !CDS_PN = "2";
BODY = "Q_INDUCTOR","I73": #LOCATION = "PL23" !CDS_LOCATION = "PL23" &SEC = "1" #&CDS_SEC = "1";
"1":   PN = "1"  !CDS_PN = "1";
"2":   PN = "2"  !CDS_PN = "2";
BODY = "Q_CAPP","I75": #LOCATION = "PC220" !CDS_LOCATION = "PC220" &SEC = "1" #&CDS_SEC = "1";
"A":   PN = "1"  !CDS_PN = "1";
"B":   PN = "2"  !CDS_PN = "2";
BODY = "Q_CAP","I76": #LOCATION = "PC222" !CDS_LOCATION = "PC222" &SEC = "1" #&CDS_SEC = "1";
"A":   PN = "1"  !CDS_PN = "1";
"B":   PN = "2"  !CDS_PN = "2";
BODY = "Q_INDUCTOR","I78": #LOCATION = "PL24" !CDS_LOCATION = "PL24" &SEC = "1" #&CDS_SEC = "1";
"1":   PN = "1"  !CDS_PN = "1";
"2":   PN = "2"  !CDS_PN = "2";
BODY = "Q_CAP","I82": #LOCATION = "PC227_1" !CDS_LOCATION = "PC227_1" &SEC = "1" #&CDS_SEC = "1";
"A":   PN = "1"  !CDS_PN = "1";
"B":   PN = "2"  !CDS_PN = "2";
BODY = "Q_RES","I83": #LOCATION = "PR414" !CDS_LOCATION = "PR414" &SEC = "1" #&CDS_SEC = "1";
"A":   PN = "1"  !CDS_PN = "1";
"B":   PN = "2"  !CDS_PN = "2";
BODY = "Q_RES","I85": #LOCATION = "PR411" !CDS_LOCATION = "PR411" &SEC = "1" #&CDS_SEC = "1";
"A":   PN = "1"  !CDS_PN = "1";
"B":   PN = "2"  !CDS_PN = "2";
BODY = "Q_RES","I86": #LOCATION = "PR413" !CDS_LOCATION = "PR413" &SEC = "1" #&CDS_SEC = "1";
"A":   PN = "1"  !CDS_PN = "1";
"B":   PN = "2"  !CDS_PN = "2";
BODY = "Q_CAP","I87": #LOCATION = "PC215_1" !CDS_LOCATION = "PC215_1" &SEC = "1" #&CDS_SEC = "1";
"A":   PN = "1"  !CDS_PN = "1";
"B":   PN = "2"  !CDS_PN = "2";
BODY = "Q_CAP","I88": #LOCATION = "PC219_1" !CDS_LOCATION = "PC219_1" &SEC = "1" #&CDS_SEC = "1";
"A":   PN = "1"  !CDS_PN = "1";
"B":   PN = "2"  !CDS_PN = "2";
BODY = "Q_CAPP","I89": #LOCATION = "PC800" !CDS_LOCATION = "PC800" &SEC = "1" #&CDS_SEC = "1";
"A":   PN = "1"  !CDS_PN = "1";
"B":   PN = "2"  !CDS_PN = "2";
BODY = "Q_CAP","I90": #LOCATION = "PC221_2" !CDS_LOCATION = "PC221_2" &SEC = "1" #&CDS_SEC = "1";
"A":   PN = "1"  !CDS_PN = "1";
"B":   PN = "2"  !CDS_PN = "2";
BODY = "Q_RES","I91": #LOCATION = "PR138" !CDS_LOCATION = "PR138" &SEC = "1" #&CDS_SEC = "1";
"A":   PN = "1"  !CDS_PN = "1";
"B":   PN = "2"  !CDS_PN = "2";
BODY = "ISL99390FRZTR5935","I92": #LOCATION = "PU22" !CDS_LOCATION = "PU22" &SEC = "1" #&CDS_SEC = "1";
"AGND":   PN = "2"  !CDS_PN = "2";
"BOOT":   PN = "33"  !CDS_PN = "33";
"DNC":   PN = "31"  !CDS_PN = "31";
"EN":   PN = "35"  !CDS_PN = "35";
"GL1":   PN = "6"  !CDS_PN = "6";
"GL2":   PN = "41"  !CDS_PN = "41";
"IOUT":   PN = "38"  !CDS_PN = "38";
"LSET":   PN = "37"  !CDS_PN = "37";
"PGND1":   PN = "5"  !CDS_PN = "5";
"PGND2":   PN = "7_9-20_24"  !CDS_PN = "7_9-20_24";
"PGND3":   PN = "40"  !CDS_PN = "40";
"PHASE":   PN = "32"  !CDS_PN = "32";
"PVCC":   PN = "4"  !CDS_PN = "4";
"PWM":   PN = "34"  !CDS_PN = "34";
"REFIN":   PN = "39"  !CDS_PN = "39";
"SW":   PN = "10_19"  !CDS_PN = "10_19";
"TOUT_FLT":   PN = "36"  !CDS_PN = "36";
"VCC":   PN = "3"  !CDS_PN = "3";
"VIN1":   PN = "25_29"  !CDS_PN = "25_29";
"VIN2":   PN = "30"  !CDS_PN = "30";
"VOS":   PN = "1"  !CDS_PN = "1";
BODY = "Q_CAP","I93": #LOCATION = "PC8004" !CDS_LOCATION = "PC8004" &SEC = "1" #&CDS_SEC = "1";
"A":   PN = "1"  !CDS_PN = "1";
"B":   PN = "2"  !CDS_PN = "2";
BODY = "Q_CAP","I94": #LOCATION = "PC8005" !CDS_LOCATION = "PC8005" &SEC = "1" #&CDS_SEC = "1";
"A":   PN = "1"  !CDS_PN = "1";
"B":   PN = "2"  !CDS_PN = "2";
BODY = "Q_CAP","I95": #LOCATION = "PC7002" !CDS_LOCATION = "PC7002" &SEC = "1" #&CDS_SEC = "1";
"A":   PN = "1"  !CDS_PN = "1";
"B":   PN = "2"  !CDS_PN = "2";
DRAWING = "@t6g_mb_lib.t6g(sch_1):page185";
BODY = "Q_RES","I4": #LOCATION = "PR150" !CDS_LOCATION = "PR150" &SEC = "1" #&CDS_SEC = "1";
"A":   PN = "1"  !CDS_PN = "1";
"B":   PN = "2"  !CDS_PN = "2";
BODY = "Q_CAP","I13": #LOCATION = "C242" !CDS_LOCATION = "C242" &SEC = "1" #&CDS_SEC = "1";
"A":   PN = "1"  !CDS_PN = "1";
"B":   PN = "2"  !CDS_PN = "2";
BODY = "Q_RES","I36": #LOCATION = "PR164" !CDS_LOCATION = "PR164" &SEC = "1" #&CDS_SEC = "1";
"A":   PN = "1"  !CDS_PN = "1";
"B":   PN = "2"  !CDS_PN = "2";
BODY = "Q_RES","I42": #LOCATION = "R8182" !CDS_LOCATION = "R8182" &SEC = "1" #&CDS_SEC = "1";
"A":   PN = "1"  !CDS_PN = "1";
"B":   PN = "2"  !CDS_PN = "2";
BODY = "Q_RES","I43": #LOCATION = "R8168" !CDS_LOCATION = "R8168" &SEC = "1" #&CDS_SEC = "1";
"A":   PN = "1"  !CDS_PN = "1";
"B":   PN = "2"  !CDS_PN = "2";
BODY = "Q_RES","I47": #LOCATION = "PR181" !CDS_LOCATION = "PR181" &SEC = "1" #&CDS_SEC = "1";
"A":   PN = "1"  !CDS_PN = "1";
"B":   PN = "2"  !CDS_PN = "2";
BODY = "Q_RES","I57": #LOCATION = "PR174" !CDS_LOCATION = "PR174" &SEC = "1" #&CDS_SEC = "1";
"A":   PN = "1"  !CDS_PN = "1";
"B":   PN = "2"  !CDS_PN = "2";
BODY = "Q_CAP","I58": #LOCATION = "PC245" !CDS_LOCATION = "PC245" &SEC = "1" #&CDS_SEC = "1";
"A":   PN = "1"  !CDS_PN = "1";
"B":   PN = "2"  !CDS_PN = "2";
BODY = "Q_CAP","I62": #LOCATION = "C295" !CDS_LOCATION = "C295" &SEC = "1" #&CDS_SEC = "1";
"A":   PN = "1"  !CDS_PN = "1";
"B":   PN = "2"  !CDS_PN = "2";
BODY = "Q_RES","I67": #LOCATION = "R154" !CDS_LOCATION = "R154" &SEC = "1" #&CDS_SEC = "1";
"A":   PN = "1"  !CDS_PN = "1";
"B":   PN = "2"  !CDS_PN = "2";
BODY = "Q_RES","I68": #LOCATION = "R8156" !CDS_LOCATION = "R8156" &SEC = "1" #&CDS_SEC = "1";
"A":   PN = "1"  !CDS_PN = "1";
"B":   PN = "2"  !CDS_PN = "2";
BODY = "Q_RES","I81": #LOCATION = "R175" !CDS_LOCATION = "R175" &SEC = "1" #&CDS_SEC = "1";
"A":   PN = "1"  !CDS_PN = "1";
"B":   PN = "2"  !CDS_PN = "2";
BODY = "Q_RES","I82": #LOCATION = "PR172" !CDS_LOCATION = "PR172" &SEC = "1" #&CDS_SEC = "1";
"A":   PN = "1"  !CDS_PN = "1";
"B":   PN = "2"  !CDS_PN = "2";
BODY = "Q_CAP","I86": #LOCATION = "C249" !CDS_LOCATION = "C249" &SEC = "1" #&CDS_SEC = "1";
"A":   PN = "1"  !CDS_PN = "1";
"B":   PN = "2"  !CDS_PN = "2";
BODY = "Q_CAP","I88": #LOCATION = "C248" !CDS_LOCATION = "C248" &SEC = "1" #&CDS_SEC = "1";
"A":   PN = "1"  !CDS_PN = "1";
"B":   PN = "2"  !CDS_PN = "2";
BODY = "Q_CAP","I114": #LOCATION = "PC11" !CDS_LOCATION = "PC11" &SEC = "1" #&CDS_SEC = "1";
"A":   PN = "1"  !CDS_PN = "1";
"B":   PN = "2"  !CDS_PN = "2";
BODY = "Q_RES","I2": #LOCATION = "R149" !CDS_LOCATION = "R149" &SEC = "1" #&CDS_SEC = "1";
"A":   PN = "1"  !CDS_PN = "1";
"B":   PN = "2"  !CDS_PN = "2";
BODY = "Q_RES","I6": #LOCATION = "R8153" !CDS_LOCATION = "R8153" &SEC = "1" #&CDS_SEC = "1";
"A":   PN = "1"  !CDS_PN = "1";
"B":   PN = "2"  !CDS_PN = "2";
BODY = "Q_RES","I10": #LOCATION = "PR151" !CDS_LOCATION = "PR151" &SEC = "1" #&CDS_SEC = "1";
"A":   PN = "1"  !CDS_PN = "1";
"B":   PN = "2"  !CDS_PN = "2";
BODY = "Q_RES","I14": #LOCATION = "PR157" !CDS_LOCATION = "PR157" &SEC = "1" #&CDS_SEC = "1";
"A":   PN = "1"  !CDS_PN = "1";
"B":   PN = "2"  !CDS_PN = "2";
BODY = "MOSFET_N","I16": #LOCATION = "PQ15" !CDS_LOCATION = "PQ15" &SEC = "1" #&CDS_SEC = "1";
"DRAIN":   PN = "D"  !CDS_PN = "D";
"GATE":   PN = "G"  !CDS_PN = "G";
"SOURCE":   PN = "S"  !CDS_PN = "S";
BODY = "Q_RES","I17": #LOCATION = "PR152" !CDS_LOCATION = "PR152" &SEC = "1" #&CDS_SEC = "1";
"A":   PN = "1"  !CDS_PN = "1";
"B":   PN = "2"  !CDS_PN = "2";
BODY = "MOSFET_PCH_GDS_ESD_PROTECTED","I18": #LOCATION = "PQ11" !CDS_LOCATION = "PQ11" &SEC = "1" #&CDS_SEC = "1";
"D":   PN = "D"  !CDS_PN = "D";
"G":   PN = "G"  !CDS_PN = "G";
"S":   PN = "S"  !CDS_PN = "S";
BODY = "Q_RES","I20": #LOCATION = "PR4" !CDS_LOCATION = "PR4" #SEC = "1" !CDS_SEC = "1";
"A":   PN = "1"  !CDS_PN = "1";
"B":   PN = "2"  !CDS_PN = "2";
BODY = "Q_CAP","I22": #LOCATION = "PC243" !CDS_LOCATION = "PC243" &SEC = "1" #&CDS_SEC = "1";
"A":   PN = "1"  !CDS_PN = "1";
"B":   PN = "2"  !CDS_PN = "2";
BODY = "Q_RES","I23": #LOCATION = "R8166" !CDS_LOCATION = "R8166" &SEC = "1" #&CDS_SEC = "1";
"A":   PN = "1"  !CDS_PN = "1";
"B":   PN = "2"  !CDS_PN = "2";
BODY = "Q_RES","I27": #LOCATION = "R8165" !CDS_LOCATION = "R8165" &SEC = "1" #&CDS_SEC = "1";
"A":   PN = "1"  !CDS_PN = "1";
"B":   PN = "2"  !CDS_PN = "2";
BODY = "Q_RES","I39": #LOCATION = "PR163" !CDS_LOCATION = "PR163" &SEC = "1" #&CDS_SEC = "1";
"A":   PN = "1"  !CDS_PN = "1";
"B":   PN = "2"  !CDS_PN = "2";
BODY = "Q_RES","I41": #LOCATION = "R8184" !CDS_LOCATION = "R8184" &SEC = "1" #&CDS_SEC = "1";
"A":   PN = "1"  !CDS_PN = "1";
"B":   PN = "2"  !CDS_PN = "2";
BODY = "Q_RES","I45": #LOCATION = "PR162" !CDS_LOCATION = "PR162" &SEC = "1" #&CDS_SEC = "1";
"A":   PN = "1"  !CDS_PN = "1";
"B":   PN = "2"  !CDS_PN = "2";
BODY = "Q_RES","I48": #LOCATION = "PR602" !CDS_LOCATION = "PR602" &SEC = "1" #&CDS_SEC = "1";
"A":   PN = "1"  !CDS_PN = "1";
"B":   PN = "2"  !CDS_PN = "2";
BODY = "Q_CAP","I51": #LOCATION = "PC6" !CDS_LOCATION = "PC6" #SEC = "1" !CDS_SEC = "1";
"A":   PN = "1"  !CDS_PN = "1";
"B":   PN = "2"  !CDS_PN = "2";
BODY = "Q_CAP","I52": #LOCATION = "C8246" !CDS_LOCATION = "C8246" &SEC = "1" #&CDS_SEC = "1";
"A":   PN = "1"  !CDS_PN = "1";
"B":   PN = "2"  !CDS_PN = "2";
BODY = "Q_RES","I54": #LOCATION = "R8180" !CDS_LOCATION = "R8180" &SEC = "1" #&CDS_SEC = "1";
"A":   PN = "1"  !CDS_PN = "1";
"B":   PN = "2"  !CDS_PN = "2";
BODY = "Q_RES","I59": #LOCATION = "PR173" !CDS_LOCATION = "PR173" &SEC = "1" #&CDS_SEC = "1";
"A":   PN = "1"  !CDS_PN = "1";
"B":   PN = "2"  !CDS_PN = "2";
BODY = "Q_CAP","I60": #LOCATION = "PC244" !CDS_LOCATION = "PC244" &SEC = "1" #&CDS_SEC = "1";
"A":   PN = "1"  !CDS_PN = "1";
"B":   PN = "2"  !CDS_PN = "2";
BODY = "Q_CAP","I64": #LOCATION = "C296" !CDS_LOCATION = "C296" &SEC = "1" #&CDS_SEC = "1";
"A":   PN = "1"  !CDS_PN = "1";
"B":   PN = "2"  !CDS_PN = "2";
BODY = "Q_CAP","I66": #LOCATION = "C297" !CDS_LOCATION = "C297" &SEC = "1" #&CDS_SEC = "1";
"A":   PN = "1"  !CDS_PN = "1";
"B":   PN = "2"  !CDS_PN = "2";
BODY = "Q_RES","I69": #LOCATION = "R8160" !CDS_LOCATION = "R8160" &SEC = "1" #&CDS_SEC = "1";
"A":   PN = "1"  !CDS_PN = "1";
"B":   PN = "2"  !CDS_PN = "2";
BODY = "Q_RES","I70": #LOCATION = "PR161" !CDS_LOCATION = "PR161" &SEC = "1" #&CDS_SEC = "1";
"A":   PN = "1"  !CDS_PN = "1";
"B":   PN = "2"  !CDS_PN = "2";
BODY = "Q_RES","I78": #LOCATION = "R8167" !CDS_LOCATION = "R8167" &SEC = "1" #&CDS_SEC = "1";
"A":   PN = "1"  !CDS_PN = "1";
"B":   PN = "2"  !CDS_PN = "2";
BODY = "Q_RES","I79": #LOCATION = "R8177" !CDS_LOCATION = "R8177" &SEC = "1" #&CDS_SEC = "1";
"A":   PN = "1"  !CDS_PN = "1";
"B":   PN = "2"  !CDS_PN = "2";
BODY = "Q_RES","I80": #LOCATION = "R8176" !CDS_LOCATION = "R8176" &SEC = "1" #&CDS_SEC = "1";
"A":   PN = "1"  !CDS_PN = "1";
"B":   PN = "2"  !CDS_PN = "2";
BODY = "Q_RES","I83": #LOCATION = "R8171" !CDS_LOCATION = "R8171" &SEC = "1" #&CDS_SEC = "1";
"A":   PN = "1"  !CDS_PN = "1";
"B":   PN = "2"  !CDS_PN = "2";
BODY = "Q_RES","I84": #LOCATION = "R8179" !CDS_LOCATION = "R8179" &SEC = "1" #&CDS_SEC = "1";
"A":   PN = "1"  !CDS_PN = "1";
"B":   PN = "2"  !CDS_PN = "2";
BODY = "Q_RES","I85": #LOCATION = "R8178" !CDS_LOCATION = "R8178" &SEC = "1" #&CDS_SEC = "1";
"A":   PN = "1"  !CDS_PN = "1";
"B":   PN = "2"  !CDS_PN = "2";
BODY = "Q_CAP","I91": #LOCATION = "PC250" !CDS_LOCATION = "PC250" &SEC = "1" #&CDS_SEC = "1";
"A":   PN = "1"  !CDS_PN = "1";
"B":   PN = "2"  !CDS_PN = "2";
BODY = "Q_CAP","I94": #LOCATION = "PC253" !CDS_LOCATION = "PC253" &SEC = "1" #&CDS_SEC = "1";
"A":   PN = "1"  !CDS_PN = "1";
"B":   PN = "2"  !CDS_PN = "2";
BODY = "Q_RES","I102": #LOCATION = "PR437" !CDS_LOCATION = "PR437" &SEC = "1" #&CDS_SEC = "1";
"A":   PN = "1"  !CDS_PN = "1";
"B":   PN = "2"  !CDS_PN = "2";
BODY = "Q_RES","I103": #LOCATION = "PR436" !CDS_LOCATION = "PR436" &SEC = "1" #&CDS_SEC = "1";
"A":   PN = "1"  !CDS_PN = "1";
"B":   PN = "2"  !CDS_PN = "2";
BODY = "Q_RES","I107": #LOCATION = "PR530" !CDS_LOCATION = "PR530" &SEC = "1" #&CDS_SEC = "1";
"A":   PN = "1"  !CDS_PN = "1";
"B":   PN = "2"  !CDS_PN = "2";
BODY = "Q_CAP","I116": #LOCATION = "PC10" !CDS_LOCATION = "PC10" &SEC = "1" #&CDS_SEC = "1";
"A":   PN = "1"  !CDS_PN = "1";
"B":   PN = "2"  !CDS_PN = "2";
BODY = "Q_CAP","I125": #LOCATION = "PC251" !CDS_LOCATION = "PC251" &SEC = "1" #&CDS_SEC = "1";
"A":   PN = "1"  !CDS_PN = "1";
"B":   PN = "2"  !CDS_PN = "2";
BODY = "Q_CAP","I127": #LOCATION = "PC252" !CDS_LOCATION = "PC252" &SEC = "1" #&CDS_SEC = "1";
"A":   PN = "1"  !CDS_PN = "1";
"B":   PN = "2"  !CDS_PN = "2";
BODY = "Q_RES","I129": #LOCATION = "PR183" !CDS_LOCATION = "PR183" &SEC = "1" #&CDS_SEC = "1";
"A":   PN = "1"  !CDS_PN = "1";
"B":   PN = "2"  !CDS_PN = "2";
BODY = "Q_CAP","I132": #LOCATION = "PC247" !CDS_LOCATION = "PC247" &SEC = "1" #&CDS_SEC = "1";
"A":   PN = "1"  !CDS_PN = "1";
"B":   PN = "2"  !CDS_PN = "2";
BODY = "RAA229620GNPHA0","I133": #LOCATION = "PU25" !CDS_LOCATION = "PU25" #SEC = "1" !CDS_SEC = "1";
"CS0":   PN = "38"  !CDS_PN = "38";
"CS1":   PN = "37"  !CDS_PN = "37";
"CS2":   PN = "36"  !CDS_PN = "36";
"CS3":   PN = "35"  !CDS_PN = "35";
"CS4":   PN = "34"  !CDS_PN = "34";
"CS5":   PN = "33"  !CDS_PN = "33";
"CS6":   PN = "32"  !CDS_PN = "32";
"CS7":   PN = "31"  !CDS_PN = "31";
"CS8":   PN = "30"  !CDS_PN = "30";
"CS9":   PN = "29"  !CDS_PN = "29";
"CS10":   PN = "28"  !CDS_PN = "28";
"CS11":   PN = "27"  !CDS_PN = "27";
"EN0":   PN = "17"  !CDS_PN = "17";
"EN1||ADDR_CFG":   PN = "42"  !CDS_PN = "42";
"NPMALERT":   PN = "15"  !CDS_PN = "15";
"OCP_L":   PN = "41"  !CDS_PN = "41";
"PG0":   PN = "16"  !CDS_PN = "16";
"PG1":   PN = "20"  !CDS_PN = "20";
"PMSCL":   PN = "14"  !CDS_PN = "14";
"PMSDA":   PN = "13"  !CDS_PN = "13";
"PWM0":   PN = "1"  !CDS_PN = "1";
"PWM1":   PN = "2"  !CDS_PN = "2";
"PWM2":   PN = "3"  !CDS_PN = "3";
"PWM3":   PN = "4"  !CDS_PN = "4";
"PWM4":   PN = "5"  !CDS_PN = "5";
"PWM5":   PN = "6"  !CDS_PN = "6";
"PWM6":   PN = "7"  !CDS_PN = "7";
"PWM7":   PN = "8"  !CDS_PN = "8";
"PWM8":   PN = "9"  !CDS_PN = "9";
"PWM9":   PN = "10"  !CDS_PN = "10";
"PWM10":   PN = "11"  !CDS_PN = "11";
"PWM11":   PN = "12"  !CDS_PN = "12";
"RESET_L":   PN = "18"  !CDS_PN = "18";
"RGND0":   PN = "26"  !CDS_PN = "26";
"RGND1":   PN = "39"  !CDS_PN = "39";
"SVC":   PN = "22"  !CDS_PN = "22";
"SVD":   PN = "21"  !CDS_PN = "21";
"SVTI":   PN = "24"  !CDS_PN = "24";
"SVTO":   PN = "23"  !CDS_PN = "23";
"TEMP0":   PN = "44"  !CDS_PN = "44";
"TEMP1":   PN = "43"  !CDS_PN = "43";
"TH_GND":   PN = "TH"  !CDS_PN = "TH";
"VCC":   PN = "47"  !CDS_PN = "47";
"VCCS":   PN = "48"  !CDS_PN = "48";
"VDDIO":   PN = "19"  !CDS_PN = "19";
"VINSEN":   PN = "46"  !CDS_PN = "46";
"VMON||IINSEN":   PN = "45"  !CDS_PN = "45";
"VSEN0":   PN = "25"  !CDS_PN = "25";
"VSEN1":   PN = "40"  !CDS_PN = "40";
BODY = "Q_RES","I135": #LOCATION = "R6087" !CDS_LOCATION = "R6087" &SEC = "1" #&CDS_SEC = "1";
"A":   PN = "1"  !CDS_PN = "1";
"B":   PN = "2"  !CDS_PN = "2";
BODY = "Q_CAP","I137": #LOCATION = "C5019" !CDS_LOCATION = "C5019" &SEC = "1" #&CDS_SEC = "1";
"A":   PN = "1"  !CDS_PN = "1";
"B":   PN = "2"  !CDS_PN = "2";
BODY = "Q_CAP","I139": #LOCATION = "C5012" !CDS_LOCATION = "C5012" &SEC = "1" #&CDS_SEC = "1";
"A":   PN = "1"  !CDS_PN = "1";
"B":   PN = "2"  !CDS_PN = "2";
BODY = "Q_CAP","I141": #LOCATION = "C5003" !CDS_LOCATION = "C5003" &SEC = "1" #&CDS_SEC = "1";
"A":   PN = "1"  !CDS_PN = "1";
"B":   PN = "2"  !CDS_PN = "2";
BODY = "Q_RES","I142": #LOCATION = "PR159" !CDS_LOCATION = "PR159" &SEC = "1" #&CDS_SEC = "1";
"A":   PN = "1"  !CDS_PN = "1";
"B":   PN = "2"  !CDS_PN = "2";
BODY = "Q_RES","I143": #LOCATION = "PR8009" !CDS_LOCATION = "PR8009" &SEC = "1" #&CDS_SEC = "1";
"A":   PN = "1"  !CDS_PN = "1";
"B":   PN = "2"  !CDS_PN = "2";
BODY = "Q_RES","I144": #LOCATION = "PR8010" !CDS_LOCATION = "PR8010" &SEC = "1" #&CDS_SEC = "1";
"A":   PN = "1"  !CDS_PN = "1";
"B":   PN = "2"  !CDS_PN = "2";
DRAWING = "@t6g_mb_lib.t6g(sch_1):page186";
BODY = "Q_RES","I3": #LOCATION = "PR335" !CDS_LOCATION = "PR335" &SEC = "1" #&CDS_SEC = "1";
"A":   PN = "1"  !CDS_PN = "1";
"B":   PN = "2"  !CDS_PN = "2";
BODY = "Q_RES","I11": #LOCATION = "PR186" !CDS_LOCATION = "PR186" &SEC = "1" #&CDS_SEC = "1";
"A":   PN = "1"  !CDS_PN = "1";
"B":   PN = "2"  !CDS_PN = "2";
BODY = "Q_CAP","I13": #LOCATION = "PC259_C0P1_2" !CDS_LOCATION = "PC259_C0P1_2" &SEC = "1" #&CDS_SEC = "1";
"A":   PN = "1"  !CDS_PN = "1";
"B":   PN = "2"  !CDS_PN = "2";
BODY = "Q_CAP","I16": #LOCATION = "PC254_1" !CDS_LOCATION = "PC254_1" &SEC = "1" #&CDS_SEC = "1";
"A":   PN = "1"  !CDS_PN = "1";
"B":   PN = "2"  !CDS_PN = "2";
BODY = "Q_CAP","I24": #LOCATION = "PC173" !CDS_LOCATION = "PC173" &SEC = "1" #&CDS_SEC = "1";
"A":   PN = "1"  !CDS_PN = "1";
"B":   PN = "2"  !CDS_PN = "2";
BODY = "Q_CAP","I26": #LOCATION = "PC263_2" !CDS_LOCATION = "PC263_2" &SEC = "1" #&CDS_SEC = "1";
"A":   PN = "1"  !CDS_PN = "1";
"B":   PN = "2"  !CDS_PN = "2";
BODY = "Q_CAP","I31": #LOCATION = "PC269_2" !CDS_LOCATION = "PC269_2" &SEC = "1" #&CDS_SEC = "1";
"A":   PN = "1"  !CDS_PN = "1";
"B":   PN = "2"  !CDS_PN = "2";
BODY = "Q_RES","I35": #LOCATION = "PR191" !CDS_LOCATION = "PR191" &SEC = "1" #&CDS_SEC = "1";
"A":   PN = "1"  !CDS_PN = "1";
"B":   PN = "2"  !CDS_PN = "2";
BODY = "Q_CAP","I46": #LOCATION = "PC260_1" !CDS_LOCATION = "PC260_1" &SEC = "1" #&CDS_SEC = "1";
"A":   PN = "1"  !CDS_PN = "1";
"B":   PN = "2"  !CDS_PN = "2";
BODY = "Q_CAP","I48": #LOCATION = "PC170" !CDS_LOCATION = "PC170" &SEC = "1" #&CDS_SEC = "1";
"A":   PN = "1"  !CDS_PN = "1";
"B":   PN = "2"  !CDS_PN = "2";
BODY = "Q_CAP","I63": #LOCATION = "PC282_2" !CDS_LOCATION = "PC282_2" &SEC = "1" #&CDS_SEC = "1";
"A":   PN = "1"  !CDS_PN = "1";
"B":   PN = "2"  !CDS_PN = "2";
BODY = "Q_CAPP","I66": #LOCATION = "PC279" !CDS_LOCATION = "PC279" &SEC = "1" #&CDS_SEC = "1";
"A":   PN = "1"  !CDS_PN = "1";
"B":   PN = "2"  !CDS_PN = "2";
BODY = "Q_CAPP","I71": #LOCATION = "PC273" !CDS_LOCATION = "PC273" &SEC = "1" #&CDS_SEC = "1";
"A":   PN = "1"  !CDS_PN = "1";
"B":   PN = "2"  !CDS_PN = "2";
BODY = "Q_CAP","I5": #LOCATION = "PC255_2" !CDS_LOCATION = "PC255_2" &SEC = "1" #&CDS_SEC = "1";
"A":   PN = "1"  !CDS_PN = "1";
"B":   PN = "2"  !CDS_PN = "2";
BODY = "Q_CAP","I9": #LOCATION = "PC257" !CDS_LOCATION = "PC257" &SEC = "1" #&CDS_SEC = "1";
"A":   PN = "1"  !CDS_PN = "1";
"B":   PN = "2"  !CDS_PN = "2";
BODY = "Q_RES","I22": #LOCATION = "PR486" !CDS_LOCATION = "PR486" &SEC = "1" #&CDS_SEC = "1";
"A":   PN = "1"  !CDS_PN = "1";
"B":   PN = "2"  !CDS_PN = "2";
BODY = "Q_RES","I23": #LOCATION = "PR192" !CDS_LOCATION = "PR192" &SEC = "1" #&CDS_SEC = "1";
"A":   PN = "1"  !CDS_PN = "1";
"B":   PN = "2"  !CDS_PN = "2";
BODY = "Q_CAP","I25": #LOCATION = "PC261_2" !CDS_LOCATION = "PC261_2" &SEC = "1" #&CDS_SEC = "1";
"A":   PN = "1"  !CDS_PN = "1";
"B":   PN = "2"  !CDS_PN = "2";
BODY = "Q_CAP","I28": #LOCATION = "PC265_2" !CDS_LOCATION = "PC265_2" &SEC = "1" #&CDS_SEC = "1";
"A":   PN = "1"  !CDS_PN = "1";
"B":   PN = "2"  !CDS_PN = "2";
BODY = "Q_CAP","I29": #LOCATION = "PC267_2" !CDS_LOCATION = "PC267_2" &SEC = "1" #&CDS_SEC = "1";
"A":   PN = "1"  !CDS_PN = "1";
"B":   PN = "2"  !CDS_PN = "2";
BODY = "Q_RES","I34": #LOCATION = "PR485" !CDS_LOCATION = "PR485" &SEC = "1" #&CDS_SEC = "1";
"A":   PN = "1"  !CDS_PN = "1";
"B":   PN = "2"  !CDS_PN = "2";
BODY = "Q_CAP","I36": #LOCATION = "PC256" !CDS_LOCATION = "PC256" &SEC = "1" #&CDS_SEC = "1";
"A":   PN = "1"  !CDS_PN = "1";
"B":   PN = "2"  !CDS_PN = "2";
BODY = "Q_RES","I37": #LOCATION = "PR187" !CDS_LOCATION = "PR187" &SEC = "1" #&CDS_SEC = "1";
"A":   PN = "1"  !CDS_PN = "1";
"B":   PN = "2"  !CDS_PN = "2";
BODY = "Q_RES","I41": #LOCATION = "PR336" !CDS_LOCATION = "PR336" &SEC = "1" #&CDS_SEC = "1";
"A":   PN = "1"  !CDS_PN = "1";
"B":   PN = "2"  !CDS_PN = "2";
BODY = "Q_RES","I43": #LOCATION = "PR185" !CDS_LOCATION = "PR185" &SEC = "1" #&CDS_SEC = "1";
"A":   PN = "1"  !CDS_PN = "1";
"B":   PN = "2"  !CDS_PN = "2";
BODY = "Q_CAP","I44": #LOCATION = "PC258_C0P1_1" !CDS_LOCATION = "PC258_C0P1_1" &SEC = "1" #&CDS_SEC = "1";
"A":   PN = "1"  !CDS_PN = "1";
"B":   PN = "2"  !CDS_PN = "2";
BODY = "Q_CAP","I47": #LOCATION = "PC262_1" !CDS_LOCATION = "PC262_1" &SEC = "1" #&CDS_SEC = "1";
"A":   PN = "1"  !CDS_PN = "1";
"B":   PN = "2"  !CDS_PN = "2";
BODY = "Q_RES","I49": #LOCATION = "PR189" !CDS_LOCATION = "PR189" &SEC = "1" #&CDS_SEC = "1";
"A":   PN = "1"  !CDS_PN = "1";
"B":   PN = "2"  !CDS_PN = "2";
BODY = "Q_CAP","I51": #LOCATION = "PC264_1" !CDS_LOCATION = "PC264_1" &SEC = "1" #&CDS_SEC = "1";
"A":   PN = "1"  !CDS_PN = "1";
"B":   PN = "2"  !CDS_PN = "2";
BODY = "Q_CAP","I52": #LOCATION = "PC266_1" !CDS_LOCATION = "PC266_1" &SEC = "1" #&CDS_SEC = "1";
"A":   PN = "1"  !CDS_PN = "1";
"B":   PN = "2"  !CDS_PN = "2";
BODY = "Q_CAP","I53": #LOCATION = "PC268_1" !CDS_LOCATION = "PC268_1" &SEC = "1" #&CDS_SEC = "1";
"A":   PN = "1"  !CDS_PN = "1";
"B":   PN = "2"  !CDS_PN = "2";
BODY = "Q_CAP","I55": #LOCATION = "PC271" !CDS_LOCATION = "PC271" &SEC = "1" #&CDS_SEC = "1";
"A":   PN = "1"  !CDS_PN = "1";
"B":   PN = "2"  !CDS_PN = "2";
BODY = "Q_INDUCTOR4P_14","I56": #LOCATION = "PL29" !CDS_LOCATION = "PL29" &SEC = "1" #&CDS_SEC = "1";
"1":   PN = "1"  !CDS_PN = "1";
"2":   PN = "2"  !CDS_PN = "2";
"3":   PN = "3"  !CDS_PN = "3";
"4":   PN = "4"  !CDS_PN = "4";
BODY = "Q_CAPP","I58": #LOCATION = "PC275" !CDS_LOCATION = "PC275" &SEC = "1" #&CDS_SEC = "1";
"A":   PN = "1"  !CDS_PN = "1";
"B":   PN = "2"  !CDS_PN = "2";
BODY = "Q_CAPP","I59": #LOCATION = "PC276" !CDS_LOCATION = "PC276" &SEC = "1" #&CDS_SEC = "1";
"A":   PN = "1"  !CDS_PN = "1";
"B":   PN = "2"  !CDS_PN = "2";
BODY = "Q_CAPP","I60": #LOCATION = "PC277" !CDS_LOCATION = "PC277" &SEC = "1" #&CDS_SEC = "1";
"A":   PN = "1"  !CDS_PN = "1";
"B":   PN = "2"  !CDS_PN = "2";
BODY = "Q_CAP","I61": #LOCATION = "PC280_2" !CDS_LOCATION = "PC280_2" &SEC = "1" #&CDS_SEC = "1";
"A":   PN = "1"  !CDS_PN = "1";
"B":   PN = "2"  !CDS_PN = "2";
BODY = "Q_CAPP","I70": #LOCATION = "PC272" !CDS_LOCATION = "PC272" &SEC = "1" #&CDS_SEC = "1";
"A":   PN = "1"  !CDS_PN = "1";
"B":   PN = "2"  !CDS_PN = "2";
BODY = "Q_INDUCTOR","I73": #LOCATION = "PL30" !CDS_LOCATION = "PL30" &SEC = "1" #&CDS_SEC = "1";
"1":   PN = "1"  !CDS_PN = "1";
"2":   PN = "2"  !CDS_PN = "2";
BODY = "Q_CAP","I74": #LOCATION = "PC6004" !CDS_LOCATION = "PC6004" &SEC = "1" #&CDS_SEC = "1";
"A":   PN = "1"  !CDS_PN = "1";
"B":   PN = "2"  !CDS_PN = "2";
BODY = "Q_CAP","I76": #LOCATION = "PC281_1" !CDS_LOCATION = "PC281_1" &SEC = "1" #&CDS_SEC = "1";
"A":   PN = "1"  !CDS_PN = "1";
"B":   PN = "2"  !CDS_PN = "2";
BODY = "Q_CAP","I77": #LOCATION = "PC283_1" !CDS_LOCATION = "PC283_1" &SEC = "1" #&CDS_SEC = "1";
"A":   PN = "1"  !CDS_PN = "1";
"B":   PN = "2"  !CDS_PN = "2";
BODY = "Q_RES","I78": #LOCATION = "PR337" !CDS_LOCATION = "PR337" &SEC = "1" #&CDS_SEC = "1";
"A":   PN = "1"  !CDS_PN = "1";
"B":   PN = "2"  !CDS_PN = "2";
BODY = "Q_RES","I80": #LOCATION = "PR188" !CDS_LOCATION = "PR188" &SEC = "1" #&CDS_SEC = "1";
"A":   PN = "1"  !CDS_PN = "1";
"B":   PN = "2"  !CDS_PN = "2";
BODY = "Q_RES","I83": #LOCATION = "PR190" !CDS_LOCATION = "PR190" &SEC = "1" #&CDS_SEC = "1";
"A":   PN = "1"  !CDS_PN = "1";
"B":   PN = "2"  !CDS_PN = "2";
BODY = "Q_CAPP","I84": #LOCATION = "PC105" !CDS_LOCATION = "PC105" &SEC = "1" #&CDS_SEC = "1";
"A":   PN = "1"  !CDS_PN = "1";
"B":   PN = "2"  !CDS_PN = "2";
BODY = "Q_CAP","I85": #LOCATION = "PC278" !CDS_LOCATION = "PC278" &SEC = "1" #&CDS_SEC = "1";
"A":   PN = "1"  !CDS_PN = "1";
"B":   PN = "2"  !CDS_PN = "2";
BODY = "ISL99390FRZTR5935","I88": #LOCATION = "PU4" !CDS_LOCATION = "PU4" &SEC = "1" #&CDS_SEC = "1";
"AGND":   PN = "2"  !CDS_PN = "2";
"BOOT":   PN = "33"  !CDS_PN = "33";
"DNC":   PN = "31"  !CDS_PN = "31";
"EN":   PN = "35"  !CDS_PN = "35";
"GL1":   PN = "6"  !CDS_PN = "6";
"GL2":   PN = "41"  !CDS_PN = "41";
"IOUT":   PN = "38"  !CDS_PN = "38";
"LSET":   PN = "37"  !CDS_PN = "37";
"PGND1":   PN = "5"  !CDS_PN = "5";
"PGND2":   PN = "7_9-20_24"  !CDS_PN = "7_9-20_24";
"PGND3":   PN = "40"  !CDS_PN = "40";
"PHASE":   PN = "32"  !CDS_PN = "32";
"PVCC":   PN = "4"  !CDS_PN = "4";
"PWM":   PN = "34"  !CDS_PN = "34";
"REFIN":   PN = "39"  !CDS_PN = "39";
"SW":   PN = "10_19"  !CDS_PN = "10_19";
"TOUT_FLT":   PN = "36"  !CDS_PN = "36";
"VCC":   PN = "3"  !CDS_PN = "3";
"VIN1":   PN = "25_29"  !CDS_PN = "25_29";
"VIN2":   PN = "30"  !CDS_PN = "30";
"VOS":   PN = "1"  !CDS_PN = "1";
BODY = "Q_CAP","I89": #LOCATION = "PC270" !CDS_LOCATION = "PC270" &SEC = "1" #&CDS_SEC = "1";
"A":   PN = "1"  !CDS_PN = "1";
"B":   PN = "2"  !CDS_PN = "2";
BODY = "Q_INDUCTOR4P_14","I90": #LOCATION = "PL28" !CDS_LOCATION = "PL28" &SEC = "1" #&CDS_SEC = "1";
"1":   PN = "1"  !CDS_PN = "1";
"2":   PN = "2"  !CDS_PN = "2";
"3":   PN = "3"  !CDS_PN = "3";
"4":   PN = "4"  !CDS_PN = "4";
BODY = "ISL99390FRZTR5935","I91": #LOCATION = "PU26" !CDS_LOCATION = "PU26" &SEC = "1" #&CDS_SEC = "1";
"AGND":   PN = "2"  !CDS_PN = "2";
"BOOT":   PN = "33"  !CDS_PN = "33";
"DNC":   PN = "31"  !CDS_PN = "31";
"EN":   PN = "35"  !CDS_PN = "35";
"GL1":   PN = "6"  !CDS_PN = "6";
"GL2":   PN = "41"  !CDS_PN = "41";
"IOUT":   PN = "38"  !CDS_PN = "38";
"LSET":   PN = "37"  !CDS_PN = "37";
"PGND1":   PN = "5"  !CDS_PN = "5";
"PGND2":   PN = "7_9-20_24"  !CDS_PN = "7_9-20_24";
"PGND3":   PN = "40"  !CDS_PN = "40";
"PHASE":   PN = "32"  !CDS_PN = "32";
"PVCC":   PN = "4"  !CDS_PN = "4";
"PWM":   PN = "34"  !CDS_PN = "34";
"REFIN":   PN = "39"  !CDS_PN = "39";
"SW":   PN = "10_19"  !CDS_PN = "10_19";
"TOUT_FLT":   PN = "36"  !CDS_PN = "36";
"VCC":   PN = "3"  !CDS_PN = "3";
"VIN1":   PN = "25_29"  !CDS_PN = "25_29";
"VIN2":   PN = "30"  !CDS_PN = "30";
"VOS":   PN = "1"  !CDS_PN = "1";
DRAWING = "@t6g_mb_lib.t6g(sch_1):page190";
BODY = "Q_CAP","I4": #LOCATION = "PC318_8" !CDS_LOCATION = "PC318_8" &SEC = "1" #&CDS_SEC = "1";
"A":   PN = "1"  !CDS_PN = "1";
"B":   PN = "2"  !CDS_PN = "2";
BODY = "Q_CAP","I22": #LOCATION = "PC326_2" !CDS_LOCATION = "PC326_2" &SEC = "1" #&CDS_SEC = "1";
"A":   PN = "1"  !CDS_PN = "1";
"B":   PN = "2"  !CDS_PN = "2";
BODY = "Q_RES","I24": #LOCATION = "PR210" !CDS_LOCATION = "PR210" &SEC = "1" #&CDS_SEC = "1";
"A":   PN = "1"  !CDS_PN = "1";
"B":   PN = "2"  !CDS_PN = "2";
BODY = "Q_CAP","I25": #LOCATION = "PC324_2" !CDS_LOCATION = "PC324_2" &SEC = "1" #&CDS_SEC = "1";
"A":   PN = "1"  !CDS_PN = "1";
"B":   PN = "2"  !CDS_PN = "2";
BODY = "Q_CAP","I26": #LOCATION = "PC328_2" !CDS_LOCATION = "PC328_2" &SEC = "1" #&CDS_SEC = "1";
"A":   PN = "1"  !CDS_PN = "1";
"B":   PN = "2"  !CDS_PN = "2";
BODY = "Q_RES","I29": #LOCATION = "PR525" !CDS_LOCATION = "PR525" &SEC = "1" #&CDS_SEC = "1";
"A":   PN = "1"  !CDS_PN = "1";
"B":   PN = "2"  !CDS_PN = "2";
BODY = "Q_RES","I39": #LOCATION = "PR205" !CDS_LOCATION = "PR205" &SEC = "1" #&CDS_SEC = "1";
"A":   PN = "1"  !CDS_PN = "1";
"B":   PN = "2"  !CDS_PN = "2";
BODY = "Q_CAP","I43": #LOCATION = "PC325_1" !CDS_LOCATION = "PC325_1" &SEC = "1" #&CDS_SEC = "1";
"A":   PN = "1"  !CDS_PN = "1";
"B":   PN = "2"  !CDS_PN = "2";
BODY = "Q_CAP","I44": #LOCATION = "PC323_1" !CDS_LOCATION = "PC323_1" &SEC = "1" #&CDS_SEC = "1";
"A":   PN = "1"  !CDS_PN = "1";
"B":   PN = "2"  !CDS_PN = "2";
BODY = "Q_CAP","I48": #LOCATION = "PC327_1" !CDS_LOCATION = "PC327_1" &SEC = "1" #&CDS_SEC = "1";
"A":   PN = "1"  !CDS_PN = "1";
"B":   PN = "2"  !CDS_PN = "2";
BODY = "Q_INDUCTOR4P_14","I52": #LOCATION = "PL36" !CDS_LOCATION = "PL36" &SEC = "1" #&CDS_SEC = "1";
"1":   PN = "1"  !CDS_PN = "1";
"2":   PN = "2"  !CDS_PN = "2";
"3":   PN = "3"  !CDS_PN = "3";
"4":   PN = "4"  !CDS_PN = "4";
BODY = "Q_CAPP","I63": #LOCATION = "PC340" !CDS_LOCATION = "PC340" &SEC = "1" #&CDS_SEC = "1";
"A":   PN = "1"  !CDS_PN = "1";
"B":   PN = "2"  !CDS_PN = "2";
BODY = "Q_CAPP","I66": #LOCATION = "PC343" !CDS_LOCATION = "PC343" &SEC = "1" #&CDS_SEC = "1";
"A":   PN = "1"  !CDS_PN = "1";
"B":   PN = "2"  !CDS_PN = "2";
BODY = "Q_CAP","I68": #LOCATION = "PC333" !CDS_LOCATION = "PC333" &SEC = "1" #&CDS_SEC = "1";
"A":   PN = "1"  !CDS_PN = "1";
"B":   PN = "2"  !CDS_PN = "2";
BODY = "Q_INDUCTOR4P_14","I69": #LOCATION = "PL35" !CDS_LOCATION = "PL35" &SEC = "1" #&CDS_SEC = "1";
"1":   PN = "1"  !CDS_PN = "1";
"2":   PN = "2"  !CDS_PN = "2";
"3":   PN = "3"  !CDS_PN = "3";
"4":   PN = "4"  !CDS_PN = "4";
BODY = "Q_CAP","I79": #LOCATION = "PC338" !CDS_LOCATION = "PC338" &SEC = "1" #&CDS_SEC = "1";
"A":   PN = "1"  !CDS_PN = "1";
"B":   PN = "2"  !CDS_PN = "2";
BODY = "Q_CAP","I81": #LOCATION = "PC344_1" !CDS_LOCATION = "PC344_1" &SEC = "1" #&CDS_SEC = "1";
"A":   PN = "1"  !CDS_PN = "1";
"B":   PN = "2"  !CDS_PN = "2";
BODY = "Q_RES","I83": #LOCATION = "PR339" !CDS_LOCATION = "PR339" &SEC = "1" #&CDS_SEC = "1";
"A":   PN = "1"  !CDS_PN = "1";
"B":   PN = "2"  !CDS_PN = "2";
BODY = "Q_RES","I8": #LOCATION = "PR208" !CDS_LOCATION = "PR208" &SEC = "1" #&CDS_SEC = "1";
"A":   PN = "1"  !CDS_PN = "1";
"B":   PN = "2"  !CDS_PN = "2";
BODY = "Q_CAP","I11": #LOCATION = "PC320" !CDS_LOCATION = "PC320" &SEC = "1" #&CDS_SEC = "1";
"A":   PN = "1"  !CDS_PN = "1";
"B":   PN = "2"  !CDS_PN = "2";
BODY = "Q_RES","I12": #LOCATION = "PR206" !CDS_LOCATION = "PR206" &SEC = "1" #&CDS_SEC = "1";
"A":   PN = "1"  !CDS_PN = "1";
"B":   PN = "2"  !CDS_PN = "2";
BODY = "Q_CAP","I14": #LOCATION = "PC322_SOP1_2" !CDS_LOCATION = "PC322_SOP1_2" &SEC = "1" #&CDS_SEC = "1";
"A":   PN = "1"  !CDS_PN = "1";
"B":   PN = "2"  !CDS_PN = "2";
BODY = "ISL99390FRZTR5935","I17": #LOCATION = "PU30" !CDS_LOCATION = "PU30" &SEC = "1" #&CDS_SEC = "1";
"AGND":   PN = "2"  !CDS_PN = "2";
"BOOT":   PN = "33"  !CDS_PN = "33";
"DNC":   PN = "31"  !CDS_PN = "31";
"EN":   PN = "35"  !CDS_PN = "35";
"GL1":   PN = "6"  !CDS_PN = "6";
"GL2":   PN = "41"  !CDS_PN = "41";
"IOUT":   PN = "38"  !CDS_PN = "38";
"LSET":   PN = "37"  !CDS_PN = "37";
"PGND1":   PN = "5"  !CDS_PN = "5";
"PGND2":   PN = "7_9-20_24"  !CDS_PN = "7_9-20_24";
"PGND3":   PN = "40"  !CDS_PN = "40";
"PHASE":   PN = "32"  !CDS_PN = "32";
"PVCC":   PN = "4"  !CDS_PN = "4";
"PWM":   PN = "34"  !CDS_PN = "34";
"REFIN":   PN = "39"  !CDS_PN = "39";
"SW":   PN = "10_19"  !CDS_PN = "10_19";
"TOUT_FLT":   PN = "36"  !CDS_PN = "36";
"VCC":   PN = "3"  !CDS_PN = "3";
"VIN1":   PN = "25_29"  !CDS_PN = "25_29";
"VIN2":   PN = "30"  !CDS_PN = "30";
"VOS":   PN = "1"  !CDS_PN = "1";
BODY = "Q_CAP","I20": #LOCATION = "PC149" !CDS_LOCATION = "PC149" &SEC = "1" #&CDS_SEC = "1";
"A":   PN = "1"  !CDS_PN = "1";
"B":   PN = "2"  !CDS_PN = "2";
BODY = "Q_RES","I21": #LOCATION = "PR526" !CDS_LOCATION = "PR526" &SEC = "1" #&CDS_SEC = "1";
"A":   PN = "1"  !CDS_PN = "1";
"B":   PN = "2"  !CDS_PN = "2";
BODY = "Q_CAP","I27": #LOCATION = "PC330_2" !CDS_LOCATION = "PC330_2" &SEC = "1" #&CDS_SEC = "1";
"A":   PN = "1"  !CDS_PN = "1";
"B":   PN = "2"  !CDS_PN = "2";
BODY = "Q_RES","I30": #LOCATION = "PR211" !CDS_LOCATION = "PR211" &SEC = "1" #&CDS_SEC = "1";
"A":   PN = "1"  !CDS_PN = "1";
"B":   PN = "2"  !CDS_PN = "2";
BODY = "Q_CAP","I32": #LOCATION = "PC317_7" !CDS_LOCATION = "PC317_7" &SEC = "1" #&CDS_SEC = "1";
"A":   PN = "1"  !CDS_PN = "1";
"B":   PN = "2"  !CDS_PN = "2";
BODY = "Q_RES","I35": #LOCATION = "PR207" !CDS_LOCATION = "PR207" &SEC = "1" #&CDS_SEC = "1";
"A":   PN = "1"  !CDS_PN = "1";
"B":   PN = "2"  !CDS_PN = "2";
BODY = "Q_CAP","I36": #LOCATION = "PC319" !CDS_LOCATION = "PC319" &SEC = "1" #&CDS_SEC = "1";
"A":   PN = "1"  !CDS_PN = "1";
"B":   PN = "2"  !CDS_PN = "2";
BODY = "Q_CAP","I41": #LOCATION = "PC321_SOP1_1" !CDS_LOCATION = "PC321_SOP1_1" &SEC = "1" #&CDS_SEC = "1";
"A":   PN = "1"  !CDS_PN = "1";
"B":   PN = "2"  !CDS_PN = "2";
BODY = "Q_CAP","I45": #LOCATION = "PC141" !CDS_LOCATION = "PC141" &SEC = "1" #&CDS_SEC = "1";
"A":   PN = "1"  !CDS_PN = "1";
"B":   PN = "2"  !CDS_PN = "2";
BODY = "Q_RES","I46": #LOCATION = "PR209" !CDS_LOCATION = "PR209" &SEC = "1" #&CDS_SEC = "1";
"A":   PN = "1"  !CDS_PN = "1";
"B":   PN = "2"  !CDS_PN = "2";
BODY = "Q_CAP","I49": #LOCATION = "PC329_1" !CDS_LOCATION = "PC329_1" &SEC = "1" #&CDS_SEC = "1";
"A":   PN = "1"  !CDS_PN = "1";
"B":   PN = "2"  !CDS_PN = "2";
BODY = "Q_CAP","I50": #LOCATION = "PC331_1" !CDS_LOCATION = "PC331_1" &SEC = "1" #&CDS_SEC = "1";
"A":   PN = "1"  !CDS_PN = "1";
"B":   PN = "2"  !CDS_PN = "2";
BODY = "Q_CAP","I54": #LOCATION = "PC334" !CDS_LOCATION = "PC334" &SEC = "1" #&CDS_SEC = "1";
"A":   PN = "1"  !CDS_PN = "1";
"B":   PN = "2"  !CDS_PN = "2";
BODY = "Q_CAP","I56": #LOCATION = "PC332_2" !CDS_LOCATION = "PC332_2" &SEC = "1" #&CDS_SEC = "1";
"A":   PN = "1"  !CDS_PN = "1";
"B":   PN = "2"  !CDS_PN = "2";
BODY = "Q_CAP","I57": #LOCATION = "PC335_2" !CDS_LOCATION = "PC335_2" &SEC = "1" #&CDS_SEC = "1";
"A":   PN = "1"  !CDS_PN = "1";
"B":   PN = "2"  !CDS_PN = "2";
BODY = "Q_CAPP","I59": #LOCATION = "PC337" !CDS_LOCATION = "PC337" &SEC = "1" #&CDS_SEC = "1";
"A":   PN = "1"  !CDS_PN = "1";
"B":   PN = "2"  !CDS_PN = "2";
BODY = "Q_CAP","I60": #LOCATION = "PC339_2" !CDS_LOCATION = "PC339_2" &SEC = "1" #&CDS_SEC = "1";
"A":   PN = "1"  !CDS_PN = "1";
"B":   PN = "2"  !CDS_PN = "2";
BODY = "Q_CAP","I62": #LOCATION = "PC342_2" !CDS_LOCATION = "PC342_2" &SEC = "1" #&CDS_SEC = "1";
"A":   PN = "1"  !CDS_PN = "1";
"B":   PN = "2"  !CDS_PN = "2";
BODY = "Q_CAP","I71": #LOCATION = "PC334_1" !CDS_LOCATION = "PC334_1" &SEC = "1" #&CDS_SEC = "1";
"A":   PN = "1"  !CDS_PN = "1";
"B":   PN = "2"  !CDS_PN = "2";
BODY = "Q_CAPP","I73": #LOCATION = "PC336" !CDS_LOCATION = "PC336" &SEC = "1" #&CDS_SEC = "1";
"A":   PN = "1"  !CDS_PN = "1";
"B":   PN = "2"  !CDS_PN = "2";
BODY = "Q_INDUCTOR","I74": #LOCATION = "PL37" !CDS_LOCATION = "PL37" &SEC = "1" #&CDS_SEC = "1";
"1":   PN = "1"  !CDS_PN = "1";
"2":   PN = "2"  !CDS_PN = "2";
BODY = "Q_CAP","I77": #LOCATION = "PC6007" !CDS_LOCATION = "PC6007" &SEC = "1" #&CDS_SEC = "1";
"A":   PN = "1"  !CDS_PN = "1";
"B":   PN = "2"  !CDS_PN = "2";
BODY = "Q_CAP","I80": #LOCATION = "PC341_1" !CDS_LOCATION = "PC341_1" &SEC = "1" #&CDS_SEC = "1";
"A":   PN = "1"  !CDS_PN = "1";
"B":   PN = "2"  !CDS_PN = "2";
BODY = "Q_RES","I85": #LOCATION = "PR212" !CDS_LOCATION = "PR212" &SEC = "1" #&CDS_SEC = "1";
"A":   PN = "1"  !CDS_PN = "1";
"B":   PN = "2"  !CDS_PN = "2";
BODY = "ISL99390FRZTR5935","I86": #LOCATION = "PU31" !CDS_LOCATION = "PU31" &SEC = "1" #&CDS_SEC = "1";
"AGND":   PN = "2"  !CDS_PN = "2";
"BOOT":   PN = "33"  !CDS_PN = "33";
"DNC":   PN = "31"  !CDS_PN = "31";
"EN":   PN = "35"  !CDS_PN = "35";
"GL1":   PN = "6"  !CDS_PN = "6";
"GL2":   PN = "41"  !CDS_PN = "41";
"IOUT":   PN = "38"  !CDS_PN = "38";
"LSET":   PN = "37"  !CDS_PN = "37";
"PGND1":   PN = "5"  !CDS_PN = "5";
"PGND2":   PN = "7_9-20_24"  !CDS_PN = "7_9-20_24";
"PGND3":   PN = "40"  !CDS_PN = "40";
"PHASE":   PN = "32"  !CDS_PN = "32";
"PVCC":   PN = "4"  !CDS_PN = "4";
"PWM":   PN = "34"  !CDS_PN = "34";
"REFIN":   PN = "39"  !CDS_PN = "39";
"SW":   PN = "10_19"  !CDS_PN = "10_19";
"TOUT_FLT":   PN = "36"  !CDS_PN = "36";
"VCC":   PN = "3"  !CDS_PN = "3";
"VIN1":   PN = "25_29"  !CDS_PN = "25_29";
"VIN2":   PN = "30"  !CDS_PN = "30";
"VOS":   PN = "1"  !CDS_PN = "1";
BODY = "Q_CAP","I87": #LOCATION = "PC8011" !CDS_LOCATION = "PC8011" &SEC = "1" #&CDS_SEC = "1";
"A":   PN = "1"  !CDS_PN = "1";
"B":   PN = "2"  !CDS_PN = "2";
BODY = "Q_CAP","I88": #LOCATION = "PC8012" !CDS_LOCATION = "PC8012" &SEC = "1" #&CDS_SEC = "1";
"A":   PN = "1"  !CDS_PN = "1";
"B":   PN = "2"  !CDS_PN = "2";
DRAWING = "@t6g_mb_lib.t6g(sch_1):page191";
BODY = "Q_RES","I7": #LOCATION = "PR214" !CDS_LOCATION = "PR214" &SEC = "1" #&CDS_SEC = "1";
"A":   PN = "1"  !CDS_PN = "1";
"B":   PN = "2"  !CDS_PN = "2";
BODY = "Q_CAP","I18": #LOCATION = "PC347_SOP1_3" !CDS_LOCATION = "PC347_SOP1_3" &SEC = "1" #&CDS_SEC = "1";
"A":   PN = "1"  !CDS_PN = "1";
"B":   PN = "2"  !CDS_PN = "2";
BODY = "Q_CAP","I20": #LOCATION = "PC349_3" !CDS_LOCATION = "PC349_3" &SEC = "1" #&CDS_SEC = "1";
"A":   PN = "1"  !CDS_PN = "1";
"B":   PN = "2"  !CDS_PN = "2";
BODY = "Q_RES","I21": #LOCATION = "PR215" !CDS_LOCATION = "PR215" &SEC = "1" #&CDS_SEC = "1";
"A":   PN = "1"  !CDS_PN = "1";
"B":   PN = "2"  !CDS_PN = "2";
BODY = "Q_CAP","I22": #LOCATION = "PC350_3" !CDS_LOCATION = "PC350_3" &SEC = "1" #&CDS_SEC = "1";
"A":   PN = "1"  !CDS_PN = "1";
"B":   PN = "2"  !CDS_PN = "2";
BODY = "Q_INDUCTOR","I25": #LOCATION = "PL34" !CDS_LOCATION = "PL34" &SEC = "1" #&CDS_SEC = "1";
"1":   PN = "1"  !CDS_PN = "1";
"2":   PN = "2"  !CDS_PN = "2";
BODY = "Q_INDUCTOR4P_14","I26": #LOCATION = "PL38" !CDS_LOCATION = "PL38" &SEC = "1" #&CDS_SEC = "1";
"1":   PN = "1"  !CDS_PN = "1";
"2":   PN = "2"  !CDS_PN = "2";
"3":   PN = "3"  !CDS_PN = "3";
"4":   PN = "4"  !CDS_PN = "4";
BODY = "Q_CAP","I31": #LOCATION = "PC351_3" !CDS_LOCATION = "PC351_3" &SEC = "1" #&CDS_SEC = "1";
"A":   PN = "1"  !CDS_PN = "1";
"B":   PN = "2"  !CDS_PN = "2";
BODY = "Q_CAP","I32": #LOCATION = "PC352_3" !CDS_LOCATION = "PC352_3" &SEC = "1" #&CDS_SEC = "1";
"A":   PN = "1"  !CDS_PN = "1";
"B":   PN = "2"  !CDS_PN = "2";
BODY = "Q_CAP","I34": #LOCATION = "PC353_3" !CDS_LOCATION = "PC353_3" &SEC = "1" #&CDS_SEC = "1";
"A":   PN = "1"  !CDS_PN = "1";
"B":   PN = "2"  !CDS_PN = "2";
BODY = "ISL99390FRZTR5935","I38": #LOCATION = "PU32" !CDS_LOCATION = "PU32" &SEC = "1" #&CDS_SEC = "1";
"AGND":   PN = "2"  !CDS_PN = "2";
"BOOT":   PN = "33"  !CDS_PN = "33";
"DNC":   PN = "31"  !CDS_PN = "31";
"EN":   PN = "35"  !CDS_PN = "35";
"GL1":   PN = "6"  !CDS_PN = "6";
"GL2":   PN = "41"  !CDS_PN = "41";
"IOUT":   PN = "38"  !CDS_PN = "38";
"LSET":   PN = "37"  !CDS_PN = "37";
"PGND1":   PN = "5"  !CDS_PN = "5";
"PGND2":   PN = "7_9-20_24"  !CDS_PN = "7_9-20_24";
"PGND3":   PN = "40"  !CDS_PN = "40";
"PHASE":   PN = "32"  !CDS_PN = "32";
"PVCC":   PN = "4"  !CDS_PN = "4";
"PWM":   PN = "34"  !CDS_PN = "34";
"REFIN":   PN = "39"  !CDS_PN = "39";
"SW":   PN = "10_19"  !CDS_PN = "10_19";
"TOUT_FLT":   PN = "36"  !CDS_PN = "36";
"VCC":   PN = "3"  !CDS_PN = "3";
"VIN1":   PN = "25_29"  !CDS_PN = "25_29";
"VIN2":   PN = "30"  !CDS_PN = "30";
"VOS":   PN = "1"  !CDS_PN = "1";
BODY = "Q_CAP","I2": #LOCATION = "PC345_9" !CDS_LOCATION = "PC345_9" &SEC = "1" #&CDS_SEC = "1";
"A":   PN = "1"  !CDS_PN = "1";
"B":   PN = "2"  !CDS_PN = "2";
BODY = "Q_RES","I10": #LOCATION = "PR511" !CDS_LOCATION = "PR511" &SEC = "1" #&CDS_SEC = "1";
"A":   PN = "1"  !CDS_PN = "1";
"B":   PN = "2"  !CDS_PN = "2";
BODY = "Q_CAP","I11": #LOCATION = "PC195" !CDS_LOCATION = "PC195" &SEC = "1" #&CDS_SEC = "1";
"A":   PN = "1"  !CDS_PN = "1";
"B":   PN = "2"  !CDS_PN = "2";
BODY = "Q_CAP","I13": #LOCATION = "PC346" !CDS_LOCATION = "PC346" &SEC = "1" #&CDS_SEC = "1";
"A":   PN = "1"  !CDS_PN = "1";
"B":   PN = "2"  !CDS_PN = "2";
BODY = "Q_RES","I14": #LOCATION = "PR213" !CDS_LOCATION = "PR213" &SEC = "1" #&CDS_SEC = "1";
"A":   PN = "1"  !CDS_PN = "1";
"B":   PN = "2"  !CDS_PN = "2";
BODY = "Q_CAP","I19": #LOCATION = "PC348_3" !CDS_LOCATION = "PC348_3" &SEC = "1" #&CDS_SEC = "1";
"A":   PN = "1"  !CDS_PN = "1";
"B":   PN = "2"  !CDS_PN = "2";
BODY = "Q_RES","I23": #LOCATION = "PR216" !CDS_LOCATION = "PR216" &SEC = "1" #&CDS_SEC = "1";
"A":   PN = "1"  !CDS_PN = "1";
"B":   PN = "2"  !CDS_PN = "2";
BODY = "Q_CAP","I28": #LOCATION = "PC354_3" !CDS_LOCATION = "PC354_3" &SEC = "1" #&CDS_SEC = "1";
"A":   PN = "1"  !CDS_PN = "1";
"B":   PN = "2"  !CDS_PN = "2";
BODY = "Q_CAP","I30": #LOCATION = "PC355_3" !CDS_LOCATION = "PC355_3" &SEC = "1" #&CDS_SEC = "1";
"A":   PN = "1"  !CDS_PN = "1";
"B":   PN = "2"  !CDS_PN = "2";
BODY = "Q_CAP","I33": #LOCATION = "PC353" !CDS_LOCATION = "PC353" &SEC = "1" #&CDS_SEC = "1";
"A":   PN = "1"  !CDS_PN = "1";
"B":   PN = "2"  !CDS_PN = "2";
DRAWING = "@t6g_mb_lib.t6g(sch_1):page193";
BODY = "Q_CAP","I2": #LOCATION = "PC373_2" !CDS_LOCATION = "PC373_2" &SEC = "1" #&CDS_SEC = "1";
"A":   PN = "1"  !CDS_PN = "1";
"B":   PN = "2"  !CDS_PN = "2";
BODY = "Q_RES","I14": #LOCATION = "PR257" !CDS_LOCATION = "PR257" &SEC = "1" #&CDS_SEC = "1";
"A":   PN = "1"  !CDS_PN = "1";
"B":   PN = "2"  !CDS_PN = "2";
BODY = "Q_CAP","I23": #LOCATION = "PC369" !CDS_LOCATION = "PC369" &SEC = "1" #&CDS_SEC = "1";
"A":   PN = "1"  !CDS_PN = "1";
"B":   PN = "2"  !CDS_PN = "2";
BODY = "Q_RES","I41": #LOCATION = "PR259" !CDS_LOCATION = "PR259" &SEC = "1" #&CDS_SEC = "1";
"A":   PN = "1"  !CDS_PN = "1";
"B":   PN = "2"  !CDS_PN = "2";
BODY = "Q_CAP","I46": #LOCATION = "PC382_2" !CDS_LOCATION = "PC382_2" &SEC = "1" #&CDS_SEC = "1";
"A":   PN = "1"  !CDS_PN = "1";
"B":   PN = "2"  !CDS_PN = "2";
BODY = "Q_CAPP","I65": #LOCATION = "PC106" !CDS_LOCATION = "PC106" &SEC = "1" #&CDS_SEC = "1";
"A":   PN = "1"  !CDS_PN = "1";
"B":   PN = "2"  !CDS_PN = "2";
BODY = "Q_CAPP","I66": #LOCATION = "PC387" !CDS_LOCATION = "PC387" &SEC = "1" #&CDS_SEC = "1";
"A":   PN = "1"  !CDS_PN = "1";
"B":   PN = "2"  !CDS_PN = "2";
BODY = "Q_CAPP","I67": #LOCATION = "PC388" !CDS_LOCATION = "PC388" &SEC = "1" #&CDS_SEC = "1";
"A":   PN = "1"  !CDS_PN = "1";
"B":   PN = "2"  !CDS_PN = "2";
BODY = "Q_CAPP","I74": #LOCATION = "PC391" !CDS_LOCATION = "PC391" &SEC = "1" #&CDS_SEC = "1";
"A":   PN = "1"  !CDS_PN = "1";
"B":   PN = "2"  !CDS_PN = "2";
BODY = "Q_RES","I87": #LOCATION = "PR342" !CDS_LOCATION = "PR342" &SEC = "1" #&CDS_SEC = "1";
"A":   PN = "1"  !CDS_PN = "1";
"B":   PN = "2"  !CDS_PN = "2";
BODY = "Q_RES","I4": #LOCATION = "PR254" !CDS_LOCATION = "PR254" &SEC = "1" #&CDS_SEC = "1";
"A":   PN = "1"  !CDS_PN = "1";
"B":   PN = "2"  !CDS_PN = "2";
BODY = "Q_CAP","I11": #LOCATION = "PC374_1" !CDS_LOCATION = "PC374_1" &SEC = "1" #&CDS_SEC = "1";
"A":   PN = "1"  !CDS_PN = "1";
"B":   PN = "2"  !CDS_PN = "2";
BODY = "Q_CAP","I12": #LOCATION = "PC370" !CDS_LOCATION = "PC370" &SEC = "1" #&CDS_SEC = "1";
"A":   PN = "1"  !CDS_PN = "1";
"B":   PN = "2"  !CDS_PN = "2";
BODY = "Q_CAP","I15": #LOCATION = "PC372_C1P1_2" !CDS_LOCATION = "PC372_C1P1_2" &SEC = "1" #&CDS_SEC = "1";
"A":   PN = "1"  !CDS_PN = "1";
"B":   PN = "2"  !CDS_PN = "2";
BODY = "Q_RES","I17": #LOCATION = "PR255" !CDS_LOCATION = "PR255" &SEC = "1" #&CDS_SEC = "1";
"A":   PN = "1"  !CDS_PN = "1";
"B":   PN = "2"  !CDS_PN = "2";
BODY = "Q_RES","I27": #LOCATION = "PR256" !CDS_LOCATION = "PR256" &SEC = "1" #&CDS_SEC = "1";
"A":   PN = "1"  !CDS_PN = "1";
"B":   PN = "2"  !CDS_PN = "2";
BODY = "Q_CAP","I29": #LOCATION = "PC371_C1P1_1" !CDS_LOCATION = "PC371_C1P1_1" &SEC = "1" #&CDS_SEC = "1";
"A":   PN = "1"  !CDS_PN = "1";
"B":   PN = "2"  !CDS_PN = "2";
BODY = "ISL99390FRZTR5935","I31": #LOCATION = "PU5" !CDS_LOCATION = "PU5" #SEC = "1" !CDS_SEC = "1";
"AGND":   PN = "2"  !CDS_PN = "2";
"BOOT":   PN = "33"  !CDS_PN = "33";
"DNC":   PN = "31"  !CDS_PN = "31";
"EN":   PN = "35"  !CDS_PN = "35";
"GL1":   PN = "6"  !CDS_PN = "6";
"GL2":   PN = "41"  !CDS_PN = "41";
"IOUT":   PN = "38"  !CDS_PN = "38";
"LSET":   PN = "37"  !CDS_PN = "37";
"PGND1":   PN = "5"  !CDS_PN = "5";
"PGND2":   PN = "7_9-20_24"  !CDS_PN = "7_9-20_24";
"PGND3":   PN = "40"  !CDS_PN = "40";
"PHASE":   PN = "32"  !CDS_PN = "32";
"PVCC":   PN = "4"  !CDS_PN = "4";
"PWM":   PN = "34"  !CDS_PN = "34";
"REFIN":   PN = "39"  !CDS_PN = "39";
"SW":   PN = "10_19"  !CDS_PN = "10_19";
"TOUT_FLT":   PN = "36"  !CDS_PN = "36";
"VCC":   PN = "3"  !CDS_PN = "3";
"VIN1":   PN = "25_29"  !CDS_PN = "25_29";
"VIN2":   PN = "30"  !CDS_PN = "30";
"VOS":   PN = "1"  !CDS_PN = "1";
BODY = "Q_CAP","I34": #LOCATION = "PC376_2" !CDS_LOCATION = "PC376_2" &SEC = "1" #&CDS_SEC = "1";
"A":   PN = "1"  !CDS_PN = "1";
"B":   PN = "2"  !CDS_PN = "2";
BODY = "Q_RES","I36": #LOCATION = "PR513" !CDS_LOCATION = "PR513" &SEC = "1" #&CDS_SEC = "1";
"A":   PN = "1"  !CDS_PN = "1";
"B":   PN = "2"  !CDS_PN = "2";
BODY = "Q_CAP","I37": #LOCATION = "PC202" !CDS_LOCATION = "PC202" &SEC = "1" #&CDS_SEC = "1";
"A":   PN = "1"  !CDS_PN = "1";
"B":   PN = "2"  !CDS_PN = "2";
BODY = "Q_RES","I38": #LOCATION = "PR260" !CDS_LOCATION = "PR260" &SEC = "1" #&CDS_SEC = "1";
"A":   PN = "1"  !CDS_PN = "1";
"B":   PN = "2"  !CDS_PN = "2";
BODY = "Q_CAP","I40": #LOCATION = "PC386" !CDS_LOCATION = "PC386" &SEC = "1" #&CDS_SEC = "1";
"A":   PN = "1"  !CDS_PN = "1";
"B":   PN = "2"  !CDS_PN = "2";
BODY = "Q_CAP","I42": #LOCATION = "PC378_2" !CDS_LOCATION = "PC378_2" &SEC = "1" #&CDS_SEC = "1";
"A":   PN = "1"  !CDS_PN = "1";
"B":   PN = "2"  !CDS_PN = "2";
BODY = "Q_CAP","I43": #LOCATION = "PC380_2" !CDS_LOCATION = "PC380_2" &SEC = "1" #&CDS_SEC = "1";
"A":   PN = "1"  !CDS_PN = "1";
"B":   PN = "2"  !CDS_PN = "2";
BODY = "Q_RES","I45": #LOCATION = "PR512" !CDS_LOCATION = "PR512" &SEC = "1" #&CDS_SEC = "1";
"A":   PN = "1"  !CDS_PN = "1";
"B":   PN = "2"  !CDS_PN = "2";
BODY = "Q_CAP","I48": #LOCATION = "PC385_2" !CDS_LOCATION = "PC385_2" &SEC = "1" #&CDS_SEC = "1";
"A":   PN = "1"  !CDS_PN = "1";
"B":   PN = "2"  !CDS_PN = "2";
BODY = "Q_CAP","I50": #LOCATION = "PC375_1" !CDS_LOCATION = "PC375_1" &SEC = "1" #&CDS_SEC = "1";
"A":   PN = "1"  !CDS_PN = "1";
"B":   PN = "2"  !CDS_PN = "2";
BODY = "Q_RES","I51": #LOCATION = "PR258" !CDS_LOCATION = "PR258" &SEC = "1" #&CDS_SEC = "1";
"A":   PN = "1"  !CDS_PN = "1";
"B":   PN = "2"  !CDS_PN = "2";
BODY = "Q_CAP","I52": #LOCATION = "PC201" !CDS_LOCATION = "PC201" &SEC = "1" #&CDS_SEC = "1";
"A":   PN = "1"  !CDS_PN = "1";
"B":   PN = "2"  !CDS_PN = "2";
BODY = "Q_CAP","I53": #LOCATION = "PC377_1" !CDS_LOCATION = "PC377_1" &SEC = "1" #&CDS_SEC = "1";
"A":   PN = "1"  !CDS_PN = "1";
"B":   PN = "2"  !CDS_PN = "2";
BODY = "Q_CAP","I54": #LOCATION = "PC379_1" !CDS_LOCATION = "PC379_1" &SEC = "1" #&CDS_SEC = "1";
"A":   PN = "1"  !CDS_PN = "1";
"B":   PN = "2"  !CDS_PN = "2";
BODY = "Q_CAP","I57": #LOCATION = "PC383" !CDS_LOCATION = "PC383" &SEC = "1" #&CDS_SEC = "1";
"A":   PN = "1"  !CDS_PN = "1";
"B":   PN = "2"  !CDS_PN = "2";
BODY = "Q_CAP","I58": #LOCATION = "PC381_1" !CDS_LOCATION = "PC381_1" &SEC = "1" #&CDS_SEC = "1";
"A":   PN = "1"  !CDS_PN = "1";
"B":   PN = "2"  !CDS_PN = "2";
BODY = "Q_CAP","I60": #LOCATION = "PC384_1" !CDS_LOCATION = "PC384_1" &SEC = "1" #&CDS_SEC = "1";
"A":   PN = "1"  !CDS_PN = "1";
"B":   PN = "2"  !CDS_PN = "2";
BODY = "Q_INDUCTOR4P_14","I62": #LOCATION = "PL41" !CDS_LOCATION = "PL41" &SEC = "1" #&CDS_SEC = "1";
"1":   PN = "1"  !CDS_PN = "1";
"2":   PN = "2"  !CDS_PN = "2";
"3":   PN = "3"  !CDS_PN = "3";
"4":   PN = "4"  !CDS_PN = "4";
BODY = "Q_RES","I64": #LOCATION = "PR261" !CDS_LOCATION = "PR261" &SEC = "1" #&CDS_SEC = "1";
"A":   PN = "1"  !CDS_PN = "1";
"B":   PN = "2"  !CDS_PN = "2";
BODY = "Q_CAP","I68": #LOCATION = "PC394_2" !CDS_LOCATION = "PC394_2" &SEC = "1" #&CDS_SEC = "1";
"A":   PN = "1"  !CDS_PN = "1";
"B":   PN = "2"  !CDS_PN = "2";
BODY = "Q_CAP","I70": #LOCATION = "PC397_2" !CDS_LOCATION = "PC397_2" &SEC = "1" #&CDS_SEC = "1";
"A":   PN = "1"  !CDS_PN = "1";
"B":   PN = "2"  !CDS_PN = "2";
BODY = "Q_CAPP","I73": #LOCATION = "PC389" !CDS_LOCATION = "PC389" &SEC = "1" #&CDS_SEC = "1";
"A":   PN = "1"  !CDS_PN = "1";
"B":   PN = "2"  !CDS_PN = "2";
BODY = "Q_INDUCTOR4P_14","I77": #LOCATION = "PL40" !CDS_LOCATION = "PL40" &SEC = "1" #&CDS_SEC = "1";
"1":   PN = "1"  !CDS_PN = "1";
"2":   PN = "2"  !CDS_PN = "2";
"3":   PN = "3"  !CDS_PN = "3";
"4":   PN = "4"  !CDS_PN = "4";
BODY = "Q_INDUCTOR","I79": #LOCATION = "PL42" !CDS_LOCATION = "PL42" &SEC = "1" #&CDS_SEC = "1";
"1":   PN = "1"  !CDS_PN = "1";
"2":   PN = "2"  !CDS_PN = "2";
BODY = "Q_CAP","I82": #LOCATION = "PC392" !CDS_LOCATION = "PC392" &SEC = "1" #&CDS_SEC = "1";
"A":   PN = "1"  !CDS_PN = "1";
"B":   PN = "2"  !CDS_PN = "2";
BODY = "Q_CAP","I83": #LOCATION = "PC375" !CDS_LOCATION = "PC375" &SEC = "1" #&CDS_SEC = "1";
"A":   PN = "1"  !CDS_PN = "1";
"B":   PN = "2"  !CDS_PN = "2";
BODY = "Q_CAP","I85": #LOCATION = "PC395_1" !CDS_LOCATION = "PC395_1" &SEC = "1" #&CDS_SEC = "1";
"A":   PN = "1"  !CDS_PN = "1";
"B":   PN = "2"  !CDS_PN = "2";
BODY = "Q_CAP","I86": #LOCATION = "PC398_1" !CDS_LOCATION = "PC398_1" &SEC = "1" #&CDS_SEC = "1";
"A":   PN = "1"  !CDS_PN = "1";
"B":   PN = "2"  !CDS_PN = "2";
BODY = "Q_RES","I89": #LOCATION = "PR340" !CDS_LOCATION = "PR340" &SEC = "1" #&CDS_SEC = "1";
"A":   PN = "1"  !CDS_PN = "1";
"B":   PN = "2"  !CDS_PN = "2";
BODY = "Q_RES","I90": #LOCATION = "PR341" !CDS_LOCATION = "PR341" &SEC = "1" #&CDS_SEC = "1";
"A":   PN = "1"  !CDS_PN = "1";
"B":   PN = "2"  !CDS_PN = "2";
BODY = "ISL99390FRZTR5935","I91": #LOCATION = "PU35" !CDS_LOCATION = "PU35" &SEC = "1" #&CDS_SEC = "1";
"AGND":   PN = "2"  !CDS_PN = "2";
"BOOT":   PN = "33"  !CDS_PN = "33";
"DNC":   PN = "31"  !CDS_PN = "31";
"EN":   PN = "35"  !CDS_PN = "35";
"GL1":   PN = "6"  !CDS_PN = "6";
"GL2":   PN = "41"  !CDS_PN = "41";
"IOUT":   PN = "38"  !CDS_PN = "38";
"LSET":   PN = "37"  !CDS_PN = "37";
"PGND1":   PN = "5"  !CDS_PN = "5";
"PGND2":   PN = "7_9-20_24"  !CDS_PN = "7_9-20_24";
"PGND3":   PN = "40"  !CDS_PN = "40";
"PHASE":   PN = "32"  !CDS_PN = "32";
"PVCC":   PN = "4"  !CDS_PN = "4";
"PWM":   PN = "34"  !CDS_PN = "34";
"REFIN":   PN = "39"  !CDS_PN = "39";
"SW":   PN = "10_19"  !CDS_PN = "10_19";
"TOUT_FLT":   PN = "36"  !CDS_PN = "36";
"VCC":   PN = "3"  !CDS_PN = "3";
"VIN1":   PN = "25_29"  !CDS_PN = "25_29";
"VIN2":   PN = "30"  !CDS_PN = "30";
"VOS":   PN = "1"  !CDS_PN = "1";
BODY = "Q_CAPP","I92": #LOCATION = "PC393" !CDS_LOCATION = "PC393" &SEC = "1" #&CDS_SEC = "1";
"A":   PN = "1"  !CDS_PN = "1";
"B":   PN = "2"  !CDS_PN = "2";
BODY = "Q_CAPP","I93": #LOCATION = "PC390" !CDS_LOCATION = "PC390" &SEC = "1" #&CDS_SEC = "1";
"A":   PN = "1"  !CDS_PN = "1";
"B":   PN = "2"  !CDS_PN = "2";
DRAWING = "@t6g_mb_lib.t6g(sch_1):page194";
BODY = "Q_CAP","I2": #LOCATION = "PC403_4" !CDS_LOCATION = "PC403_4" &SEC = "1" #&CDS_SEC = "1";
"A":   PN = "1"  !CDS_PN = "1";
"B":   PN = "2"  !CDS_PN = "2";
BODY = "Q_CAP","I37": #LOCATION = "PC205" !CDS_LOCATION = "PC205" &SEC = "1" #&CDS_SEC = "1";
"A":   PN = "1"  !CDS_PN = "1";
"B":   PN = "2"  !CDS_PN = "2";
BODY = "Q_RES","I38": #LOCATION = "PR268" !CDS_LOCATION = "PR268" &SEC = "1" #&CDS_SEC = "1";
"A":   PN = "1"  !CDS_PN = "1";
"B":   PN = "2"  !CDS_PN = "2";
BODY = "Q_CAP","I40": #LOCATION = "PC413" !CDS_LOCATION = "PC413" &SEC = "1" #&CDS_SEC = "1";
"A":   PN = "1"  !CDS_PN = "1";
"B":   PN = "2"  !CDS_PN = "2";
BODY = "Q_CAP","I42": #LOCATION = "PC409_4" !CDS_LOCATION = "PC409_4" &SEC = "1" #&CDS_SEC = "1";
"A":   PN = "1"  !CDS_PN = "1";
"B":   PN = "2"  !CDS_PN = "2";
BODY = "Q_INDUCTOR4P_14","I50": #LOCATION = "PL43" !CDS_LOCATION = "PL43" &SEC = "1" #&CDS_SEC = "1";
"1":   PN = "1"  !CDS_PN = "1";
"2":   PN = "2"  !CDS_PN = "2";
"3":   PN = "3"  !CDS_PN = "3";
"4":   PN = "4"  !CDS_PN = "4";
BODY = "Q_CAP","I55": #LOCATION = "PC410_3" !CDS_LOCATION = "PC410_3" &SEC = "1" #&CDS_SEC = "1";
"A":   PN = "1"  !CDS_PN = "1";
"B":   PN = "2"  !CDS_PN = "2";
BODY = "Q_RES","I4": #LOCATION = "PR262" !CDS_LOCATION = "PR262" &SEC = "1" #&CDS_SEC = "1";
"A":   PN = "1"  !CDS_PN = "1";
"B":   PN = "2"  !CDS_PN = "2";
BODY = "Q_CAP","I7": #LOCATION = "PC399" !CDS_LOCATION = "PC399" &SEC = "1" #&CDS_SEC = "1";
"A":   PN = "1"  !CDS_PN = "1";
"B":   PN = "2"  !CDS_PN = "2";
BODY = "Q_CAP","I12": #LOCATION = "PC404_3" !CDS_LOCATION = "PC404_3" &SEC = "1" #&CDS_SEC = "1";
"A":   PN = "1"  !CDS_PN = "1";
"B":   PN = "2"  !CDS_PN = "2";
BODY = "Q_RES","I13": #LOCATION = "PR264" !CDS_LOCATION = "PR264" &SEC = "1" #&CDS_SEC = "1";
"A":   PN = "1"  !CDS_PN = "1";
"B":   PN = "2"  !CDS_PN = "2";
BODY = "Q_CAP","I16": #LOCATION = "PC401_C1P1_4" !CDS_LOCATION = "PC401_C1P1_4" &SEC = "1" #&CDS_SEC = "1";
"A":   PN = "1"  !CDS_PN = "1";
"B":   PN = "2"  !CDS_PN = "2";
BODY = "Q_RES","I18": #LOCATION = "PR263" !CDS_LOCATION = "PR263" &SEC = "1" #&CDS_SEC = "1";
"A":   PN = "1"  !CDS_PN = "1";
"B":   PN = "2"  !CDS_PN = "2";
BODY = "ISL99390FRZTR5935","I21": #LOCATION = "PU36" !CDS_LOCATION = "PU36" &SEC = "1" #&CDS_SEC = "1";
"AGND":   PN = "2"  !CDS_PN = "2";
"BOOT":   PN = "33"  !CDS_PN = "33";
"DNC":   PN = "31"  !CDS_PN = "31";
"EN":   PN = "35"  !CDS_PN = "35";
"GL1":   PN = "6"  !CDS_PN = "6";
"GL2":   PN = "41"  !CDS_PN = "41";
"IOUT":   PN = "38"  !CDS_PN = "38";
"LSET":   PN = "37"  !CDS_PN = "37";
"PGND1":   PN = "5"  !CDS_PN = "5";
"PGND2":   PN = "7_9-20_24"  !CDS_PN = "7_9-20_24";
"PGND3":   PN = "40"  !CDS_PN = "40";
"PHASE":   PN = "32"  !CDS_PN = "32";
"PVCC":   PN = "4"  !CDS_PN = "4";
"PWM":   PN = "34"  !CDS_PN = "34";
"REFIN":   PN = "39"  !CDS_PN = "39";
"SW":   PN = "10_19"  !CDS_PN = "10_19";
"TOUT_FLT":   PN = "36"  !CDS_PN = "36";
"VCC":   PN = "3"  !CDS_PN = "3";
"VIN1":   PN = "25_29"  !CDS_PN = "25_29";
"VIN2":   PN = "30"  !CDS_PN = "30";
"VOS":   PN = "1"  !CDS_PN = "1";
BODY = "Q_CAP","I23": #LOCATION = "PC405_4" !CDS_LOCATION = "PC405_4" &SEC = "1" #&CDS_SEC = "1";
"A":   PN = "1"  !CDS_PN = "1";
"B":   PN = "2"  !CDS_PN = "2";
BODY = "Q_CAP","I27": #LOCATION = "PC400" !CDS_LOCATION = "PC400" &SEC = "1" #&CDS_SEC = "1";
"A":   PN = "1"  !CDS_PN = "1";
"B":   PN = "2"  !CDS_PN = "2";
BODY = "Q_RES","I29": #LOCATION = "PR265" !CDS_LOCATION = "PR265" &SEC = "1" #&CDS_SEC = "1";
"A":   PN = "1"  !CDS_PN = "1";
"B":   PN = "2"  !CDS_PN = "2";
BODY = "Q_CAP","I31": #LOCATION = "PC402_C1P1_3" !CDS_LOCATION = "PC402_C1P1_3" &SEC = "1" #&CDS_SEC = "1";
"A":   PN = "1"  !CDS_PN = "1";
"B":   PN = "2"  !CDS_PN = "2";
BODY = "Q_CAP","I33": #LOCATION = "PC408_3" !CDS_LOCATION = "PC408_3" &SEC = "1" #&CDS_SEC = "1";
"A":   PN = "1"  !CDS_PN = "1";
"B":   PN = "2"  !CDS_PN = "2";
BODY = "Q_RES","I35": #LOCATION = "PR515" !CDS_LOCATION = "PR515" &SEC = "1" #&CDS_SEC = "1";
"A":   PN = "1"  !CDS_PN = "1";
"B":   PN = "2"  !CDS_PN = "2";
BODY = "Q_RES","I36": #LOCATION = "PR266" !CDS_LOCATION = "PR266" &SEC = "1" #&CDS_SEC = "1";
"A":   PN = "1"  !CDS_PN = "1";
"B":   PN = "2"  !CDS_PN = "2";
BODY = "Q_CAP","I41": #LOCATION = "PC407_4" !CDS_LOCATION = "PC407_4" &SEC = "1" #&CDS_SEC = "1";
"A":   PN = "1"  !CDS_PN = "1";
"B":   PN = "2"  !CDS_PN = "2";
BODY = "Q_RES","I44": #LOCATION = "PR516" !CDS_LOCATION = "PR516" &SEC = "1" #&CDS_SEC = "1";
"A":   PN = "1"  !CDS_PN = "1";
"B":   PN = "2"  !CDS_PN = "2";
BODY = "Q_CAP","I45": #LOCATION = "PC411_4" !CDS_LOCATION = "PC411_4" &SEC = "1" #&CDS_SEC = "1";
"A":   PN = "1"  !CDS_PN = "1";
"B":   PN = "2"  !CDS_PN = "2";
BODY = "Q_CAP","I47": #LOCATION = "PC415_4" !CDS_LOCATION = "PC415_4" &SEC = "1" #&CDS_SEC = "1";
"A":   PN = "1"  !CDS_PN = "1";
"B":   PN = "2"  !CDS_PN = "2";
BODY = "Q_RES","I49": #LOCATION = "PR269" !CDS_LOCATION = "PR269" &SEC = "1" #&CDS_SEC = "1";
"A":   PN = "1"  !CDS_PN = "1";
"B":   PN = "2"  !CDS_PN = "2";
BODY = "Q_RES","I52": #LOCATION = "PR267" !CDS_LOCATION = "PR267" &SEC = "1" #&CDS_SEC = "1";
"A":   PN = "1"  !CDS_PN = "1";
"B":   PN = "2"  !CDS_PN = "2";
BODY = "Q_CAP","I53": #LOCATION = "PC206" !CDS_LOCATION = "PC206" &SEC = "1" #&CDS_SEC = "1";
"A":   PN = "1"  !CDS_PN = "1";
"B":   PN = "2"  !CDS_PN = "2";
BODY = "Q_CAP","I54": #LOCATION = "PC406_3" !CDS_LOCATION = "PC406_3" &SEC = "1" #&CDS_SEC = "1";
"A":   PN = "1"  !CDS_PN = "1";
"B":   PN = "2"  !CDS_PN = "2";
BODY = "Q_CAP","I57": #LOCATION = "PC414" !CDS_LOCATION = "PC414" &SEC = "1" #&CDS_SEC = "1";
"A":   PN = "1"  !CDS_PN = "1";
"B":   PN = "2"  !CDS_PN = "2";
BODY = "Q_CAP","I59": #LOCATION = "PC412_3" !CDS_LOCATION = "PC412_3" &SEC = "1" #&CDS_SEC = "1";
"A":   PN = "1"  !CDS_PN = "1";
"B":   PN = "2"  !CDS_PN = "2";
BODY = "Q_CAP","I60": #LOCATION = "PC416_3" !CDS_LOCATION = "PC416_3" &SEC = "1" #&CDS_SEC = "1";
"A":   PN = "1"  !CDS_PN = "1";
"B":   PN = "2"  !CDS_PN = "2";
BODY = "Q_INDUCTOR4P_14","I62": #LOCATION = "PL44" !CDS_LOCATION = "PL44" &SEC = "1" #&CDS_SEC = "1";
"1":   PN = "1"  !CDS_PN = "1";
"2":   PN = "2"  !CDS_PN = "2";
"3":   PN = "3"  !CDS_PN = "3";
"4":   PN = "4"  !CDS_PN = "4";
BODY = "Q_CAP","I64": #LOCATION = "PC417_3" !CDS_LOCATION = "PC417_3" &SEC = "1" #&CDS_SEC = "1";
"A":   PN = "1"  !CDS_PN = "1";
"B":   PN = "2"  !CDS_PN = "2";
BODY = "Q_CAP","I65": #LOCATION = "PC418_4" !CDS_LOCATION = "PC418_4" &SEC = "1" #&CDS_SEC = "1";
"A":   PN = "1"  !CDS_PN = "1";
"B":   PN = "2"  !CDS_PN = "2";
BODY = "Q_CAP","I67": #LOCATION = "PC420_4" !CDS_LOCATION = "PC420_4" &SEC = "1" #&CDS_SEC = "1";
"A":   PN = "1"  !CDS_PN = "1";
"B":   PN = "2"  !CDS_PN = "2";
BODY = "Q_CAP","I70": #LOCATION = "PC419_3" !CDS_LOCATION = "PC419_3" &SEC = "1" #&CDS_SEC = "1";
"A":   PN = "1"  !CDS_PN = "1";
"B":   PN = "2"  !CDS_PN = "2";
BODY = "ISL99390FRZTR5935","I72": #LOCATION = "PU37" !CDS_LOCATION = "PU37" &SEC = "1" #&CDS_SEC = "1";
"AGND":   PN = "2"  !CDS_PN = "2";
"BOOT":   PN = "33"  !CDS_PN = "33";
"DNC":   PN = "31"  !CDS_PN = "31";
"EN":   PN = "35"  !CDS_PN = "35";
"GL1":   PN = "6"  !CDS_PN = "6";
"GL2":   PN = "41"  !CDS_PN = "41";
"IOUT":   PN = "38"  !CDS_PN = "38";
"LSET":   PN = "37"  !CDS_PN = "37";
"PGND1":   PN = "5"  !CDS_PN = "5";
"PGND2":   PN = "7_9-20_24"  !CDS_PN = "7_9-20_24";
"PGND3":   PN = "40"  !CDS_PN = "40";
"PHASE":   PN = "32"  !CDS_PN = "32";
"PVCC":   PN = "4"  !CDS_PN = "4";
"PWM":   PN = "34"  !CDS_PN = "34";
"REFIN":   PN = "39"  !CDS_PN = "39";
"SW":   PN = "10_19"  !CDS_PN = "10_19";
"TOUT_FLT":   PN = "36"  !CDS_PN = "36";
"VCC":   PN = "3"  !CDS_PN = "3";
"VIN1":   PN = "25_29"  !CDS_PN = "25_29";
"VIN2":   PN = "30"  !CDS_PN = "30";
"VOS":   PN = "1"  !CDS_PN = "1";
DRAWING = "@t6g_mb_lib.t6g(sch_1):page195";
BODY = "Q_CAP","I31": #LOCATION = "PC423_C1P1_5" !CDS_LOCATION = "PC423_C1P1_5" &SEC = "1" #&CDS_SEC = "1";
"A":   PN = "1"  !CDS_PN = "1";
"B":   PN = "2"  !CDS_PN = "2";
BODY = "Q_RES","I39": #LOCATION = "PR428" !CDS_LOCATION = "PR428" &SEC = "1" #&CDS_SEC = "1";
"A":   PN = "1"  !CDS_PN = "1";
"B":   PN = "2"  !CDS_PN = "2";
BODY = "Q_CAP","I40": #LOCATION = "PC140_6" !CDS_LOCATION = "PC140_6" &SEC = "1" #&CDS_SEC = "1";
"A":   PN = "1"  !CDS_PN = "1";
"B":   PN = "2"  !CDS_PN = "2";
BODY = "Q_CAP","I60": #LOCATION = "PC427_5" !CDS_LOCATION = "PC427_5" &SEC = "1" #&CDS_SEC = "1";
"A":   PN = "1"  !CDS_PN = "1";
"B":   PN = "2"  !CDS_PN = "2";
BODY = "Q_CAP","I1": #LOCATION = "PC136_6" !CDS_LOCATION = "PC136_6" &SEC = "1" #&CDS_SEC = "1";
"A":   PN = "1"  !CDS_PN = "1";
"B":   PN = "2"  !CDS_PN = "2";
BODY = "Q_RES","I4": #LOCATION = "PR426" !CDS_LOCATION = "PR426" &SEC = "1" #&CDS_SEC = "1";
"A":   PN = "1"  !CDS_PN = "1";
"B":   PN = "2"  !CDS_PN = "2";
BODY = "Q_CAP","I10": #LOCATION = "PC422_5" !CDS_LOCATION = "PC422_5" &SEC = "1" #&CDS_SEC = "1";
"A":   PN = "1"  !CDS_PN = "1";
"B":   PN = "2"  !CDS_PN = "2";
BODY = "Q_CAP","I12": #LOCATION = "PC138" !CDS_LOCATION = "PC138" &SEC = "1" #&CDS_SEC = "1";
"A":   PN = "1"  !CDS_PN = "1";
"B":   PN = "2"  !CDS_PN = "2";
BODY = "Q_RES","I13": #LOCATION = "PR427" !CDS_LOCATION = "PR427" &SEC = "1" #&CDS_SEC = "1";
"A":   PN = "1"  !CDS_PN = "1";
"B":   PN = "2"  !CDS_PN = "2";
BODY = "Q_RES","I15": #LOCATION = "PR270" !CDS_LOCATION = "PR270" &SEC = "1" #&CDS_SEC = "1";
"A":   PN = "1"  !CDS_PN = "1";
"B":   PN = "2"  !CDS_PN = "2";
BODY = "ISL99390FRZTR5935","I19": #LOCATION = "PU33" !CDS_LOCATION = "PU33" &SEC = "1" #&CDS_SEC = "1";
"AGND":   PN = "2"  !CDS_PN = "2";
"BOOT":   PN = "33"  !CDS_PN = "33";
"DNC":   PN = "31"  !CDS_PN = "31";
"EN":   PN = "35"  !CDS_PN = "35";
"GL1":   PN = "6"  !CDS_PN = "6";
"GL2":   PN = "41"  !CDS_PN = "41";
"IOUT":   PN = "38"  !CDS_PN = "38";
"LSET":   PN = "37"  !CDS_PN = "37";
"PGND1":   PN = "5"  !CDS_PN = "5";
"PGND2":   PN = "7_9-20_24"  !CDS_PN = "7_9-20_24";
"PGND3":   PN = "40"  !CDS_PN = "40";
"PHASE":   PN = "32"  !CDS_PN = "32";
"PVCC":   PN = "4"  !CDS_PN = "4";
"PWM":   PN = "34"  !CDS_PN = "34";
"REFIN":   PN = "39"  !CDS_PN = "39";
"SW":   PN = "10_19"  !CDS_PN = "10_19";
"TOUT_FLT":   PN = "36"  !CDS_PN = "36";
"VCC":   PN = "3"  !CDS_PN = "3";
"VIN1":   PN = "25_29"  !CDS_PN = "25_29";
"VIN2":   PN = "30"  !CDS_PN = "30";
"VOS":   PN = "1"  !CDS_PN = "1";
BODY = "Q_CAP","I22": #LOCATION = "PC139_C1P1_6" !CDS_LOCATION = "PC139_C1P1_6" &SEC = "1" #&CDS_SEC = "1";
"A":   PN = "1"  !CDS_PN = "1";
"B":   PN = "2"  !CDS_PN = "2";
BODY = "Q_CAP","I27": #LOCATION = "PC421" !CDS_LOCATION = "PC421" &SEC = "1" #&CDS_SEC = "1";
"A":   PN = "1"  !CDS_PN = "1";
"B":   PN = "2"  !CDS_PN = "2";
BODY = "Q_RES","I28": #LOCATION = "PR271" !CDS_LOCATION = "PR271" &SEC = "1" #&CDS_SEC = "1";
"A":   PN = "1"  !CDS_PN = "1";
"B":   PN = "2"  !CDS_PN = "2";
BODY = "Q_RES","I33": #LOCATION = "PR518" !CDS_LOCATION = "PR518" &SEC = "1" #&CDS_SEC = "1";
"A":   PN = "1"  !CDS_PN = "1";
"B":   PN = "2"  !CDS_PN = "2";
BODY = "Q_CAP","I34": #LOCATION = "PC208" !CDS_LOCATION = "PC208" &SEC = "1" #&CDS_SEC = "1";
"A":   PN = "1"  !CDS_PN = "1";
"B":   PN = "2"  !CDS_PN = "2";
BODY = "Q_RES","I35": #LOCATION = "PR429" !CDS_LOCATION = "PR429" &SEC = "1" #&CDS_SEC = "1";
"A":   PN = "1"  !CDS_PN = "1";
"B":   PN = "2"  !CDS_PN = "2";
BODY = "Q_INDUCTOR","I37": #LOCATION = "PL39" !CDS_LOCATION = "PL39" &SEC = "1" #&CDS_SEC = "1";
"1":   PN = "1"  !CDS_PN = "1";
"2":   PN = "2"  !CDS_PN = "2";
BODY = "Q_CAP","I38": #LOCATION = "PC141_6" !CDS_LOCATION = "PC141_6" &SEC = "1" #&CDS_SEC = "1";
"A":   PN = "1"  !CDS_PN = "1";
"B":   PN = "2"  !CDS_PN = "2";
BODY = "Q_CAP","I41": #LOCATION = "PC144_6" !CDS_LOCATION = "PC144_6" &SEC = "1" #&CDS_SEC = "1";
"A":   PN = "1"  !CDS_PN = "1";
"B":   PN = "2"  !CDS_PN = "2";
BODY = "Q_RES","I43": #LOCATION = "PR517" !CDS_LOCATION = "PR517" &SEC = "1" #&CDS_SEC = "1";
"A":   PN = "1"  !CDS_PN = "1";
"B":   PN = "2"  !CDS_PN = "2";
BODY = "Q_CAP","I44": #LOCATION = "PC145_6" !CDS_LOCATION = "PC145_6" &SEC = "1" #&CDS_SEC = "1";
"A":   PN = "1"  !CDS_PN = "1";
"B":   PN = "2"  !CDS_PN = "2";
BODY = "Q_CAP","I45": #LOCATION = "PC146" !CDS_LOCATION = "PC146" &SEC = "1" #&CDS_SEC = "1";
"A":   PN = "1"  !CDS_PN = "1";
"B":   PN = "2"  !CDS_PN = "2";
BODY = "Q_CAP","I47": #LOCATION = "PC147_6" !CDS_LOCATION = "PC147_6" &SEC = "1" #&CDS_SEC = "1";
"A":   PN = "1"  !CDS_PN = "1";
"B":   PN = "2"  !CDS_PN = "2";
BODY = "Q_RES","I49": #LOCATION = "PR273" !CDS_LOCATION = "PR273" &SEC = "1" #&CDS_SEC = "1";
"A":   PN = "1"  !CDS_PN = "1";
"B":   PN = "2"  !CDS_PN = "2";
BODY = "Q_INDUCTOR4P_14","I50": #LOCATION = "PL69" !CDS_LOCATION = "PL69" &SEC = "1" #&CDS_SEC = "1";
"1":   PN = "1"  !CDS_PN = "1";
"2":   PN = "2"  !CDS_PN = "2";
"3":   PN = "3"  !CDS_PN = "3";
"4":   PN = "4"  !CDS_PN = "4";
BODY = "Q_RES","I52": #LOCATION = "PR272" !CDS_LOCATION = "PR272" &SEC = "1" #&CDS_SEC = "1";
"A":   PN = "1"  !CDS_PN = "1";
"B":   PN = "2"  !CDS_PN = "2";
BODY = "Q_CAP","I53": #LOCATION = "PC207" !CDS_LOCATION = "PC207" &SEC = "1" #&CDS_SEC = "1";
"A":   PN = "1"  !CDS_PN = "1";
"B":   PN = "2"  !CDS_PN = "2";
BODY = "Q_CAP","I54": #LOCATION = "PC425_5" !CDS_LOCATION = "PC425_5" &SEC = "1" #&CDS_SEC = "1";
"A":   PN = "1"  !CDS_PN = "1";
"B":   PN = "2"  !CDS_PN = "2";
BODY = "Q_CAP","I55": #LOCATION = "PC424_5" !CDS_LOCATION = "PC424_5" &SEC = "1" #&CDS_SEC = "1";
"A":   PN = "1"  !CDS_PN = "1";
"B":   PN = "2"  !CDS_PN = "2";
BODY = "Q_CAP","I56": #LOCATION = "PC426_5" !CDS_LOCATION = "PC426_5" &SEC = "1" #&CDS_SEC = "1";
"A":   PN = "1"  !CDS_PN = "1";
"B":   PN = "2"  !CDS_PN = "2";
BODY = "Q_CAP","I57": #LOCATION = "PC428" !CDS_LOCATION = "PC428" &SEC = "1" #&CDS_SEC = "1";
"A":   PN = "1"  !CDS_PN = "1";
"B":   PN = "2"  !CDS_PN = "2";
BODY = "Q_CAP","I61": #LOCATION = "PC429_5" !CDS_LOCATION = "PC429_5" &SEC = "1" #&CDS_SEC = "1";
"A":   PN = "1"  !CDS_PN = "1";
"B":   PN = "2"  !CDS_PN = "2";
BODY = "Q_INDUCTOR4P_14","I63": #LOCATION = "PL45" !CDS_LOCATION = "PL45" &SEC = "1" #&CDS_SEC = "1";
"1":   PN = "1"  !CDS_PN = "1";
"2":   PN = "2"  !CDS_PN = "2";
"3":   PN = "3"  !CDS_PN = "3";
"4":   PN = "4"  !CDS_PN = "4";
BODY = "Q_CAP","I65": #LOCATION = "PC148_6" !CDS_LOCATION = "PC148_6" &SEC = "1" #&CDS_SEC = "1";
"A":   PN = "1"  !CDS_PN = "1";
"B":   PN = "2"  !CDS_PN = "2";
BODY = "Q_CAP","I67": #LOCATION = "PC149_6" !CDS_LOCATION = "PC149_6" &SEC = "1" #&CDS_SEC = "1";
"A":   PN = "1"  !CDS_PN = "1";
"B":   PN = "2"  !CDS_PN = "2";
BODY = "Q_CAP","I70": #LOCATION = "PC430_5" !CDS_LOCATION = "PC430_5" &SEC = "1" #&CDS_SEC = "1";
"A":   PN = "1"  !CDS_PN = "1";
"B":   PN = "2"  !CDS_PN = "2";
BODY = "Q_CAP","I71": #LOCATION = "PC431_5" !CDS_LOCATION = "PC431_5" &SEC = "1" #&CDS_SEC = "1";
"A":   PN = "1"  !CDS_PN = "1";
"B":   PN = "2"  !CDS_PN = "2";
BODY = "ISL99390FRZTR5935","I73": #LOCATION = "PU38" !CDS_LOCATION = "PU38" &SEC = "1" #&CDS_SEC = "1";
"AGND":   PN = "2"  !CDS_PN = "2";
"BOOT":   PN = "33"  !CDS_PN = "33";
"DNC":   PN = "31"  !CDS_PN = "31";
"EN":   PN = "35"  !CDS_PN = "35";
"GL1":   PN = "6"  !CDS_PN = "6";
"GL2":   PN = "41"  !CDS_PN = "41";
"IOUT":   PN = "38"  !CDS_PN = "38";
"LSET":   PN = "37"  !CDS_PN = "37";
"PGND1":   PN = "5"  !CDS_PN = "5";
"PGND2":   PN = "7_9-20_24"  !CDS_PN = "7_9-20_24";
"PGND3":   PN = "40"  !CDS_PN = "40";
"PHASE":   PN = "32"  !CDS_PN = "32";
"PVCC":   PN = "4"  !CDS_PN = "4";
"PWM":   PN = "34"  !CDS_PN = "34";
"REFIN":   PN = "39"  !CDS_PN = "39";
"SW":   PN = "10_19"  !CDS_PN = "10_19";
"TOUT_FLT":   PN = "36"  !CDS_PN = "36";
"VCC":   PN = "3"  !CDS_PN = "3";
"VIN1":   PN = "25_29"  !CDS_PN = "25_29";
"VIN2":   PN = "30"  !CDS_PN = "30";
"VOS":   PN = "1"  !CDS_PN = "1";
DRAWING = "@t6g_mb_lib.t6g(sch_1):page198";
BODY = "Q_CAP","I2": #LOCATION = "PC621_10" !CDS_LOCATION = "PC621_10" &SEC = "1" #&CDS_SEC = "1";
"A":   PN = "1"  !CDS_PN = "1";
"B":   PN = "2"  !CDS_PN = "2";
BODY = "ISL99390FRZTR5935","I15": #LOCATION = "PU53" !CDS_LOCATION = "PU53" &SEC = "1" #&CDS_SEC = "1";
"AGND":   PN = "2"  !CDS_PN = "2";
"BOOT":   PN = "33"  !CDS_PN = "33";
"DNC":   PN = "31"  !CDS_PN = "31";
"EN":   PN = "35"  !CDS_PN = "35";
"GL1":   PN = "6"  !CDS_PN = "6";
"GL2":   PN = "41"  !CDS_PN = "41";
"IOUT":   PN = "38"  !CDS_PN = "38";
"LSET":   PN = "37"  !CDS_PN = "37";
"PGND1":   PN = "5"  !CDS_PN = "5";
"PGND2":   PN = "7_9-20_24"  !CDS_PN = "7_9-20_24";
"PGND3":   PN = "40"  !CDS_PN = "40";
"PHASE":   PN = "32"  !CDS_PN = "32";
"PVCC":   PN = "4"  !CDS_PN = "4";
"PWM":   PN = "34"  !CDS_PN = "34";
"REFIN":   PN = "39"  !CDS_PN = "39";
"SW":   PN = "10_19"  !CDS_PN = "10_19";
"TOUT_FLT":   PN = "36"  !CDS_PN = "36";
"VCC":   PN = "3"  !CDS_PN = "3";
"VIN1":   PN = "25_29"  !CDS_PN = "25_29";
"VIN2":   PN = "30"  !CDS_PN = "30";
"VOS":   PN = "1"  !CDS_PN = "1";
BODY = "Q_CAP","I28": #LOCATION = "PC617" !CDS_LOCATION = "PC617" &SEC = "1" #&CDS_SEC = "1";
"A":   PN = "1"  !CDS_PN = "1";
"B":   PN = "2"  !CDS_PN = "2";
BODY = "Q_CAP","I44": #LOCATION = "PC630" !CDS_LOCATION = "PC630" &SEC = "1" #&CDS_SEC = "1";
"A":   PN = "1"  !CDS_PN = "1";
"B":   PN = "2"  !CDS_PN = "2";
BODY = "Q_CAP","I46": #LOCATION = "PC629_4" !CDS_LOCATION = "PC629_4" &SEC = "1" #&CDS_SEC = "1";
"A":   PN = "1"  !CDS_PN = "1";
"B":   PN = "2"  !CDS_PN = "2";
BODY = "Q_CAP","I51": #LOCATION = "PC634_4" !CDS_LOCATION = "PC634_4" &SEC = "1" #&CDS_SEC = "1";
"A":   PN = "1"  !CDS_PN = "1";
"B":   PN = "2"  !CDS_PN = "2";
BODY = "Q_RES","I55": #LOCATION = "PR374" !CDS_LOCATION = "PR374" &SEC = "1" #&CDS_SEC = "1";
"A":   PN = "1"  !CDS_PN = "1";
"B":   PN = "2"  !CDS_PN = "2";
BODY = "Q_RES","I57": #LOCATION = "PR492" !CDS_LOCATION = "PR492" &SEC = "1" #&CDS_SEC = "1";
"A":   PN = "1"  !CDS_PN = "1";
"B":   PN = "2"  !CDS_PN = "2";
BODY = "Q_CAP","I65": #LOCATION = "PC632_3" !CDS_LOCATION = "PC632_3" &SEC = "1" #&CDS_SEC = "1";
"A":   PN = "1"  !CDS_PN = "1";
"B":   PN = "2"  !CDS_PN = "2";
BODY = "Q_CAP","I68": #LOCATION = "PC635_3" !CDS_LOCATION = "PC635_3" &SEC = "1" #&CDS_SEC = "1";
"A":   PN = "1"  !CDS_PN = "1";
"B":   PN = "2"  !CDS_PN = "2";
BODY = "Q_RES","I4": #LOCATION = "PR368" !CDS_LOCATION = "PR368" &SEC = "1" #&CDS_SEC = "1";
"A":   PN = "1"  !CDS_PN = "1";
"B":   PN = "2"  !CDS_PN = "2";
BODY = "Q_CAP","I10": #LOCATION = "PC616" !CDS_LOCATION = "PC616" &SEC = "1" #&CDS_SEC = "1";
"A":   PN = "1"  !CDS_PN = "1";
"B":   PN = "2"  !CDS_PN = "2";
BODY = "Q_RES","I12": #LOCATION = "PR370" !CDS_LOCATION = "PR370" &SEC = "1" #&CDS_SEC = "1";
"A":   PN = "1"  !CDS_PN = "1";
"B":   PN = "2"  !CDS_PN = "2";
BODY = "Q_CAP","I13": #LOCATION = "PC618_IOP1_4" !CDS_LOCATION = "PC618_IOP1_4" &SEC = "1" #&CDS_SEC = "1";
"A":   PN = "1"  !CDS_PN = "1";
"B":   PN = "2"  !CDS_PN = "2";
BODY = "Q_RES","I17": #LOCATION = "PR372" !CDS_LOCATION = "PR372" &SEC = "1" #&CDS_SEC = "1";
"A":   PN = "1"  !CDS_PN = "1";
"B":   PN = "2"  !CDS_PN = "2";
BODY = "Q_CAP","I18": #LOCATION = "PC623_4" !CDS_LOCATION = "PC623_4" &SEC = "1" #&CDS_SEC = "1";
"A":   PN = "1"  !CDS_PN = "1";
"B":   PN = "2"  !CDS_PN = "2";
BODY = "Q_CAP","I20": #LOCATION = "PC620_9" !CDS_LOCATION = "PC620_9" &SEC = "1" #&CDS_SEC = "1";
"A":   PN = "1"  !CDS_PN = "1";
"B":   PN = "2"  !CDS_PN = "2";
BODY = "Q_RES","I22": #LOCATION = "PR369" !CDS_LOCATION = "PR369" &SEC = "1" #&CDS_SEC = "1";
"A":   PN = "1"  !CDS_PN = "1";
"B":   PN = "2"  !CDS_PN = "2";
BODY = "Q_RES","I29": #LOCATION = "PR371" !CDS_LOCATION = "PR371" &SEC = "1" #&CDS_SEC = "1";
"A":   PN = "1"  !CDS_PN = "1";
"B":   PN = "2"  !CDS_PN = "2";
BODY = "Q_CAP","I31": #LOCATION = "PC619_IOP1_3" !CDS_LOCATION = "PC619_IOP1_3" &SEC = "1" #&CDS_SEC = "1";
"A":   PN = "1"  !CDS_PN = "1";
"B":   PN = "2"  !CDS_PN = "2";
BODY = "Q_RES","I34": #LOCATION = "PR373" !CDS_LOCATION = "PR373" &SEC = "1" #&CDS_SEC = "1";
"A":   PN = "1"  !CDS_PN = "1";
"B":   PN = "2"  !CDS_PN = "2";
BODY = "Q_CAP","I35": #LOCATION = "PC622_3" !CDS_LOCATION = "PC622_3" &SEC = "1" #&CDS_SEC = "1";
"A":   PN = "1"  !CDS_PN = "1";
"B":   PN = "2"  !CDS_PN = "2";
BODY = "Q_CAP","I36": #LOCATION = "PC624_3" !CDS_LOCATION = "PC624_3" &SEC = "1" #&CDS_SEC = "1";
"A":   PN = "1"  !CDS_PN = "1";
"B":   PN = "2"  !CDS_PN = "2";
BODY = "Q_CAP","I37": #LOCATION = "PC176" !CDS_LOCATION = "PC176" &SEC = "1" #&CDS_SEC = "1";
"A":   PN = "1"  !CDS_PN = "1";
"B":   PN = "2"  !CDS_PN = "2";
BODY = "Q_RES","I39": #LOCATION = "PR491" !CDS_LOCATION = "PR491" &SEC = "1" #&CDS_SEC = "1";
"A":   PN = "1"  !CDS_PN = "1";
"B":   PN = "2"  !CDS_PN = "2";
BODY = "Q_RES","I41": #LOCATION = "PR375" !CDS_LOCATION = "PR375" &SEC = "1" #&CDS_SEC = "1";
"A":   PN = "1"  !CDS_PN = "1";
"B":   PN = "2"  !CDS_PN = "2";
BODY = "Q_INDUCTOR4P_14","I42": #LOCATION = "PL67" !CDS_LOCATION = "PL67" &SEC = "1" #&CDS_SEC = "1";
"1":   PN = "1"  !CDS_PN = "1";
"2":   PN = "2"  !CDS_PN = "2";
"3":   PN = "3"  !CDS_PN = "3";
"4":   PN = "4"  !CDS_PN = "4";
BODY = "Q_INDUCTOR","I43": #LOCATION = "PL46" !CDS_LOCATION = "PL46" &SEC = "1" #&CDS_SEC = "1";
"1":   PN = "1"  !CDS_PN = "1";
"2":   PN = "2"  !CDS_PN = "2";
BODY = "Q_CAP","I45": #LOCATION = "PC625_4" !CDS_LOCATION = "PC625_4" &SEC = "1" #&CDS_SEC = "1";
"A":   PN = "1"  !CDS_PN = "1";
"B":   PN = "2"  !CDS_PN = "2";
BODY = "Q_CAP","I48": #LOCATION = "PC633_4" !CDS_LOCATION = "PC633_4" &SEC = "1" #&CDS_SEC = "1";
"A":   PN = "1"  !CDS_PN = "1";
"B":   PN = "2"  !CDS_PN = "2";
BODY = "Q_CAP","I53": #LOCATION = "PC636_4" !CDS_LOCATION = "PC636_4" &SEC = "1" #&CDS_SEC = "1";
"A":   PN = "1"  !CDS_PN = "1";
"B":   PN = "2"  !CDS_PN = "2";
BODY = "Q_CAP","I58": #LOCATION = "PC177" !CDS_LOCATION = "PC177" &SEC = "1" #&CDS_SEC = "1";
"A":   PN = "1"  !CDS_PN = "1";
"B":   PN = "2"  !CDS_PN = "2";
BODY = "Q_CAP","I60": #LOCATION = "PC626_3" !CDS_LOCATION = "PC626_3" &SEC = "1" #&CDS_SEC = "1";
"A":   PN = "1"  !CDS_PN = "1";
"B":   PN = "2"  !CDS_PN = "2";
BODY = "Q_CAP","I61": #LOCATION = "PC628_3" !CDS_LOCATION = "PC628_3" &SEC = "1" #&CDS_SEC = "1";
"A":   PN = "1"  !CDS_PN = "1";
"B":   PN = "2"  !CDS_PN = "2";
BODY = "Q_INDUCTOR4P_14","I62": #LOCATION = "PL68" !CDS_LOCATION = "PL68" &SEC = "1" #&CDS_SEC = "1";
"1":   PN = "1"  !CDS_PN = "1";
"2":   PN = "2"  !CDS_PN = "2";
"3":   PN = "3"  !CDS_PN = "3";
"4":   PN = "4"  !CDS_PN = "4";
BODY = "Q_CAP","I63": #LOCATION = "PC631" !CDS_LOCATION = "PC631" &SEC = "1" #&CDS_SEC = "1";
"A":   PN = "1"  !CDS_PN = "1";
"B":   PN = "2"  !CDS_PN = "2";
BODY = "Q_CAP","I70": #LOCATION = "PC637_3" !CDS_LOCATION = "PC637_3" &SEC = "1" #&CDS_SEC = "1";
"A":   PN = "1"  !CDS_PN = "1";
"B":   PN = "2"  !CDS_PN = "2";
BODY = "Q_CAP","I72": #LOCATION = "PC627_4" !CDS_LOCATION = "PC627_4" &SEC = "1" #&CDS_SEC = "1";
"A":   PN = "1"  !CDS_PN = "1";
"B":   PN = "2"  !CDS_PN = "2";
BODY = "ISL99390FRZTR5935","I73": #LOCATION = "PU52" !CDS_LOCATION = "PU52" &SEC = "1" #&CDS_SEC = "1";
"AGND":   PN = "2"  !CDS_PN = "2";
"BOOT":   PN = "33"  !CDS_PN = "33";
"DNC":   PN = "31"  !CDS_PN = "31";
"EN":   PN = "35"  !CDS_PN = "35";
"GL1":   PN = "6"  !CDS_PN = "6";
"GL2":   PN = "41"  !CDS_PN = "41";
"IOUT":   PN = "38"  !CDS_PN = "38";
"LSET":   PN = "37"  !CDS_PN = "37";
"PGND1":   PN = "5"  !CDS_PN = "5";
"PGND2":   PN = "7_9-20_24"  !CDS_PN = "7_9-20_24";
"PGND3":   PN = "40"  !CDS_PN = "40";
"PHASE":   PN = "32"  !CDS_PN = "32";
"PVCC":   PN = "4"  !CDS_PN = "4";
"PWM":   PN = "34"  !CDS_PN = "34";
"REFIN":   PN = "39"  !CDS_PN = "39";
"SW":   PN = "10_19"  !CDS_PN = "10_19";
"TOUT_FLT":   PN = "36"  !CDS_PN = "36";
"VCC":   PN = "3"  !CDS_PN = "3";
"VIN1":   PN = "25_29"  !CDS_PN = "25_29";
"VIN2":   PN = "30"  !CDS_PN = "30";
"VOS":   PN = "1"  !CDS_PN = "1";
DRAWING = "@t6g_mb_lib.t6g(sch_1):page245";
BODY = "Q_RES","I2": #LOCATION = "R3118" !CDS_LOCATION = "R3118" &SEC = "1" #&CDS_SEC = "1";
"A":   PN = "1"  !CDS_PN = "1";
"B":   PN = "2"  !CDS_PN = "2";
BODY = "Q_RES","I4": #LOCATION = "R3117" !CDS_LOCATION = "R3117" &SEC = "1" #&CDS_SEC = "1";
"A":   PN = "1"  !CDS_PN = "1";
"B":   PN = "2"  !CDS_PN = "2";
BODY = "Q_CAP","I8": #LOCATION = "PC1870" !CDS_LOCATION = "PC1870" &SEC = "1" #&CDS_SEC = "1";
"A":   PN = "1"  !CDS_PN = "1";
"B":   PN = "2"  !CDS_PN = "2";
BODY = "Q_RES","I11": #LOCATION = "R1571" !CDS_LOCATION = "R1571" &SEC = "1" #&CDS_SEC = "1";
"A":   PN = "1"  !CDS_PN = "1";
"B":   PN = "2"  !CDS_PN = "2";
BODY = "Q_RES","I15": #LOCATION = "PR833" !CDS_LOCATION = "PR833" &SEC = "1" #&CDS_SEC = "1";
"A":   PN = "1"  !CDS_PN = "1";
"B":   PN = "2"  !CDS_PN = "2";
BODY = "Q_RES","I17": #LOCATION = "PR834" !CDS_LOCATION = "PR834" &SEC = "1" #&CDS_SEC = "1";
"A":   PN = "1"  !CDS_PN = "1";
"B":   PN = "2"  !CDS_PN = "2";
BODY = "Q_RES","I20": #LOCATION = "PR8389" !CDS_LOCATION = "PR8389" &SEC = "1" #&CDS_SEC = "1";
"A":   PN = "1"  !CDS_PN = "1";
"B":   PN = "2"  !CDS_PN = "2";
BODY = "NCP3284AMNTXG","I21": #LOCATION = "PU9" !CDS_LOCATION = "PU9" &SEC = "1" #&CDS_SEC = "1";
"AGND":   PN = "32"  !CDS_PN = "32";
"BOOT":   PN = "26"  !CDS_PN = "26";
"EN":   PN = "27"  !CDS_PN = "27";
"FB":   PN = "30"  !CDS_PN = "30";
"GL1":   PN = "6"  !CDS_PN = "6";
"GL2":   PN = "37"  !CDS_PN = "37";
"HICCUP#":   PN = "35"  !CDS_PN = "35";
"ILIM":   PN = "1"  !CDS_PN = "1";
"MODE||FSET":   PN = "36"  !CDS_PN = "36";
"NC1":   PN = "33"  !CDS_PN = "33";
"NC2":   PN = "34"  !CDS_PN = "34";
"PGND":   PN = "7_10-19"  !CDS_PN = "7_10-19";
"PGOOD":   PN = "2"  !CDS_PN = "2";
"PHASE":   PN = "25"  !CDS_PN = "25";
"PVIN":   PN = "20_24"  !CDS_PN = "20_24";
"SS":   PN = "29"  !CDS_PN = "29";
"SW":   PN = "11_18"  !CDS_PN = "11_18";
"VCC":   PN = "4"  !CDS_PN = "4";
"VDRV":   PN = "5"  !CDS_PN = "5";
"VIN":   PN = "3"  !CDS_PN = "3";
"VOS":   PN = "28"  !CDS_PN = "28";
"VSNS-":   PN = "31"  !CDS_PN = "31";
BODY = "Q_CAP","I23": #LOCATION = "PC1649" !CDS_LOCATION = "PC1649" &SEC = "1" #&CDS_SEC = "1";
"A":   PN = "1"  !CDS_PN = "1";
"B":   PN = "2"  !CDS_PN = "2";
BODY = "Q_CAP","I26": #LOCATION = "PC2260" !CDS_LOCATION = "PC2260" &SEC = "1" #&CDS_SEC = "1";
"A":   PN = "1"  !CDS_PN = "1";
"B":   PN = "2"  !CDS_PN = "2";
BODY = "Q_CAPP","I29": #LOCATION = "PC3" !CDS_LOCATION = "PC3" &SEC = "1" #&CDS_SEC = "1";
"A":   PN = "1"  !CDS_PN = "1";
"B":   PN = "2"  !CDS_PN = "2";
BODY = "Q_CAPP","I30": #LOCATION = "PC566" !CDS_LOCATION = "PC566" &SEC = "1" #&CDS_SEC = "1";
"A":   PN = "1"  !CDS_PN = "1";
"B":   PN = "2"  !CDS_PN = "2";
BODY = "Q_CAP","I31": #LOCATION = "PC2262" !CDS_LOCATION = "PC2262" &SEC = "1" #&CDS_SEC = "1";
"A":   PN = "1"  !CDS_PN = "1";
"B":   PN = "2"  !CDS_PN = "2";
BODY = "Q_CAP","I32": #LOCATION = "PC8567" !CDS_LOCATION = "PC8567" &SEC = "1" #&CDS_SEC = "1";
"A":   PN = "1"  !CDS_PN = "1";
"B":   PN = "2"  !CDS_PN = "2";
BODY = "Q_CAP","I33": #LOCATION = "PC2263" !CDS_LOCATION = "PC2263" &SEC = "1" #&CDS_SEC = "1";
"A":   PN = "1"  !CDS_PN = "1";
"B":   PN = "2"  !CDS_PN = "2";
BODY = "Q_CAP","I34": #LOCATION = "PC2342" !CDS_LOCATION = "PC2342" &SEC = "1" #&CDS_SEC = "1";
"A":   PN = "1"  !CDS_PN = "1";
"B":   PN = "2"  !CDS_PN = "2";
BODY = "Q_CAP","I35": #LOCATION = "PC570" !CDS_LOCATION = "PC570" &SEC = "1" #&CDS_SEC = "1";
"A":   PN = "1"  !CDS_PN = "1";
"B":   PN = "2"  !CDS_PN = "2";
BODY = "Q_CAP","I36": #LOCATION = "PC571" !CDS_LOCATION = "PC571" &SEC = "1" #&CDS_SEC = "1";
"A":   PN = "1"  !CDS_PN = "1";
"B":   PN = "2"  !CDS_PN = "2";
BODY = "Q_CAP","I37": #LOCATION = "PC2343" !CDS_LOCATION = "PC2343" &SEC = "1" #&CDS_SEC = "1";
"A":   PN = "1"  !CDS_PN = "1";
"B":   PN = "2"  !CDS_PN = "2";
BODY = "Q_CAP","I38": #LOCATION = "PC2344" !CDS_LOCATION = "PC2344" &SEC = "1" #&CDS_SEC = "1";
"A":   PN = "1"  !CDS_PN = "1";
"B":   PN = "2"  !CDS_PN = "2";
BODY = "Q_CAP","I39": #LOCATION = "PC576" !CDS_LOCATION = "PC576" &SEC = "1" #&CDS_SEC = "1";
"A":   PN = "1"  !CDS_PN = "1";
"B":   PN = "2"  !CDS_PN = "2";
BODY = "Q_CAP","I40": #LOCATION = "PC8071" !CDS_LOCATION = "PC8071" &SEC = "1" #&CDS_SEC = "1";
"A":   PN = "1"  !CDS_PN = "1";
"B":   PN = "2"  !CDS_PN = "2";
BODY = "Q_CAP","I41": #LOCATION = "PC577" !CDS_LOCATION = "PC577" &SEC = "1" #&CDS_SEC = "1";
"A":   PN = "1"  !CDS_PN = "1";
"B":   PN = "2"  !CDS_PN = "2";
BODY = "Q_CAP","I48": #LOCATION = "PC568" !CDS_LOCATION = "PC568" &SEC = "1" #&CDS_SEC = "1";
"A":   PN = "1"  !CDS_PN = "1";
"B":   PN = "2"  !CDS_PN = "2";
BODY = "Q_RES","I49": #LOCATION = "PR835" !CDS_LOCATION = "PR835" &SEC = "1" #&CDS_SEC = "1";
"A":   PN = "1"  !CDS_PN = "1";
"B":   PN = "2"  !CDS_PN = "2";
BODY = "Q_RES","I51": #LOCATION = "PR830" !CDS_LOCATION = "PR830" &SEC = "1" #&CDS_SEC = "1";
"A":   PN = "1"  !CDS_PN = "1";
"B":   PN = "2"  !CDS_PN = "2";
BODY = "Q_CAP","I53": #LOCATION = "PC569" !CDS_LOCATION = "PC569" &SEC = "1" #&CDS_SEC = "1";
"A":   PN = "1"  !CDS_PN = "1";
"B":   PN = "2"  !CDS_PN = "2";
BODY = "Q_INDUCTOR","I55": #LOCATION = "PL8066" !CDS_LOCATION = "PL8066" &SEC = "1" #&CDS_SEC = "1";
"1":   PN = "1"  !CDS_PN = "1";
"2":   PN = "2"  !CDS_PN = "2";
BODY = "Q_CAPP","I57": #LOCATION = "PC1866" !CDS_LOCATION = "PC1866" &SEC = "1" #&CDS_SEC = "1";
"A":   PN = "1"  !CDS_PN = "1";
"B":   PN = "2"  !CDS_PN = "2";
BODY = "Q_CAPP","I58": #LOCATION = "PC1867" !CDS_LOCATION = "PC1867" &SEC = "1" #&CDS_SEC = "1";
"A":   PN = "1"  !CDS_PN = "1";
"B":   PN = "2"  !CDS_PN = "2";
BODY = "Q_CAP","I59": #LOCATION = "PC1868" !CDS_LOCATION = "PC1868" &SEC = "1" #&CDS_SEC = "1";
"A":   PN = "1"  !CDS_PN = "1";
"B":   PN = "2"  !CDS_PN = "2";
BODY = "Q_CAP","I62": #LOCATION = "PC1600" !CDS_LOCATION = "PC1600" &SEC = "1" #&CDS_SEC = "1";
"A":   PN = "1"  !CDS_PN = "1";
"B":   PN = "2"  !CDS_PN = "2";
BODY = "Q_CAP","I63": #LOCATION = "PC1869" !CDS_LOCATION = "PC1869" &SEC = "1" #&CDS_SEC = "1";
"A":   PN = "1"  !CDS_PN = "1";
"B":   PN = "2"  !CDS_PN = "2";
BODY = "Q_RES","I65": #LOCATION = "PR8073" !CDS_LOCATION = "PR8073" &SEC = "1" #&CDS_SEC = "1";
"A":   PN = "1"  !CDS_PN = "1";
"B":   PN = "2"  !CDS_PN = "2";
BODY = "Q_RES","I10": #LOCATION = "PR832" !CDS_LOCATION = "PR832" &SEC = "1" #&CDS_SEC = "1";
"A":   PN = "1"  !CDS_PN = "1";
"B":   PN = "2"  !CDS_PN = "2";
BODY = "Q_CAP","I12": #LOCATION = "PC581" !CDS_LOCATION = "PC581" &SEC = "1" #&CDS_SEC = "1";
"A":   PN = "1"  !CDS_PN = "1";
"B":   PN = "2"  !CDS_PN = "2";
BODY = "Q_CAP","I19": #LOCATION = "PC591" !CDS_LOCATION = "PC591" &SEC = "1" #&CDS_SEC = "1";
"A":   PN = "1"  !CDS_PN = "1";
"B":   PN = "2"  !CDS_PN = "2";
BODY = "Q_INDUCTOR","I24": #LOCATION = "PL8045" !CDS_LOCATION = "PL8045" &SEC = "1" #&CDS_SEC = "1";
"1":   PN = "1"  !CDS_PN = "1";
"2":   PN = "2"  !CDS_PN = "2";
BODY = "Q_CAP","I27": #LOCATION = "PC2261" !CDS_LOCATION = "PC2261" &SEC = "1" #&CDS_SEC = "1";
"A":   PN = "1"  !CDS_PN = "1";
"B":   PN = "2"  !CDS_PN = "2";
BODY = "Q_CAP","I44": #LOCATION = "PC8008" !CDS_LOCATION = "PC8008" &SEC = "1" #&CDS_SEC = "1";
"A":   PN = "1"  !CDS_PN = "1";
"B":   PN = "2"  !CDS_PN = "2";
BODY = "Q_RES","I46": #LOCATION = "PR836" !CDS_LOCATION = "PR836" &SEC = "1" #&CDS_SEC = "1";
"A":   PN = "1"  !CDS_PN = "1";
"B":   PN = "2"  !CDS_PN = "2";
BODY = "Q_RES","I54": #LOCATION = "PR831" !CDS_LOCATION = "PR831" &SEC = "1" #&CDS_SEC = "1";
"A":   PN = "1"  !CDS_PN = "1";
"B":   PN = "2"  !CDS_PN = "2";
BODY = "Q_CAP","I60": #LOCATION = "PC1599" !CDS_LOCATION = "PC1599" &SEC = "1" #&CDS_SEC = "1";
"A":   PN = "1"  !CDS_PN = "1";
"B":   PN = "2"  !CDS_PN = "2";
BODY = "Q_RES","I67": #LOCATION = "R6099" !CDS_LOCATION = "R6099" &SEC = "1" #&CDS_SEC = "1";
"A":   PN = "1"  !CDS_PN = "1";
"B":   PN = "2"  !CDS_PN = "2";
BODY = "Q_CAP","I68": #LOCATION = "C5015" !CDS_LOCATION = "C5015" &SEC = "1" #&CDS_SEC = "1";
"A":   PN = "1"  !CDS_PN = "1";
"B":   PN = "2"  !CDS_PN = "2";
BODY = "Q_CAP","I70": #LOCATION = "PC8013" !CDS_LOCATION = "PC8013" &SEC = "1" #&CDS_SEC = "1";
"A":   PN = "1"  !CDS_PN = "1";
"B":   PN = "2"  !CDS_PN = "2";
BODY = "Q_CAP","I71": #LOCATION = "PC8014" !CDS_LOCATION = "PC8014" &SEC = "1" #&CDS_SEC = "1";
"A":   PN = "1"  !CDS_PN = "1";
"B":   PN = "2"  !CDS_PN = "2";
DRAWING = "@t6g_mb_lib.t6g(sch_1):page301";
BODY = "Q_CAP","I2": #LOCATION = "PC2183" !CDS_LOCATION = "PC2183" &SEC = "1" #&CDS_SEC = "1";
"A":   PN = "1"  !CDS_PN = "1";
"B":   PN = "2"  !CDS_PN = "2";
BODY = "Q_CAP","I4": #LOCATION = "PC2181" !CDS_LOCATION = "PC2181" &SEC = "1" #&CDS_SEC = "1";
"A":   PN = "1"  !CDS_PN = "1";
"B":   PN = "2"  !CDS_PN = "2";
BODY = "Q_RES","I5": #LOCATION = "PR3911" !CDS_LOCATION = "PR3911" &SEC = "1" #&CDS_SEC = "1";
"A":   PN = "1"  !CDS_PN = "1";
"B":   PN = "2"  !CDS_PN = "2";
BODY = "Q_RES","I11": #LOCATION = "PR3912" !CDS_LOCATION = "PR3912" &SEC = "1" #&CDS_SEC = "1";
"A":   PN = "1"  !CDS_PN = "1";
"B":   PN = "2"  !CDS_PN = "2";
BODY = "Q_CAP","I12": #LOCATION = "PC2348" !CDS_LOCATION = "PC2348" &SEC = "1" #&CDS_SEC = "1";
"A":   PN = "1"  !CDS_PN = "1";
"B":   PN = "2"  !CDS_PN = "2";
BODY = "Q_RES","I13": #LOCATION = "PR3915" !CDS_LOCATION = "PR3915" &SEC = "1" #&CDS_SEC = "1";
"A":   PN = "1"  !CDS_PN = "1";
"B":   PN = "2"  !CDS_PN = "2";
BODY = "Q_RES","I15": #LOCATION = "PR1101" !CDS_LOCATION = "PR1101" &SEC = "1" #&CDS_SEC = "1";
"A":   PN = "1"  !CDS_PN = "1";
"B":   PN = "2"  !CDS_PN = "2";
BODY = "MP5991GLUZ","I16": #LOCATION = "PU288" !CDS_LOCATION = "PU288" #SEC = "1" !CDS_SEC = "1";
"CS":   PN = "23"  !CDS_PN = "23";
"D_OC":   PN = "3"  !CDS_PN = "3";
"FLT_TYPE":   PN = "6"  !CDS_PN = "6";
"GND":   PN = "20"  !CDS_PN = "20";
"GOK":   PN = "5"  !CDS_PN = "5";
"IMON":   PN = "22"  !CDS_PN = "22";
"MODE":   PN = "8"  !CDS_PN = "8";
"NC1":   PN = "7"  !CDS_PN = "7";
"OCREF":   PN = "24"  !CDS_PN = "24";
"ON":   PN = "4"  !CDS_PN = "4";
"SCREF_OCWREF":   PN = "17"  !CDS_PN = "17";
"SS":   PN = "19"  !CDS_PN = "19";
"VDD33":   PN = "21"  !CDS_PN = "21";
"VIN1":   PN = "9"  !CDS_PN = "9";
"VIN2":   PN = "10"  !CDS_PN = "10";
"VIN3":   PN = "11"  !CDS_PN = "11";
"VIN4":   PN = "12"  !CDS_PN = "12";
"VIN5":   PN = "13"  !CDS_PN = "13";
"VIN6":   PN = "14"  !CDS_PN = "14";
"VIN7":   PN = "15"  !CDS_PN = "15";
"VIN8":   PN = "16"  !CDS_PN = "16";
"VIN9":   PN = "33"  !CDS_PN = "33";
"VOUT1":   PN = "1"  !CDS_PN = "1";
"VOUT2":   PN = "2"  !CDS_PN = "2";
"VOUT3":   PN = "25"  !CDS_PN = "25";
"VOUT4":   PN = "26"  !CDS_PN = "26";
"VOUT5":   PN = "27"  !CDS_PN = "27";
"VOUT6":   PN = "28"  !CDS_PN = "28";
"VOUT7":   PN = "29"  !CDS_PN = "29";
"VOUT8":   PN = "30"  !CDS_PN = "30";
"VOUT9":   PN = "31"  !CDS_PN = "31";
"VOUT10":   PN = "32"  !CDS_PN = "32";
"VTEMP":   PN = "18"  !CDS_PN = "18";
BODY = "Q_RES","I17": #LOCATION = "PR3917" !CDS_LOCATION = "PR3917" &SEC = "1" #&CDS_SEC = "1";
"A":   PN = "1"  !CDS_PN = "1";
"B":   PN = "2"  !CDS_PN = "2";
BODY = "Q_CAP","I20": #LOCATION = "PC1525" !CDS_LOCATION = "PC1525" &SEC = "1" #&CDS_SEC = "1";
"A":   PN = "1"  !CDS_PN = "1";
"B":   PN = "2"  !CDS_PN = "2";
BODY = "Q_RES","I21": #LOCATION = "PR3910" !CDS_LOCATION = "PR3910" &SEC = "1" #&CDS_SEC = "1";
"A":   PN = "1"  !CDS_PN = "1";
"B":   PN = "2"  !CDS_PN = "2";
BODY = "Q_CAP","I24": #LOCATION = "PC2182" !CDS_LOCATION = "PC2182" &SEC = "1" #&CDS_SEC = "1";
"A":   PN = "1"  !CDS_PN = "1";
"B":   PN = "2"  !CDS_PN = "2";
BODY = "Q_RES","I29": #LOCATION = "PR1134" !CDS_LOCATION = "PR1134" &SEC = "1" #&CDS_SEC = "1";
"A":   PN = "1"  !CDS_PN = "1";
"B":   PN = "2"  !CDS_PN = "2";
BODY = "Q_CAP","I30": #LOCATION = "PC2347" !CDS_LOCATION = "PC2347" &SEC = "1" #&CDS_SEC = "1";
"A":   PN = "1"  !CDS_PN = "1";
"B":   PN = "2"  !CDS_PN = "2";
BODY = "Q_RES","I31": #LOCATION = "PR3914" !CDS_LOCATION = "PR3914" &SEC = "1" #&CDS_SEC = "1";
"A":   PN = "1"  !CDS_PN = "1";
"B":   PN = "2"  !CDS_PN = "2";
BODY = "Q_RES","I33": #LOCATION = "PR3916" !CDS_LOCATION = "PR3916" &SEC = "1" #&CDS_SEC = "1";
"A":   PN = "1"  !CDS_PN = "1";
"B":   PN = "2"  !CDS_PN = "2";
BODY = "Q_RES","I34": #LOCATION = "PR3918" !CDS_LOCATION = "PR3918" &SEC = "1" #&CDS_SEC = "1";
"A":   PN = "1"  !CDS_PN = "1";
"B":   PN = "2"  !CDS_PN = "2";
BODY = "MP5991GLUZ","I35": #LOCATION = "PU287" !CDS_LOCATION = "PU287" #SEC = "1" !CDS_SEC = "1";
"CS":   PN = "23"  !CDS_PN = "23";
"D_OC":   PN = "3"  !CDS_PN = "3";
"FLT_TYPE":   PN = "6"  !CDS_PN = "6";
"GND":   PN = "20"  !CDS_PN = "20";
"GOK":   PN = "5"  !CDS_PN = "5";
"IMON":   PN = "22"  !CDS_PN = "22";
"MODE":   PN = "8"  !CDS_PN = "8";
"NC1":   PN = "7"  !CDS_PN = "7";
"OCREF":   PN = "24"  !CDS_PN = "24";
"ON":   PN = "4"  !CDS_PN = "4";
"SCREF_OCWREF":   PN = "17"  !CDS_PN = "17";
"SS":   PN = "19"  !CDS_PN = "19";
"VDD33":   PN = "21"  !CDS_PN = "21";
"VIN1":   PN = "9"  !CDS_PN = "9";
"VIN2":   PN = "10"  !CDS_PN = "10";
"VIN3":   PN = "11"  !CDS_PN = "11";
"VIN4":   PN = "12"  !CDS_PN = "12";
"VIN5":   PN = "13"  !CDS_PN = "13";
"VIN6":   PN = "14"  !CDS_PN = "14";
"VIN7":   PN = "15"  !CDS_PN = "15";
"VIN8":   PN = "16"  !CDS_PN = "16";
"VIN9":   PN = "33"  !CDS_PN = "33";
"VOUT1":   PN = "1"  !CDS_PN = "1";
"VOUT2":   PN = "2"  !CDS_PN = "2";
"VOUT3":   PN = "25"  !CDS_PN = "25";
"VOUT4":   PN = "26"  !CDS_PN = "26";
"VOUT5":   PN = "27"  !CDS_PN = "27";
"VOUT6":   PN = "28"  !CDS_PN = "28";
"VOUT7":   PN = "29"  !CDS_PN = "29";
"VOUT8":   PN = "30"  !CDS_PN = "30";
"VOUT9":   PN = "31"  !CDS_PN = "31";
"VOUT10":   PN = "32"  !CDS_PN = "32";
"VTEMP":   PN = "18"  !CDS_PN = "18";
BODY = "Q_CAP","I38": #LOCATION = "PC2185" !CDS_LOCATION = "PC2185" &SEC = "1" #&CDS_SEC = "1";
"A":   PN = "1"  !CDS_PN = "1";
"B":   PN = "2"  !CDS_PN = "2";
BODY = "Q_RES","I39": #LOCATION = "PR3922" !CDS_LOCATION = "PR3922" &SEC = "1" #&CDS_SEC = "1";
"A":   PN = "1"  !CDS_PN = "1";
"B":   PN = "2"  !CDS_PN = "2";
BODY = "Q_RES","I40": #LOCATION = "PR3921" !CDS_LOCATION = "PR3921" &SEC = "1" #&CDS_SEC = "1";
"A":   PN = "1"  !CDS_PN = "1";
"B":   PN = "2"  !CDS_PN = "2";
BODY = "Q_CAP","I47": #LOCATION = "PC2184" !CDS_LOCATION = "PC2184" &SEC = "1" #&CDS_SEC = "1";
"A":   PN = "1"  !CDS_PN = "1";
"B":   PN = "2"  !CDS_PN = "2";
BODY = "Q_RES","I49": #LOCATION = "PR3920" !CDS_LOCATION = "PR3920" &SEC = "1" #&CDS_SEC = "1";
"A":   PN = "1"  !CDS_PN = "1";
"B":   PN = "2"  !CDS_PN = "2";
BODY = "Q_RES","I50": #LOCATION = "PR3919" !CDS_LOCATION = "PR3919" &SEC = "1" #&CDS_SEC = "1";
"A":   PN = "1"  !CDS_PN = "1";
"B":   PN = "2"  !CDS_PN = "2";
DRAWING = "@t6g_mb_lib.t6g(sch_1):page325";
BODY = "Q_CAP","I2": #LOCATION = "PC2225" !CDS_LOCATION = "PC2225" &SEC = "1" #&CDS_SEC = "1";
"A":   PN = "1"  !CDS_PN = "1";
"B":   PN = "2"  !CDS_PN = "2";
BODY = "Q_CAP","I4": #LOCATION = "PC2223" !CDS_LOCATION = "PC2223" &SEC = "1" #&CDS_SEC = "1";
"A":   PN = "1"  !CDS_PN = "1";
"B":   PN = "2"  !CDS_PN = "2";
BODY = "Q_RES","I6": #LOCATION = "PR3981" !CDS_LOCATION = "PR3981" &SEC = "1" #&CDS_SEC = "1";
"A":   PN = "1"  !CDS_PN = "1";
"B":   PN = "2"  !CDS_PN = "2";
BODY = "Q_RES","I11": #LOCATION = "PR3984" !CDS_LOCATION = "PR3984" &SEC = "1" #&CDS_SEC = "1";
"A":   PN = "1"  !CDS_PN = "1";
"B":   PN = "2"  !CDS_PN = "2";
BODY = "Q_CAP","I12": #LOCATION = "PC2349" !CDS_LOCATION = "PC2349" &SEC = "1" #&CDS_SEC = "1";
"A":   PN = "1"  !CDS_PN = "1";
"B":   PN = "2"  !CDS_PN = "2";
BODY = "Q_RES","I13": #LOCATION = "PR3987" !CDS_LOCATION = "PR3987" &SEC = "1" #&CDS_SEC = "1";
"A":   PN = "1"  !CDS_PN = "1";
"B":   PN = "2"  !CDS_PN = "2";
BODY = "Q_RES","I14": #LOCATION = "PR3991" !CDS_LOCATION = "PR3991" &SEC = "1" #&CDS_SEC = "1";
"A":   PN = "1"  !CDS_PN = "1";
"B":   PN = "2"  !CDS_PN = "2";
BODY = "Q_RES","I16": #LOCATION = "PR3989" !CDS_LOCATION = "PR3989" &SEC = "1" #&CDS_SEC = "1";
"A":   PN = "1"  !CDS_PN = "1";
"B":   PN = "2"  !CDS_PN = "2";
BODY = "MP5991GLUZ","I17": #LOCATION = "PU297" !CDS_LOCATION = "PU297" #SEC = "1" !CDS_SEC = "1";
"CS":   PN = "23"  !CDS_PN = "23";
"D_OC":   PN = "3"  !CDS_PN = "3";
"FLT_TYPE":   PN = "6"  !CDS_PN = "6";
"GND":   PN = "20"  !CDS_PN = "20";
"GOK":   PN = "5"  !CDS_PN = "5";
"IMON":   PN = "22"  !CDS_PN = "22";
"MODE":   PN = "8"  !CDS_PN = "8";
"NC1":   PN = "7"  !CDS_PN = "7";
"OCREF":   PN = "24"  !CDS_PN = "24";
"ON":   PN = "4"  !CDS_PN = "4";
"SCREF_OCWREF":   PN = "17"  !CDS_PN = "17";
"SS":   PN = "19"  !CDS_PN = "19";
"VDD33":   PN = "21"  !CDS_PN = "21";
"VIN1":   PN = "9"  !CDS_PN = "9";
"VIN2":   PN = "10"  !CDS_PN = "10";
"VIN3":   PN = "11"  !CDS_PN = "11";
"VIN4":   PN = "12"  !CDS_PN = "12";
"VIN5":   PN = "13"  !CDS_PN = "13";
"VIN6":   PN = "14"  !CDS_PN = "14";
"VIN7":   PN = "15"  !CDS_PN = "15";
"VIN8":   PN = "16"  !CDS_PN = "16";
"VIN9":   PN = "33"  !CDS_PN = "33";
"VOUT1":   PN = "1"  !CDS_PN = "1";
"VOUT2":   PN = "2"  !CDS_PN = "2";
"VOUT3":   PN = "25"  !CDS_PN = "25";
"VOUT4":   PN = "26"  !CDS_PN = "26";
"VOUT5":   PN = "27"  !CDS_PN = "27";
"VOUT6":   PN = "28"  !CDS_PN = "28";
"VOUT7":   PN = "29"  !CDS_PN = "29";
"VOUT8":   PN = "30"  !CDS_PN = "30";
"VOUT9":   PN = "31"  !CDS_PN = "31";
"VOUT10":   PN = "32"  !CDS_PN = "32";
"VTEMP":   PN = "18"  !CDS_PN = "18";
BODY = "Q_CAP","I20": #LOCATION = "PC3272" !CDS_LOCATION = "PC3272" &SEC = "1" #&CDS_SEC = "1";
"A":   PN = "1"  !CDS_PN = "1";
"B":   PN = "2"  !CDS_PN = "2";
BODY = "Q_RES","I21": #LOCATION = "PR3980" !CDS_LOCATION = "PR3980" &SEC = "1" #&CDS_SEC = "1";
"A":   PN = "1"  !CDS_PN = "1";
"B":   PN = "2"  !CDS_PN = "2";
BODY = "Q_CAP","I24": #LOCATION = "PC2224" !CDS_LOCATION = "PC2224" &SEC = "1" #&CDS_SEC = "1";
"A":   PN = "1"  !CDS_PN = "1";
"B":   PN = "2"  !CDS_PN = "2";
BODY = "Q_RES","I28": #LOCATION = "PR3982" !CDS_LOCATION = "PR3982" &SEC = "1" #&CDS_SEC = "1";
"A":   PN = "1"  !CDS_PN = "1";
"B":   PN = "2"  !CDS_PN = "2";
BODY = "Q_CAP","I30": #LOCATION = "PC2350" !CDS_LOCATION = "PC2350" &SEC = "1" #&CDS_SEC = "1";
"A":   PN = "1"  !CDS_PN = "1";
"B":   PN = "2"  !CDS_PN = "2";
BODY = "Q_RES","I31": #LOCATION = "PR3986" !CDS_LOCATION = "PR3986" &SEC = "1" #&CDS_SEC = "1";
"A":   PN = "1"  !CDS_PN = "1";
"B":   PN = "2"  !CDS_PN = "2";
BODY = "Q_RES","I33": #LOCATION = "PR3988" !CDS_LOCATION = "PR3988" &SEC = "1" #&CDS_SEC = "1";
"A":   PN = "1"  !CDS_PN = "1";
"B":   PN = "2"  !CDS_PN = "2";
BODY = "Q_RES","I34": #LOCATION = "PR3990" !CDS_LOCATION = "PR3990" &SEC = "1" #&CDS_SEC = "1";
"A":   PN = "1"  !CDS_PN = "1";
"B":   PN = "2"  !CDS_PN = "2";
BODY = "MP5991GLUZ","I35": #LOCATION = "PU296" !CDS_LOCATION = "PU296" #SEC = "1" !CDS_SEC = "1";
"CS":   PN = "23"  !CDS_PN = "23";
"D_OC":   PN = "3"  !CDS_PN = "3";
"FLT_TYPE":   PN = "6"  !CDS_PN = "6";
"GND":   PN = "20"  !CDS_PN = "20";
"GOK":   PN = "5"  !CDS_PN = "5";
"IMON":   PN = "22"  !CDS_PN = "22";
"MODE":   PN = "8"  !CDS_PN = "8";
"NC1":   PN = "7"  !CDS_PN = "7";
"OCREF":   PN = "24"  !CDS_PN = "24";
"ON":   PN = "4"  !CDS_PN = "4";
"SCREF_OCWREF":   PN = "17"  !CDS_PN = "17";
"SS":   PN = "19"  !CDS_PN = "19";
"VDD33":   PN = "21"  !CDS_PN = "21";
"VIN1":   PN = "9"  !CDS_PN = "9";
"VIN2":   PN = "10"  !CDS_PN = "10";
"VIN3":   PN = "11"  !CDS_PN = "11";
"VIN4":   PN = "12"  !CDS_PN = "12";
"VIN5":   PN = "13"  !CDS_PN = "13";
"VIN6":   PN = "14"  !CDS_PN = "14";
"VIN7":   PN = "15"  !CDS_PN = "15";
"VIN8":   PN = "16"  !CDS_PN = "16";
"VIN9":   PN = "33"  !CDS_PN = "33";
"VOUT1":   PN = "1"  !CDS_PN = "1";
"VOUT2":   PN = "2"  !CDS_PN = "2";
"VOUT3":   PN = "25"  !CDS_PN = "25";
"VOUT4":   PN = "26"  !CDS_PN = "26";
"VOUT5":   PN = "27"  !CDS_PN = "27";
"VOUT6":   PN = "28"  !CDS_PN = "28";
"VOUT7":   PN = "29"  !CDS_PN = "29";
"VOUT8":   PN = "30"  !CDS_PN = "30";
"VOUT9":   PN = "31"  !CDS_PN = "31";
"VOUT10":   PN = "32"  !CDS_PN = "32";
"VTEMP":   PN = "18"  !CDS_PN = "18";
BODY = "Q_CAP","I38": #LOCATION = "PC2227" !CDS_LOCATION = "PC2227" &SEC = "1" #&CDS_SEC = "1";
"A":   PN = "1"  !CDS_PN = "1";
"B":   PN = "2"  !CDS_PN = "2";
BODY = "Q_RES","I39": #LOCATION = "PR3995" !CDS_LOCATION = "PR3995" &SEC = "1" #&CDS_SEC = "1";
"A":   PN = "1"  !CDS_PN = "1";
"B":   PN = "2"  !CDS_PN = "2";
BODY = "Q_RES","I40": #LOCATION = "PR3994" !CDS_LOCATION = "PR3994" &SEC = "1" #&CDS_SEC = "1";
"A":   PN = "1"  !CDS_PN = "1";
"B":   PN = "2"  !CDS_PN = "2";
BODY = "Q_CAP","I47": #LOCATION = "PC2226" !CDS_LOCATION = "PC2226" &SEC = "1" #&CDS_SEC = "1";
"A":   PN = "1"  !CDS_PN = "1";
"B":   PN = "2"  !CDS_PN = "2";
BODY = "Q_RES","I49": #LOCATION = "PR3993" !CDS_LOCATION = "PR3993" &SEC = "1" #&CDS_SEC = "1";
"A":   PN = "1"  !CDS_PN = "1";
"B":   PN = "2"  !CDS_PN = "2";
BODY = "Q_RES","I50": #LOCATION = "PR3992" !CDS_LOCATION = "PR3992" &SEC = "1" #&CDS_SEC = "1";
"A":   PN = "1"  !CDS_PN = "1";
"B":   PN = "2"  !CDS_PN = "2";
DRAWING = "@t6g_mb_lib.t6g(sch_1):page299";
BODY = "Q_RES","I3": #LOCATION = "R3430" !CDS_LOCATION = "R3430" &SEC = "1" #&CDS_SEC = "1";
"A":   PN = "1"  !CDS_PN = "1";
"B":   PN = "2"  !CDS_PN = "2";
BODY = "Q_RES","I17": #LOCATION = "R3428" !CDS_LOCATION = "R3428" &SEC = "1" #&CDS_SEC = "1";
"A":   PN = "1"  !CDS_PN = "1";
"B":   PN = "2"  !CDS_PN = "2";
BODY = "MOSFET_NCH_DUAL","I21": #LOCATION = "Q104" !CDS_LOCATION = "Q104" &SEC = "1" #&CDS_SEC = "1";
"D1":   PN = "6"  !CDS_PN = "6";
"G1":   PN = "2"  !CDS_PN = "2";
"S1":   PN = "1"  !CDS_PN = "1";
BODY = "Q_RES","I23": #LOCATION = "R3435" !CDS_LOCATION = "R3435" &SEC = "1" #&CDS_SEC = "1";
"A":   PN = "1"  !CDS_PN = "1";
"B":   PN = "2"  !CDS_PN = "2";
BODY = "MOSFET_NCH_DUAL","I26": #LOCATION = "Q104" !CDS_LOCATION = "Q104" &SEC = "2" #&CDS_SEC = "2";
"D2":   PN = "3"  !CDS_PN = "3";
"G2":   PN = "5"  !CDS_PN = "5";
"S2":   PN = "4"  !CDS_PN = "4";
BODY = "Q_RES","I27": #LOCATION = "R3437" !CDS_LOCATION = "R3437" &SEC = "1" #&CDS_SEC = "1";
"A":   PN = "1"  !CDS_PN = "1";
"B":   PN = "2"  !CDS_PN = "2";
BODY = "Q_CAP","I30": #LOCATION = "C1976" !CDS_LOCATION = "C1976" &SEC = "1" #&CDS_SEC = "1";
"A":   PN = "1"  !CDS_PN = "1";
"B":   PN = "2"  !CDS_PN = "2";
BODY = "MOSFET_NCH_DUAL","I37": #LOCATION = "Q103" !CDS_LOCATION = "Q103" &SEC = "1" #&CDS_SEC = "1";
"D1":   PN = "6"  !CDS_PN = "6";
"G1":   PN = "2"  !CDS_PN = "2";
"S1":   PN = "1"  !CDS_PN = "1";
BODY = "Q_RES","I39": #LOCATION = "R3434" !CDS_LOCATION = "R3434" &SEC = "1" #&CDS_SEC = "1";
"A":   PN = "1"  !CDS_PN = "1";
"B":   PN = "2"  !CDS_PN = "2";
BODY = "MOSFET_NCH_DUAL","I40": #LOCATION = "Q102" !CDS_LOCATION = "Q102" &SEC = "1" #&CDS_SEC = "1";
"D1":   PN = "6"  !CDS_PN = "6";
"G1":   PN = "2"  !CDS_PN = "2";
"S1":   PN = "1"  !CDS_PN = "1";
BODY = "MOSFET_NCH_DUAL","I43": #LOCATION = "Q103" !CDS_LOCATION = "Q103" &SEC = "2" #&CDS_SEC = "2";
"D2":   PN = "3"  !CDS_PN = "3";
"G2":   PN = "5"  !CDS_PN = "5";
"S2":   PN = "4"  !CDS_PN = "4";
BODY = "Q_RES","I45": #LOCATION = "R3436" !CDS_LOCATION = "R3436" &SEC = "1" #&CDS_SEC = "1";
"A":   PN = "1"  !CDS_PN = "1";
"B":   PN = "2"  !CDS_PN = "2";
BODY = "MOSFET_NCH_DUAL","I48": #LOCATION = "Q102" !CDS_LOCATION = "Q102" &SEC = "2" #&CDS_SEC = "2";
"D2":   PN = "3"  !CDS_PN = "3";
"G2":   PN = "5"  !CDS_PN = "5";
"S2":   PN = "4"  !CDS_PN = "4";
BODY = "Q_RES","I49": #LOCATION = "R3433" !CDS_LOCATION = "R3433" &SEC = "1" #&CDS_SEC = "1";
"A":   PN = "1"  !CDS_PN = "1";
"B":   PN = "2"  !CDS_PN = "2";
BODY = "MOSFET_NCH_DUAL","I52": #LOCATION = "Q101" !CDS_LOCATION = "Q101" &SEC = "1" #&CDS_SEC = "1";
"D1":   PN = "6"  !CDS_PN = "6";
"G1":   PN = "2"  !CDS_PN = "2";
"S1":   PN = "1"  !CDS_PN = "1";
BODY = "Q_RES","I53": #LOCATION = "R3432" !CDS_LOCATION = "R3432" &SEC = "1" #&CDS_SEC = "1";
"A":   PN = "1"  !CDS_PN = "1";
"B":   PN = "2"  !CDS_PN = "2";
BODY = "Q_RES","I55": #LOCATION = "R3438" !CDS_LOCATION = "R3438" &SEC = "1" #&CDS_SEC = "1";
"A":   PN = "1"  !CDS_PN = "1";
"B":   PN = "2"  !CDS_PN = "2";
BODY = "MOSFET_NCH_DUAL","I57": #LOCATION = "Q101" !CDS_LOCATION = "Q101" &SEC = "2" #&CDS_SEC = "2";
"D2":   PN = "3"  !CDS_PN = "3";
"G2":   PN = "5"  !CDS_PN = "5";
"S2":   PN = "4"  !CDS_PN = "4";
BODY = "Q_RES","I59": #LOCATION = "R3439" !CDS_LOCATION = "R3439" &SEC = "1" #&CDS_SEC = "1";
"A":   PN = "1"  !CDS_PN = "1";
"B":   PN = "2"  !CDS_PN = "2";
BODY = "Q_CAP","I71": #LOCATION = "C1973" !CDS_LOCATION = "C1973" &SEC = "1" #&CDS_SEC = "1";
"A":   PN = "1"  !CDS_PN = "1";
"B":   PN = "2"  !CDS_PN = "2";
BODY = "Q_CAP","I74": #LOCATION = "C1974" !CDS_LOCATION = "C1974" &SEC = "1" #&CDS_SEC = "1";
"A":   PN = "1"  !CDS_PN = "1";
"B":   PN = "2"  !CDS_PN = "2";
BODY = "Q_CAP","I129": #LOCATION = "C1975" !CDS_LOCATION = "C1975" &SEC = "1" #&CDS_SEC = "1";
"A":   PN = "1"  !CDS_PN = "1";
"B":   PN = "2"  !CDS_PN = "2";
BODY = "Q_RES","I130": #LOCATION = "R3429" !CDS_LOCATION = "R3429" &SEC = "1" #&CDS_SEC = "1";
"A":   PN = "1"  !CDS_PN = "1";
"B":   PN = "2"  !CDS_PN = "2";
BODY = "Q_RES","I131": #LOCATION = "R3463" !CDS_LOCATION = "R3463" &SEC = "1" #&CDS_SEC = "1";
"A":   PN = "1"  !CDS_PN = "1";
"B":   PN = "2"  !CDS_PN = "2";
BODY = "Q_RES","I132": #LOCATION = "R3465" !CDS_LOCATION = "R3465" &SEC = "1" #&CDS_SEC = "1";
"A":   PN = "1"  !CDS_PN = "1";
"B":   PN = "2"  !CDS_PN = "2";
BODY = "Q_RES","I133": #LOCATION = "R3431" !CDS_LOCATION = "R3431" &SEC = "1" #&CDS_SEC = "1";
"A":   PN = "1"  !CDS_PN = "1";
"B":   PN = "2"  !CDS_PN = "2";
BODY = "Q_RES","I134": #LOCATION = "R3464" !CDS_LOCATION = "R3464" &SEC = "1" #&CDS_SEC = "1";
"A":   PN = "1"  !CDS_PN = "1";
"B":   PN = "2"  !CDS_PN = "2";
BODY = "Q_CAP","I152": #LOCATION = "C1978" !CDS_LOCATION = "C1978" &SEC = "1" #&CDS_SEC = "1";
"A":   PN = "1"  !CDS_PN = "1";
"B":   PN = "2"  !CDS_PN = "2";
BODY = "Q_RES","I154": #LOCATION = "R3475" !CDS_LOCATION = "R3475" &SEC = "1" #&CDS_SEC = "1";
"A":   PN = "1"  !CDS_PN = "1";
"B":   PN = "2"  !CDS_PN = "2";
BODY = "MOSFET_NCH_DUAL","I157": #LOCATION = "Q107" !CDS_LOCATION = "Q107" &SEC = "2" #&CDS_SEC = "2";
"D2":   PN = "3"  !CDS_PN = "3";
"G2":   PN = "5"  !CDS_PN = "5";
"S2":   PN = "4"  !CDS_PN = "4";
BODY = "Q_RES","I158": #LOCATION = "R3474" !CDS_LOCATION = "R3474" &SEC = "1" #&CDS_SEC = "1";
"A":   PN = "1"  !CDS_PN = "1";
"B":   PN = "2"  !CDS_PN = "2";
BODY = "MOSFET_NCH_DUAL","I160": #LOCATION = "Q107" !CDS_LOCATION = "Q107" &SEC = "1" #&CDS_SEC = "1";
"D1":   PN = "6"  !CDS_PN = "6";
"G1":   PN = "2"  !CDS_PN = "2";
"S1":   PN = "1"  !CDS_PN = "1";
BODY = "Q_RES","I163": #LOCATION = "R3473" !CDS_LOCATION = "R3473" &SEC = "1" #&CDS_SEC = "1";
"A":   PN = "1"  !CDS_PN = "1";
"B":   PN = "2"  !CDS_PN = "2";
BODY = "Q_RES","I166": #LOCATION = "R3487" !CDS_LOCATION = "R3487" &SEC = "1" #&CDS_SEC = "1";
"A":   PN = "1"  !CDS_PN = "1";
"B":   PN = "2"  !CDS_PN = "2";
BODY = "Q_RES","I167": #LOCATION = "R3498" !CDS_LOCATION = "R3498" &SEC = "1" #&CDS_SEC = "1";
"A":   PN = "1"  !CDS_PN = "1";
"B":   PN = "2"  !CDS_PN = "2";
BODY = "MOSFET_NCH_DUAL","I168": #LOCATION = "Q108" !CDS_LOCATION = "Q108" &SEC = "2" #&CDS_SEC = "2";
"D2":   PN = "3"  !CDS_PN = "3";
"G2":   PN = "5"  !CDS_PN = "5";
"S2":   PN = "4"  !CDS_PN = "4";
BODY = "MOSFET_NCH_DUAL","I169": #LOCATION = "Q108" !CDS_LOCATION = "Q108" &SEC = "1" #&CDS_SEC = "1";
"D1":   PN = "6"  !CDS_PN = "6";
"G1":   PN = "2"  !CDS_PN = "2";
"S1":   PN = "1"  !CDS_PN = "1";
BODY = "Q_CAP","I171": #LOCATION = "C1988" !CDS_LOCATION = "C1988" &SEC = "1" #&CDS_SEC = "1";
"A":   PN = "1"  !CDS_PN = "1";
"B":   PN = "2"  !CDS_PN = "2";
BODY = "Q_RES","I174": #LOCATION = "R3504" !CDS_LOCATION = "R3504" &SEC = "1" #&CDS_SEC = "1";
"A":   PN = "1"  !CDS_PN = "1";
"B":   PN = "2"  !CDS_PN = "2";
BODY = "Q_RES","I177": #LOCATION = "R3503" !CDS_LOCATION = "R3503" &SEC = "1" #&CDS_SEC = "1";
"A":   PN = "1"  !CDS_PN = "1";
"B":   PN = "2"  !CDS_PN = "2";
BODY = "Q_RES","I181": #LOCATION = "R3502" !CDS_LOCATION = "R3502" &SEC = "1" #&CDS_SEC = "1";
"A":   PN = "1"  !CDS_PN = "1";
"B":   PN = "2"  !CDS_PN = "2";
BODY = "Q_RES","I184": #LOCATION = "R3525" !CDS_LOCATION = "R3525" &SEC = "1" #&CDS_SEC = "1";
"A":   PN = "1"  !CDS_PN = "1";
"B":   PN = "2"  !CDS_PN = "2";
BODY = "Q_RES","I187": #LOCATION = "R3471" !CDS_LOCATION = "R3471" &SEC = "1" #&CDS_SEC = "1";
"A":   PN = "1"  !CDS_PN = "1";
"B":   PN = "2"  !CDS_PN = "2";
BODY = "Q_RES","I192": #LOCATION = "R9043" !CDS_LOCATION = "R9043" &SEC = "1" #&CDS_SEC = "1";
"A":   PN = "1"  !CDS_PN = "1";
"B":   PN = "2"  !CDS_PN = "2";
BODY = "Q_RES","I195": #LOCATION = "R9044" !CDS_LOCATION = "R9044" &SEC = "1" #&CDS_SEC = "1";
"A":   PN = "1"  !CDS_PN = "1";
"B":   PN = "2"  !CDS_PN = "2";
BODY = "Q_RES","I198": #LOCATION = "R3472" !CDS_LOCATION = "R3472" &SEC = "1" #&CDS_SEC = "1";
"A":   PN = "1"  !CDS_PN = "1";
"B":   PN = "2"  !CDS_PN = "2";
BODY = "MOSFET_NCH_DUAL","I200": #LOCATION = "Q106" !CDS_LOCATION = "Q106" &SEC = "2" #&CDS_SEC = "2";
"D2":   PN = "3"  !CDS_PN = "3";
"G2":   PN = "5"  !CDS_PN = "5";
"S2":   PN = "4"  !CDS_PN = "4";
BODY = "MOSFET_NCH_DUAL","I201": #LOCATION = "Q106" !CDS_LOCATION = "Q106" &SEC = "1" #&CDS_SEC = "1";
"D1":   PN = "6"  !CDS_PN = "6";
"G1":   PN = "2"  !CDS_PN = "2";
"S1":   PN = "1"  !CDS_PN = "1";
BODY = "Q_RES","I202": #LOCATION = "R3470" !CDS_LOCATION = "R3470" &SEC = "1" #&CDS_SEC = "1";
"A":   PN = "1"  !CDS_PN = "1";
"B":   PN = "2"  !CDS_PN = "2";
DRAWING = "@t6g_mb_lib.t6g(sch_1):page330";
BODY = "Q_RES","I8": #LOCATION = "R9002" !CDS_LOCATION = "R9002" #SEC = "1" !CDS_SEC = "1";
"A":   PN = "1"  !CDS_PN = "1";
"B":   PN = "2"  !CDS_PN = "2";
BODY = "Q_RES","I17": #LOCATION = "R9008" !CDS_LOCATION = "R9008" &SEC = "1" #&CDS_SEC = "1";
"A":   PN = "1"  !CDS_PN = "1";
"B":   PN = "2"  !CDS_PN = "2";
BODY = "MOSFET_NCH_DUAL","I21": #LOCATION = "Q9000" !CDS_LOCATION = "Q9000" #SEC = "1" !CDS_SEC = "1";
"D1":   PN = "6"  !CDS_PN = "6";
"G1":   PN = "2"  !CDS_PN = "2";
"S1":   PN = "1"  !CDS_PN = "1";
BODY = "Q_RES","I23": #LOCATION = "R9009" !CDS_LOCATION = "R9009" &SEC = "1" #&CDS_SEC = "1";
"A":   PN = "1"  !CDS_PN = "1";
"B":   PN = "2"  !CDS_PN = "2";
BODY = "Q_RES","I26": #LOCATION = "R9004" !CDS_LOCATION = "R9004" &SEC = "1" #&CDS_SEC = "1";
"A":   PN = "1"  !CDS_PN = "1";
"B":   PN = "2"  !CDS_PN = "2";
BODY = "MOSFET_NCH_DUAL","I30": #LOCATION = "Q8000" !CDS_LOCATION = "Q8000" #SEC = "2" !CDS_SEC = "2";
"D2":   PN = "3"  !CDS_PN = "3";
"G2":   PN = "5"  !CDS_PN = "5";
"S2":   PN = "4"  !CDS_PN = "4";
BODY = "Q_RES","I2": #LOCATION = "R9007" !CDS_LOCATION = "R9007" &SEC = "1" #&CDS_SEC = "1";
"A":   PN = "1"  !CDS_PN = "1";
"B":   PN = "2"  !CDS_PN = "2";
BODY = "MOSFET_NCH_DUAL","I3": #LOCATION = "Q9001" !CDS_LOCATION = "Q9001" &SEC = "1" #&CDS_SEC = "1";
"D1":   PN = "6"  !CDS_PN = "6";
"G1":   PN = "2"  !CDS_PN = "2";
"S1":   PN = "1"  !CDS_PN = "1";
BODY = "Q_RES","I12": #LOCATION = "R8001" !CDS_LOCATION = "R8001" #SEC = "1" !CDS_SEC = "1";
"A":   PN = "1"  !CDS_PN = "1";
"B":   PN = "2"  !CDS_PN = "2";
BODY = "Q_RES","I13": #LOCATION = "R4058" !CDS_LOCATION = "R4058" #SEC = "1" !CDS_SEC = "1";
"A":   PN = "1"  !CDS_PN = "1";
"B":   PN = "2"  !CDS_PN = "2";
BODY = "Q_RES","I15": #LOCATION = "R9006" !CDS_LOCATION = "R9006" &SEC = "1" #&CDS_SEC = "1";
"A":   PN = "1"  !CDS_PN = "1";
"B":   PN = "2"  !CDS_PN = "2";
BODY = "Q_RES","I20": #LOCATION = "R9003" !CDS_LOCATION = "R9003" #SEC = "1" !CDS_SEC = "1";
"A":   PN = "1"  !CDS_PN = "1";
"B":   PN = "2"  !CDS_PN = "2";
BODY = "MOSFET_NCH_DUAL","I22": #LOCATION = "Q9001" !CDS_LOCATION = "Q9001" &SEC = "2" #&CDS_SEC = "2";
"D2":   PN = "3"  !CDS_PN = "3";
"G2":   PN = "5"  !CDS_PN = "5";
"S2":   PN = "4"  !CDS_PN = "4";
BODY = "MOSFET_NCH_DUAL","I29": #LOCATION = "Q8000" !CDS_LOCATION = "Q8000" #SEC = "1" !CDS_SEC = "1";
"D1":   PN = "6"  !CDS_PN = "6";
"G1":   PN = "2"  !CDS_PN = "2";
"S1":   PN = "1"  !CDS_PN = "1";
BODY = "MOSFET_NCH_DUAL","I31": #LOCATION = "Q9000" !CDS_LOCATION = "Q9000" #SEC = "2" !CDS_SEC = "2";
"D2":   PN = "3"  !CDS_PN = "3";
"G2":   PN = "5"  !CDS_PN = "5";
"S2":   PN = "4"  !CDS_PN = "4";
BODY = "Q_RES","I32": #LOCATION = "R9005" !CDS_LOCATION = "R9005" &SEC = "1" #&CDS_SEC = "1";
"A":   PN = "1"  !CDS_PN = "1";
"B":   PN = "2"  !CDS_PN = "2";
BODY = "Q_CAP","I36": #LOCATION = "C8000" !CDS_LOCATION = "C8000" &SEC = "1" #&CDS_SEC = "1";
"A":   PN = "1"  !CDS_PN = "1";
"B":   PN = "2"  !CDS_PN = "2";
BODY = "Q_CAP","I42": #LOCATION = "C9001" !CDS_LOCATION = "C9001" &SEC = "1" #&CDS_SEC = "1";
"A":   PN = "1"  !CDS_PN = "1";
"B":   PN = "2"  !CDS_PN = "2";
BODY = "Q_CAP","I45": #LOCATION = "C9000" !CDS_LOCATION = "C9000" &SEC = "1" #&CDS_SEC = "1";
"A":   PN = "1"  !CDS_PN = "1";
"B":   PN = "2"  !CDS_PN = "2";
BODY = "Q_RES","I50": #LOCATION = "R9015" !CDS_LOCATION = "R9015" &SEC = "1" #&CDS_SEC = "1";
"A":   PN = "1"  !CDS_PN = "1";
"B":   PN = "2"  !CDS_PN = "2";
BODY = "Q_RES","I51": #LOCATION = "R9014" !CDS_LOCATION = "R9014" &SEC = "1" #&CDS_SEC = "1";
"A":   PN = "1"  !CDS_PN = "1";
"B":   PN = "2"  !CDS_PN = "2";
BODY = "MOSFET_NCH_DUAL","I52": #LOCATION = "Q9002" !CDS_LOCATION = "Q9002" &SEC = "1" #&CDS_SEC = "1";
"D1":   PN = "6"  !CDS_PN = "6";
"G1":   PN = "2"  !CDS_PN = "2";
"S1":   PN = "1"  !CDS_PN = "1";
BODY = "Q_RES","I55": #LOCATION = "R8002" !CDS_LOCATION = "R8002" &SEC = "1" #&CDS_SEC = "1";
"A":   PN = "1"  !CDS_PN = "1";
"B":   PN = "2"  !CDS_PN = "2";
BODY = "Q_RES","I57": #LOCATION = "R8003" !CDS_LOCATION = "R8003" &SEC = "1" #&CDS_SEC = "1";
"A":   PN = "1"  !CDS_PN = "1";
"B":   PN = "2"  !CDS_PN = "2";
BODY = "Q_RES","I61": #LOCATION = "R9016" !CDS_LOCATION = "R9016" &SEC = "1" #&CDS_SEC = "1";
"A":   PN = "1"  !CDS_PN = "1";
"B":   PN = "2"  !CDS_PN = "2";
BODY = "Q_RES","I64": #LOCATION = "R3441" !CDS_LOCATION = "R3441" &SEC = "1" #&CDS_SEC = "1";
"A":   PN = "1"  !CDS_PN = "1";
"B":   PN = "2"  !CDS_PN = "2";
BODY = "Q_RES","I65": #LOCATION = "R3440" !CDS_LOCATION = "R3440" &SEC = "1" #&CDS_SEC = "1";
"A":   PN = "1"  !CDS_PN = "1";
"B":   PN = "2"  !CDS_PN = "2";
BODY = "Q_RES","I66": #LOCATION = "R3443" !CDS_LOCATION = "R3443" &SEC = "1" #&CDS_SEC = "1";
"A":   PN = "1"  !CDS_PN = "1";
"B":   PN = "2"  !CDS_PN = "2";
BODY = "Q_RES","I67": #LOCATION = "R3442" !CDS_LOCATION = "R3442" &SEC = "1" #&CDS_SEC = "1";
"A":   PN = "1"  !CDS_PN = "1";
"B":   PN = "2"  !CDS_PN = "2";
BODY = "Q_RES","I69": #LOCATION = "R2656" !CDS_LOCATION = "R2656" &SEC = "1" #&CDS_SEC = "1";
"A":   PN = "1"  !CDS_PN = "1";
"B":   PN = "2"  !CDS_PN = "2";
BODY = "Q_CAP","I71": #LOCATION = "C9002" !CDS_LOCATION = "C9002" &SEC = "1" #&CDS_SEC = "1";
"A":   PN = "1"  !CDS_PN = "1";
"B":   PN = "2"  !CDS_PN = "2";
BODY = "Q_RES","I72": #LOCATION = "R9017" !CDS_LOCATION = "R9017" &SEC = "1" #&CDS_SEC = "1";
"A":   PN = "1"  !CDS_PN = "1";
"B":   PN = "2"  !CDS_PN = "2";
BODY = "MOSFET_NCH_DUAL","I75": #LOCATION = "Q9002" !CDS_LOCATION = "Q9002" &SEC = "2" #&CDS_SEC = "2";
"D2":   PN = "3"  !CDS_PN = "3";
"G2":   PN = "5"  !CDS_PN = "5";
"S2":   PN = "4"  !CDS_PN = "4";
DRAWING = "@t6g_mb_lib.t6g(sch_1):page331";
BODY = "Q_RES","I2": #LOCATION = "R4161" !CDS_LOCATION = "R4161" &SEC = "1" #&CDS_SEC = "1";
"A":   PN = "1"  !CDS_PN = "1";
"B":   PN = "2"  !CDS_PN = "2";
BODY = "Q_RES","I4": #LOCATION = "R4160" !CDS_LOCATION = "R4160" &SEC = "1" #&CDS_SEC = "1";
"A":   PN = "1"  !CDS_PN = "1";
"B":   PN = "2"  !CDS_PN = "2";
BODY = "Q_RES","I8": #LOCATION = "R4163" !CDS_LOCATION = "R4163" &SEC = "1" #&CDS_SEC = "1";
"A":   PN = "1"  !CDS_PN = "1";
"B":   PN = "2"  !CDS_PN = "2";
BODY = "Q_RES","I9": #LOCATION = "R4162" !CDS_LOCATION = "R4162" &SEC = "1" #&CDS_SEC = "1";
"A":   PN = "1"  !CDS_PN = "1";
"B":   PN = "2"  !CDS_PN = "2";
BODY = "Q_RES","I13": #LOCATION = "R4159" !CDS_LOCATION = "R4159" &SEC = "1" #&CDS_SEC = "1";
"A":   PN = "1"  !CDS_PN = "1";
"B":   PN = "2"  !CDS_PN = "2";
BODY = "Q_RES","I14": #LOCATION = "R4158" !CDS_LOCATION = "R4158" &SEC = "1" #&CDS_SEC = "1";
"A":   PN = "1"  !CDS_PN = "1";
"B":   PN = "2"  !CDS_PN = "2";
BODY = "MOSFET_NCH_DUAL","I17": #LOCATION = "Q136" !CDS_LOCATION = "Q136" &SEC = "1" #&CDS_SEC = "1";
"D1":   PN = "6"  !CDS_PN = "6";
"G1":   PN = "2"  !CDS_PN = "2";
"S1":   PN = "1"  !CDS_PN = "1";
BODY = "Q_RES","I18": #LOCATION = "R4165" !CDS_LOCATION = "R4165" &SEC = "1" #&CDS_SEC = "1";
"A":   PN = "1"  !CDS_PN = "1";
"B":   PN = "2"  !CDS_PN = "2";
BODY = "MOSFET_NCH_DUAL","I21": #LOCATION = "Q137" !CDS_LOCATION = "Q137" &SEC = "1" #&CDS_SEC = "1";
"D1":   PN = "6"  !CDS_PN = "6";
"G1":   PN = "2"  !CDS_PN = "2";
"S1":   PN = "1"  !CDS_PN = "1";
BODY = "MOSFET_NCH_DUAL","I22": #LOCATION = "Q136" !CDS_LOCATION = "Q136" &SEC = "2" #&CDS_SEC = "2";
"D2":   PN = "3"  !CDS_PN = "3";
"G2":   PN = "5"  !CDS_PN = "5";
"S2":   PN = "4"  !CDS_PN = "4";
BODY = "Q_RES","I23": #LOCATION = "R4166" !CDS_LOCATION = "R4166" &SEC = "1" #&CDS_SEC = "1";
"A":   PN = "1"  !CDS_PN = "1";
"B":   PN = "2"  !CDS_PN = "2";
BODY = "MOSFET_NCH_DUAL","I25": #LOCATION = "Q135" !CDS_LOCATION = "Q135" &SEC = "1" #&CDS_SEC = "1";
"D1":   PN = "6"  !CDS_PN = "6";
"G1":   PN = "2"  !CDS_PN = "2";
"S1":   PN = "1"  !CDS_PN = "1";
BODY = "Q_RES","I27": #LOCATION = "R4164" !CDS_LOCATION = "R4164" &SEC = "1" #&CDS_SEC = "1";
"A":   PN = "1"  !CDS_PN = "1";
"B":   PN = "2"  !CDS_PN = "2";
BODY = "MOSFET_NCH_DUAL","I28": #LOCATION = "Q137" !CDS_LOCATION = "Q137" &SEC = "2" #&CDS_SEC = "2";
"D2":   PN = "3"  !CDS_PN = "3";
"G2":   PN = "5"  !CDS_PN = "5";
"S2":   PN = "4"  !CDS_PN = "4";
BODY = "MOSFET_NCH_DUAL","I29": #LOCATION = "Q135" !CDS_LOCATION = "Q135" &SEC = "2" #&CDS_SEC = "2";
"D2":   PN = "3"  !CDS_PN = "3";
"G2":   PN = "5"  !CDS_PN = "5";
"S2":   PN = "4"  !CDS_PN = "4";
BODY = "Q_CAP","I33": #LOCATION = "C5" !CDS_LOCATION = "C5" &SEC = "1" #&CDS_SEC = "1";
"A":   PN = "1"  !CDS_PN = "1";
"B":   PN = "2"  !CDS_PN = "2";
BODY = "Q_RES","I35": #LOCATION = "R4168" !CDS_LOCATION = "R4168" &SEC = "1" #&CDS_SEC = "1";
"A":   PN = "1"  !CDS_PN = "1";
"B":   PN = "2"  !CDS_PN = "2";
BODY = "Q_RES","I39": #LOCATION = "R4169" !CDS_LOCATION = "R4169" &SEC = "1" #&CDS_SEC = "1";
"A":   PN = "1"  !CDS_PN = "1";
"B":   PN = "2"  !CDS_PN = "2";
BODY = "Q_CAP","I42": #LOCATION = "C7" !CDS_LOCATION = "C7" &SEC = "1" #&CDS_SEC = "1";
"A":   PN = "1"  !CDS_PN = "1";
"B":   PN = "2"  !CDS_PN = "2";
BODY = "Q_CAP","I44": #LOCATION = "C4" !CDS_LOCATION = "C4" &SEC = "1" #&CDS_SEC = "1";
"A":   PN = "1"  !CDS_PN = "1";
"B":   PN = "2"  !CDS_PN = "2";
BODY = "Q_RES","I47": #LOCATION = "R4167" !CDS_LOCATION = "R4167" &SEC = "1" #&CDS_SEC = "1";
"A":   PN = "1"  !CDS_PN = "1";
"B":   PN = "2"  !CDS_PN = "2";
BODY = "MOSFET_NCH_DUAL","I55": #LOCATION = "Q148" !CDS_LOCATION = "Q148" &SEC = "2" #&CDS_SEC = "2";
"D2":   PN = "3"  !CDS_PN = "3";
"G2":   PN = "5"  !CDS_PN = "5";
"S2":   PN = "4"  !CDS_PN = "4";
BODY = "Q_RES","I57": #LOCATION = "R4545" !CDS_LOCATION = "R4545" &SEC = "1" #&CDS_SEC = "1";
"A":   PN = "1"  !CDS_PN = "1";
"B":   PN = "2"  !CDS_PN = "2";
BODY = "MOSFET_NCH_DUAL","I61": #LOCATION = "Q148" !CDS_LOCATION = "Q148" &SEC = "1" #&CDS_SEC = "1";
"D1":   PN = "6"  !CDS_PN = "6";
"G1":   PN = "2"  !CDS_PN = "2";
"S1":   PN = "1"  !CDS_PN = "1";
BODY = "Q_RES","I62": #LOCATION = "R4544" !CDS_LOCATION = "R4544" &SEC = "1" #&CDS_SEC = "1";
"A":   PN = "1"  !CDS_PN = "1";
"B":   PN = "2"  !CDS_PN = "2";
BODY = "Q_RES","I85": #LOCATION = "R4543" !CDS_LOCATION = "R4543" &SEC = "1" #&CDS_SEC = "1";
"A":   PN = "1"  !CDS_PN = "1";
"B":   PN = "2"  !CDS_PN = "2";
BODY = "74LVC2G17GW","I86": #LOCATION = "U316" !CDS_LOCATION = "U316" #SEC = "1" !CDS_SEC = "1";
"A0":   PN = "1"  !CDS_PN = "1";
"A1":   PN = "3"  !CDS_PN = "3";
"B0":   PN = "6"  !CDS_PN = "6";
"B1":   PN = "4"  !CDS_PN = "4";
"GND":   PN = "2"  !CDS_PN = "2";
"VCC":   PN = "5"  !CDS_PN = "5";
BODY = "Q_RES","I87": #LOCATION = "R4548" !CDS_LOCATION = "R4548" &SEC = "1" #&CDS_SEC = "1";
"A":   PN = "1"  !CDS_PN = "1";
"B":   PN = "2"  !CDS_PN = "2";
BODY = "Q_RES","I89": #LOCATION = "R4547" !CDS_LOCATION = "R4547" &SEC = "1" #&CDS_SEC = "1";
"A":   PN = "1"  !CDS_PN = "1";
"B":   PN = "2"  !CDS_PN = "2";
BODY = "Q_CAP","I93": #LOCATION = "C8" !CDS_LOCATION = "C8" &SEC = "1" #&CDS_SEC = "1";
"A":   PN = "1"  !CDS_PN = "1";
"B":   PN = "2"  !CDS_PN = "2";
BODY = "Q_RES","I97": #LOCATION = "R4550" !CDS_LOCATION = "R4550" &SEC = "1" #&CDS_SEC = "1";
"A":   PN = "1"  !CDS_PN = "1";
"B":   PN = "2"  !CDS_PN = "2";
BODY = "Q_RES","I98": #LOCATION = "R4549" !CDS_LOCATION = "R4549" &SEC = "1" #&CDS_SEC = "1";
"A":   PN = "1"  !CDS_PN = "1";
"B":   PN = "2"  !CDS_PN = "2";
BODY = "Q_RES","I99": #LOCATION = "R4555" !CDS_LOCATION = "R4555" &SEC = "1" #&CDS_SEC = "1";
"A":   PN = "1"  !CDS_PN = "1";
"B":   PN = "2"  !CDS_PN = "2";
BODY = "Q_RES","I107": #LOCATION = "R4569" !CDS_LOCATION = "R4569" &SEC = "1" #&CDS_SEC = "1";
"A":   PN = "1"  !CDS_PN = "1";
"B":   PN = "2"  !CDS_PN = "2";
BODY = "Q_RES","I108": #LOCATION = "R4571" !CDS_LOCATION = "R4571" &SEC = "1" #&CDS_SEC = "1";
"A":   PN = "1"  !CDS_PN = "1";
"B":   PN = "2"  !CDS_PN = "2";
BODY = "Q_RES","I109": #LOCATION = "R4570" !CDS_LOCATION = "R4570" &SEC = "1" #&CDS_SEC = "1";
"A":   PN = "1"  !CDS_PN = "1";
"B":   PN = "2"  !CDS_PN = "2";
BODY = "Q_RES","I110": #LOCATION = "R4546" !CDS_LOCATION = "R4546" &SEC = "1" #&CDS_SEC = "1";
"A":   PN = "1"  !CDS_PN = "1";
"B":   PN = "2"  !CDS_PN = "2";
BODY = "Q_CAP","I111": #LOCATION = "C6" !CDS_LOCATION = "C6" &SEC = "1" #&CDS_SEC = "1";
"A":   PN = "1"  !CDS_PN = "1";
"B":   PN = "2"  !CDS_PN = "2";
DRAWING = "@t6g_mb_lib.t6g(sch_1):page333";
BODY = "Q_RES","I14": #LOCATION = "R2835" !CDS_LOCATION = "R2835" &SEC = "1" #&CDS_SEC = "1";
"A":   PN = "1"  !CDS_PN = "1";
"B":   PN = "2"  !CDS_PN = "2";
BODY = "Q_RES","I18": #LOCATION = "R2834" !CDS_LOCATION = "R2834" &SEC = "1" #&CDS_SEC = "1";
"A":   PN = "1"  !CDS_PN = "1";
"B":   PN = "2"  !CDS_PN = "2";
BODY = "Q_RES","I19": #LOCATION = "R2836" !CDS_LOCATION = "R2836" &SEC = "1" #&CDS_SEC = "1";
"A":   PN = "1"  !CDS_PN = "1";
"B":   PN = "2"  !CDS_PN = "2";
BODY = "Q_RES","I24": #LOCATION = "R2841" !CDS_LOCATION = "R2841" &SEC = "1" #&CDS_SEC = "1";
"A":   PN = "1"  !CDS_PN = "1";
"B":   PN = "2"  !CDS_PN = "2";
BODY = "Q_RES","I30": #LOCATION = "R2842" !CDS_LOCATION = "R2842" &SEC = "1" #&CDS_SEC = "1";
"A":   PN = "1"  !CDS_PN = "1";
"B":   PN = "2"  !CDS_PN = "2";
BODY = "MOSFET_NCH_DUAL","I33": #LOCATION = "Q67" !CDS_LOCATION = "Q67" &SEC = "1" #&CDS_SEC = "1";
"D1":   PN = "6"  !CDS_PN = "6";
"G1":   PN = "2"  !CDS_PN = "2";
"S1":   PN = "1"  !CDS_PN = "1";
BODY = "MOSFET_NCH_DUAL","I35": #LOCATION = "Q70" !CDS_LOCATION = "Q70" &SEC = "1" #&CDS_SEC = "1";
"D1":   PN = "6"  !CDS_PN = "6";
"G1":   PN = "2"  !CDS_PN = "2";
"S1":   PN = "1"  !CDS_PN = "1";
BODY = "MOSFET_NCH_DUAL","I37": #LOCATION = "Q72" !CDS_LOCATION = "Q72" &SEC = "1" #&CDS_SEC = "1";
"D1":   PN = "6"  !CDS_PN = "6";
"G1":   PN = "2"  !CDS_PN = "2";
"S1":   PN = "1"  !CDS_PN = "1";
BODY = "Q_RES","I56": #LOCATION = "R2831" !CDS_LOCATION = "R2831" &SEC = "1" #&CDS_SEC = "1";
"A":   PN = "1"  !CDS_PN = "1";
"B":   PN = "2"  !CDS_PN = "2";
BODY = "Q_RES","I58": #LOCATION = "R2829" !CDS_LOCATION = "R2829" &SEC = "1" #&CDS_SEC = "1";
"A":   PN = "1"  !CDS_PN = "1";
"B":   PN = "2"  !CDS_PN = "2";
BODY = "Q_RES","I60": #LOCATION = "R2833" !CDS_LOCATION = "R2833" &SEC = "1" #&CDS_SEC = "1";
"A":   PN = "1"  !CDS_PN = "1";
"B":   PN = "2"  !CDS_PN = "2";
BODY = "Q_RES","I62": #LOCATION = "R2838" !CDS_LOCATION = "R2838" &SEC = "1" #&CDS_SEC = "1";
"A":   PN = "1"  !CDS_PN = "1";
"B":   PN = "2"  !CDS_PN = "2";
BODY = "Q_RES","I66": #LOCATION = "R2828" !CDS_LOCATION = "R2828" &SEC = "1" #&CDS_SEC = "1";
"A":   PN = "1"  !CDS_PN = "1";
"B":   PN = "2"  !CDS_PN = "2";
BODY = "Q_RES","I67": #LOCATION = "R2832" !CDS_LOCATION = "R2832" &SEC = "1" #&CDS_SEC = "1";
"A":   PN = "1"  !CDS_PN = "1";
"B":   PN = "2"  !CDS_PN = "2";
BODY = "Q_RES","I68": #LOCATION = "R2830" !CDS_LOCATION = "R2830" &SEC = "1" #&CDS_SEC = "1";
"A":   PN = "1"  !CDS_PN = "1";
"B":   PN = "2"  !CDS_PN = "2";
BODY = "Q_RES","I80": #LOCATION = "R2837" !CDS_LOCATION = "R2837" &SEC = "1" #&CDS_SEC = "1";
"A":   PN = "1"  !CDS_PN = "1";
"B":   PN = "2"  !CDS_PN = "2";
BODY = "MOSFET_NCH_DUAL","I82": #LOCATION = "Q67" !CDS_LOCATION = "Q67" &SEC = "2" #&CDS_SEC = "2";
"D2":   PN = "3"  !CDS_PN = "3";
"G2":   PN = "5"  !CDS_PN = "5";
"S2":   PN = "4"  !CDS_PN = "4";
BODY = "MOSFET_NCH_DUAL","I88": #LOCATION = "Q69" !CDS_LOCATION = "Q69" &SEC = "2" #&CDS_SEC = "2";
"D2":   PN = "3"  !CDS_PN = "3";
"G2":   PN = "5"  !CDS_PN = "5";
"S2":   PN = "4"  !CDS_PN = "4";
BODY = "Q_RES","I91": #LOCATION = "R2919" !CDS_LOCATION = "R2919" &SEC = "1" #&CDS_SEC = "1";
"A":   PN = "1"  !CDS_PN = "1";
"B":   PN = "2"  !CDS_PN = "2";
BODY = "Q_CAP","I92": #LOCATION = "C1754" !CDS_LOCATION = "C1754" &SEC = "1" #&CDS_SEC = "1";
"A":   PN = "1"  !CDS_PN = "1";
"B":   PN = "2"  !CDS_PN = "2";
BODY = "MOSFET_NCH_DUAL","I100": #LOCATION = "Q71" !CDS_LOCATION = "Q71" &SEC = "2" #&CDS_SEC = "2";
"D2":   PN = "3"  !CDS_PN = "3";
"G2":   PN = "5"  !CDS_PN = "5";
"S2":   PN = "4"  !CDS_PN = "4";
BODY = "Q_RES","I101": #LOCATION = "R2934" !CDS_LOCATION = "R2934" &SEC = "1" #&CDS_SEC = "1";
"A":   PN = "1"  !CDS_PN = "1";
"B":   PN = "2"  !CDS_PN = "2";
BODY = "Q_CAP","I105": #LOCATION = "C1756" !CDS_LOCATION = "C1756" &SEC = "1" #&CDS_SEC = "1";
"A":   PN = "1"  !CDS_PN = "1";
"B":   PN = "2"  !CDS_PN = "2";
BODY = "Q_RES","I109": #LOCATION = "R2935" !CDS_LOCATION = "R2935" &SEC = "1" #&CDS_SEC = "1";
"A":   PN = "1"  !CDS_PN = "1";
"B":   PN = "2"  !CDS_PN = "2";
BODY = "Q_CAP","I111": #LOCATION = "C1774" !CDS_LOCATION = "C1774" &SEC = "1" #&CDS_SEC = "1";
"A":   PN = "1"  !CDS_PN = "1";
"B":   PN = "2"  !CDS_PN = "2";
BODY = "Q_CAP","I114": #LOCATION = "C1773" !CDS_LOCATION = "C1773" &SEC = "1" #&CDS_SEC = "1";
"A":   PN = "1"  !CDS_PN = "1";
"B":   PN = "2"  !CDS_PN = "2";
BODY = "Q_CAP","I116": #LOCATION = "C1772" !CDS_LOCATION = "C1772" &SEC = "1" #&CDS_SEC = "1";
"A":   PN = "1"  !CDS_PN = "1";
"B":   PN = "2"  !CDS_PN = "2";
BODY = "MOSFET_NCH_DUAL","I117": #LOCATION = "Q69" !CDS_LOCATION = "Q69" &SEC = "1" #&CDS_SEC = "1";
"D1":   PN = "6"  !CDS_PN = "6";
"G1":   PN = "2"  !CDS_PN = "2";
"S1":   PN = "1"  !CDS_PN = "1";
BODY = "MOSFET_NCH_DUAL","I118": #LOCATION = "Q71" !CDS_LOCATION = "Q71" &SEC = "1" #&CDS_SEC = "1";
"D1":   PN = "6"  !CDS_PN = "6";
"G1":   PN = "2"  !CDS_PN = "2";
"S1":   PN = "1"  !CDS_PN = "1";
BODY = "MOSFET_NCH_DUAL","I119": #LOCATION = "Q72" !CDS_LOCATION = "Q72" #SEC = "2" !CDS_SEC = "2";
"D2":   PN = "3"  !CDS_PN = "3";
"G2":   PN = "5"  !CDS_PN = "5";
"S2":   PN = "4"  !CDS_PN = "4";
BODY = "MOSFET_NCH_DUAL","I120": #LOCATION = "Q70" !CDS_LOCATION = "Q70" &SEC = "2" #&CDS_SEC = "2";
"D2":   PN = "3"  !CDS_PN = "3";
"G2":   PN = "5"  !CDS_PN = "5";
"S2":   PN = "4"  !CDS_PN = "4";
BODY = "MOSFET_NCH_DUAL","I121": #LOCATION = "Q74" !CDS_LOCATION = "Q74" #SEC = "1" !CDS_SEC = "1";
"D1":   PN = "6"  !CDS_PN = "6";
"G1":   PN = "2"  !CDS_PN = "2";
"S1":   PN = "1"  !CDS_PN = "1";
BODY = "MOSFET_NCH_DUAL","I122": #LOCATION = "Q74" !CDS_LOCATION = "Q74" #SEC = "2" !CDS_SEC = "2";
"D2":   PN = "3"  !CDS_PN = "3";
"G2":   PN = "5"  !CDS_PN = "5";
"S2":   PN = "4"  !CDS_PN = "4";
BODY = "Q_CAP","I125": #LOCATION = "C1804" !CDS_LOCATION = "C1804" &SEC = "1" #&CDS_SEC = "1";
"A":   PN = "1"  !CDS_PN = "1";
"B":   PN = "2"  !CDS_PN = "2";
BODY = "Q_RES","I129": #LOCATION = "R3034" !CDS_LOCATION = "R3034" &SEC = "1" #&CDS_SEC = "1";
"A":   PN = "1"  !CDS_PN = "1";
"B":   PN = "2"  !CDS_PN = "2";
BODY = "Q_RES","I134": #LOCATION = "R3032" !CDS_LOCATION = "R3032" &SEC = "1" #&CDS_SEC = "1";
"A":   PN = "1"  !CDS_PN = "1";
"B":   PN = "2"  !CDS_PN = "2";
BODY = "Q_RES","I139": #LOCATION = "R3028" !CDS_LOCATION = "R3028" &SEC = "1" #&CDS_SEC = "1";
"A":   PN = "1"  !CDS_PN = "1";
"B":   PN = "2"  !CDS_PN = "2";
BODY = "Q_RES","I144": #LOCATION = "R3029" !CDS_LOCATION = "R3029" &SEC = "1" #&CDS_SEC = "1";
"A":   PN = "1"  !CDS_PN = "1";
"B":   PN = "2"  !CDS_PN = "2";
BODY = "Q_CAP","I148": #LOCATION = "C1802" !CDS_LOCATION = "C1802" &SEC = "1" #&CDS_SEC = "1";
"A":   PN = "1"  !CDS_PN = "1";
"B":   PN = "2"  !CDS_PN = "2";
BODY = "MOSFET_NCH_DUAL","I151": #LOCATION = "Q75" !CDS_LOCATION = "Q75" &SEC = "2" #&CDS_SEC = "2";
"D2":   PN = "3"  !CDS_PN = "3";
"G2":   PN = "5"  !CDS_PN = "5";
"S2":   PN = "4"  !CDS_PN = "4";
BODY = "MOSFET_NCH_DUAL","I152": #LOCATION = "Q75" !CDS_LOCATION = "Q75" &SEC = "1" #&CDS_SEC = "1";
"D1":   PN = "6"  !CDS_PN = "6";
"G1":   PN = "2"  !CDS_PN = "2";
"S1":   PN = "1"  !CDS_PN = "1";
BODY = "MOSFET_NCH_DUAL","I154": #LOCATION = "Q96" !CDS_LOCATION = "Q96" &SEC = "1" #&CDS_SEC = "1";
"D1":   PN = "6"  !CDS_PN = "6";
"G1":   PN = "2"  !CDS_PN = "2";
"S1":   PN = "1"  !CDS_PN = "1";
BODY = "Q_CAP","I156": #LOCATION = "C1881" !CDS_LOCATION = "C1881" &SEC = "1" #&CDS_SEC = "1";
"A":   PN = "1"  !CDS_PN = "1";
"B":   PN = "2"  !CDS_PN = "2";
BODY = "Q_RES","I158": #LOCATION = "R3321" !CDS_LOCATION = "R3321" &SEC = "1" #&CDS_SEC = "1";
"A":   PN = "1"  !CDS_PN = "1";
"B":   PN = "2"  !CDS_PN = "2";
BODY = "MOSFET_NCH_DUAL","I159": #LOCATION = "Q96" !CDS_LOCATION = "Q96" &SEC = "2" #&CDS_SEC = "2";
"D2":   PN = "3"  !CDS_PN = "3";
"G2":   PN = "5"  !CDS_PN = "5";
"S2":   PN = "4"  !CDS_PN = "4";
BODY = "Q_RES","I162": #LOCATION = "R3320" !CDS_LOCATION = "R3320" &SEC = "1" #&CDS_SEC = "1";
"A":   PN = "1"  !CDS_PN = "1";
"B":   PN = "2"  !CDS_PN = "2";
BODY = "Q_RES","I171": #LOCATION = "R3318" !CDS_LOCATION = "R3318" &SEC = "1" #&CDS_SEC = "1";
"A":   PN = "1"  !CDS_PN = "1";
"B":   PN = "2"  !CDS_PN = "2";
BODY = "Q_RES","I172": #LOCATION = "R3511" !CDS_LOCATION = "R3511" &SEC = "1" #&CDS_SEC = "1";
"A":   PN = "1"  !CDS_PN = "1";
"B":   PN = "2"  !CDS_PN = "2";
BODY = "Q_RES","I173": #LOCATION = "R3513" !CDS_LOCATION = "R3513" &SEC = "1" #&CDS_SEC = "1";
"A":   PN = "1"  !CDS_PN = "1";
"B":   PN = "2"  !CDS_PN = "2";
BODY = "Q_RES","I174": #LOCATION = "R3512" !CDS_LOCATION = "R3512" &SEC = "1" #&CDS_SEC = "1";
"A":   PN = "1"  !CDS_PN = "1";
"B":   PN = "2"  !CDS_PN = "2";
BODY = "Q_RES","I175": #LOCATION = "R3514" !CDS_LOCATION = "R3514" &SEC = "1" #&CDS_SEC = "1";
"A":   PN = "1"  !CDS_PN = "1";
"B":   PN = "2"  !CDS_PN = "2";
BODY = "Q_RES","I176": #LOCATION = "R3510" !CDS_LOCATION = "R3510" &SEC = "1" #&CDS_SEC = "1";
"A":   PN = "1"  !CDS_PN = "1";
"B":   PN = "2"  !CDS_PN = "2";
BODY = "Q_RES","I177": #LOCATION = "R2920" !CDS_LOCATION = "R2920" &SEC = "1" #&CDS_SEC = "1";
"A":   PN = "1"  !CDS_PN = "1";
"B":   PN = "2"  !CDS_PN = "2";
BODY = "Q_RES","I178": #LOCATION = "R3030" !CDS_LOCATION = "R3030" &SEC = "1" #&CDS_SEC = "1";
"A":   PN = "1"  !CDS_PN = "1";
"B":   PN = "2"  !CDS_PN = "2";
BODY = "Q_RES","I179": #LOCATION = "R3035" !CDS_LOCATION = "R3035" #SEC = "1" !CDS_SEC = "1";
"A":   PN = "1"  !CDS_PN = "1";
"B":   PN = "2"  !CDS_PN = "2";
BODY = "Q_RES","I180": #LOCATION = "R2933" !CDS_LOCATION = "R2933" &SEC = "1" #&CDS_SEC = "1";
"A":   PN = "1"  !CDS_PN = "1";
"B":   PN = "2"  !CDS_PN = "2";
DRAWING = "@t6g_mb_lib.t6g(sch_1):page334";
BODY = "74LVC2G17GW","I26": #LOCATION = "U253" !CDS_LOCATION = "U253" &SEC = "1" #&CDS_SEC = "1";
"A0":   PN = "1"  !CDS_PN = "1";
"A1":   PN = "3"  !CDS_PN = "3";
"B0":   PN = "6"  !CDS_PN = "6";
"B1":   PN = "4"  !CDS_PN = "4";
"GND":   PN = "2"  !CDS_PN = "2";
"VCC":   PN = "5"  !CDS_PN = "5";
BODY = "Q_CAP","I29": #LOCATION = "C1958" !CDS_LOCATION = "C1958" &SEC = "1" #&CDS_SEC = "1";
"A":   PN = "1"  !CDS_PN = "1";
"B":   PN = "2"  !CDS_PN = "2";
BODY = "Q_RES","I62": #LOCATION = "R3392" !CDS_LOCATION = "R3392" &SEC = "1" #&CDS_SEC = "1";
"A":   PN = "1"  !CDS_PN = "1";
"B":   PN = "2"  !CDS_PN = "2";
BODY = "Q_RES","I95": #LOCATION = "R3452" !CDS_LOCATION = "R3452" &SEC = "1" #&CDS_SEC = "1";
"A":   PN = "1"  !CDS_PN = "1";
"B":   PN = "2"  !CDS_PN = "2";
BODY = "Q_RES","I123": #LOCATION = "R3457" !CDS_LOCATION = "R3457" &SEC = "1" #&CDS_SEC = "1";
"A":   PN = "1"  !CDS_PN = "1";
"B":   PN = "2"  !CDS_PN = "2";
BODY = "Q_RES","I124": #LOCATION = "R3456" !CDS_LOCATION = "R3456" &SEC = "1" #&CDS_SEC = "1";
"A":   PN = "1"  !CDS_PN = "1";
"B":   PN = "2"  !CDS_PN = "2";
BODY = "Q_RES","I127": #LOCATION = "R3451" !CDS_LOCATION = "R3451" &SEC = "1" #&CDS_SEC = "1";
"A":   PN = "1"  !CDS_PN = "1";
"B":   PN = "2"  !CDS_PN = "2";
BODY = "Q_RES","I139": #LOCATION = "R3455" !CDS_LOCATION = "R3455" &SEC = "1" #&CDS_SEC = "1";
"A":   PN = "1"  !CDS_PN = "1";
"B":   PN = "2"  !CDS_PN = "2";
BODY = "Q_RES","I140": #LOCATION = "R3391" !CDS_LOCATION = "R3391" &SEC = "1" #&CDS_SEC = "1";
"A":   PN = "1"  !CDS_PN = "1";
"B":   PN = "2"  !CDS_PN = "2";
BODY = "Q_CAP","I148": #LOCATION = "C1957" !CDS_LOCATION = "C1957" &SEC = "1" #&CDS_SEC = "1";
"A":   PN = "1"  !CDS_PN = "1";
"B":   PN = "2"  !CDS_PN = "2";
BODY = "74LVC2G17GW","I153": #LOCATION = "U252" !CDS_LOCATION = "U252" &SEC = "1" #&CDS_SEC = "1";
"A0":   PN = "1"  !CDS_PN = "1";
"A1":   PN = "3"  !CDS_PN = "3";
"B0":   PN = "6"  !CDS_PN = "6";
"B1":   PN = "4"  !CDS_PN = "4";
"GND":   PN = "2"  !CDS_PN = "2";
"VCC":   PN = "5"  !CDS_PN = "5";
BODY = "Q_RES","I162": #LOCATION = "R3390" !CDS_LOCATION = "R3390" &SEC = "1" #&CDS_SEC = "1";
"A":   PN = "1"  !CDS_PN = "1";
"B":   PN = "2"  !CDS_PN = "2";
BODY = "Q_RES","I164": #LOCATION = "R3453" !CDS_LOCATION = "R3453" &SEC = "1" #&CDS_SEC = "1";
"A":   PN = "1"  !CDS_PN = "1";
"B":   PN = "2"  !CDS_PN = "2";
BODY = "Q_RES","I165": #LOCATION = "R3454" !CDS_LOCATION = "R3454" &SEC = "1" #&CDS_SEC = "1";
"A":   PN = "1"  !CDS_PN = "1";
"B":   PN = "2"  !CDS_PN = "2";
BODY = "Q_RES","I168": #LOCATION = "R3448" !CDS_LOCATION = "R3448" &SEC = "1" #&CDS_SEC = "1";
"A":   PN = "1"  !CDS_PN = "1";
"B":   PN = "2"  !CDS_PN = "2";
BODY = "Q_RES","I170": #LOCATION = "R3449" !CDS_LOCATION = "R3449" &SEC = "1" #&CDS_SEC = "1";
"A":   PN = "1"  !CDS_PN = "1";
"B":   PN = "2"  !CDS_PN = "2";
BODY = "74LVC2G17GW","I173": #LOCATION = "U256" !CDS_LOCATION = "U256" &SEC = "1" #&CDS_SEC = "1";
"A0":   PN = "1"  !CDS_PN = "1";
"A1":   PN = "3"  !CDS_PN = "3";
"B0":   PN = "6"  !CDS_PN = "6";
"B1":   PN = "4"  !CDS_PN = "4";
"GND":   PN = "2"  !CDS_PN = "2";
"VCC":   PN = "5"  !CDS_PN = "5";
BODY = "Q_CAP","I175": #LOCATION = "C1977" !CDS_LOCATION = "C1977" &SEC = "1" #&CDS_SEC = "1";
"A":   PN = "1"  !CDS_PN = "1";
"B":   PN = "2"  !CDS_PN = "2";
BODY = "Q_RES","I180": #LOCATION = "R3469" !CDS_LOCATION = "R3469" &SEC = "1" #&CDS_SEC = "1";
"A":   PN = "1"  !CDS_PN = "1";
"B":   PN = "2"  !CDS_PN = "2";
BODY = "Q_RES","I181": #LOCATION = "R3467" !CDS_LOCATION = "R3467" &SEC = "1" #&CDS_SEC = "1";
"A":   PN = "1"  !CDS_PN = "1";
"B":   PN = "2"  !CDS_PN = "2";
BODY = "Q_RES","I183": #LOCATION = "R3468" !CDS_LOCATION = "R3468" &SEC = "1" #&CDS_SEC = "1";
"A":   PN = "1"  !CDS_PN = "1";
"B":   PN = "2"  !CDS_PN = "2";
BODY = "Q_RES","I184": #LOCATION = "R3466" !CDS_LOCATION = "R3466" &SEC = "1" #&CDS_SEC = "1";
"A":   PN = "1"  !CDS_PN = "1";
"B":   PN = "2"  !CDS_PN = "2";
BODY = "Q_RES","I187": #LOCATION = "R2910" !CDS_LOCATION = "R2910" &SEC = "1" #&CDS_SEC = "1";
"A":   PN = "1"  !CDS_PN = "1";
"B":   PN = "2"  !CDS_PN = "2";
BODY = "Q_RES","I188": #LOCATION = "R2918" !CDS_LOCATION = "R2918" &SEC = "1" #&CDS_SEC = "1";
"A":   PN = "1"  !CDS_PN = "1";
"B":   PN = "2"  !CDS_PN = "2";
BODY = "Q_RES","I192": #LOCATION = "R2914" !CDS_LOCATION = "R2914" &SEC = "1" #&CDS_SEC = "1";
"A":   PN = "1"  !CDS_PN = "1";
"B":   PN = "2"  !CDS_PN = "2";
BODY = "Q_RES","I193": #LOCATION = "R3515" !CDS_LOCATION = "R3515" &SEC = "1" #&CDS_SEC = "1";
"A":   PN = "1"  !CDS_PN = "1";
"B":   PN = "2"  !CDS_PN = "2";
BODY = "Q_RES","I195": #LOCATION = "R2932" !CDS_LOCATION = "R2932" &SEC = "1" #&CDS_SEC = "1";
"A":   PN = "1"  !CDS_PN = "1";
"B":   PN = "2"  !CDS_PN = "2";
DRAWING = "@t6g_mb_lib.t6g(sch_1):page255";
BODY = "Q_CAP","I13": #LOCATION = "C1963" !CDS_LOCATION = "C1963" &SEC = "1" #&CDS_SEC = "1";
"A":   PN = "1"  !CDS_PN = "1";
"B":   PN = "2"  !CDS_PN = "2";
BODY = "74LVC2G07DW7","I16": #LOCATION = "U255" !CDS_LOCATION = "U255" &SEC = "1" #&CDS_SEC = "1";
"1A":   PN = "1"  !CDS_PN = "1";
"1Y":   PN = "6"  !CDS_PN = "6";
"2A":   PN = "3"  !CDS_PN = "3";
"2Y":   PN = "4"  !CDS_PN = "4";
"GND":   PN = "2"  !CDS_PN = "2";
"VCC":   PN = "5"  !CDS_PN = "5";
BODY = "Q_RES","I31": #LOCATION = "R3460" !CDS_LOCATION = "R3460" &SEC = "1" #&CDS_SEC = "1";
"A":   PN = "1"  !CDS_PN = "1";
"B":   PN = "2"  !CDS_PN = "2";
BODY = "Q_RES","I33": #LOCATION = "R3462" !CDS_LOCATION = "R3462" &SEC = "1" #&CDS_SEC = "1";
"A":   PN = "1"  !CDS_PN = "1";
"B":   PN = "2"  !CDS_PN = "2";
BODY = "Q_RES","I35": #LOCATION = "R3461" !CDS_LOCATION = "R3461" &SEC = "1" #&CDS_SEC = "1";
"A":   PN = "1"  !CDS_PN = "1";
"B":   PN = "2"  !CDS_PN = "2";
BODY = "Q_RES","I37": #LOCATION = "R3397" !CDS_LOCATION = "R3397" &SEC = "1" #&CDS_SEC = "1";
"A":   PN = "1"  !CDS_PN = "1";
"B":   PN = "2"  !CDS_PN = "2";
BODY = "Q_RES","I40": #LOCATION = "R3488" !CDS_LOCATION = "R3488" &SEC = "1" #&CDS_SEC = "1";
"A":   PN = "1"  !CDS_PN = "1";
"B":   PN = "2"  !CDS_PN = "2";
BODY = "Q_RES","I42": #LOCATION = "R3489" !CDS_LOCATION = "R3489" &SEC = "1" #&CDS_SEC = "1";
"A":   PN = "1"  !CDS_PN = "1";
"B":   PN = "2"  !CDS_PN = "2";
BODY = "Q_RES","I45": #LOCATION = "R3496" !CDS_LOCATION = "R3496" &SEC = "1" #&CDS_SEC = "1";
"A":   PN = "1"  !CDS_PN = "1";
"B":   PN = "2"  !CDS_PN = "2";
BODY = "Q_RES","I47": #LOCATION = "R3492" !CDS_LOCATION = "R3492" &SEC = "1" #&CDS_SEC = "1";
"A":   PN = "1"  !CDS_PN = "1";
"B":   PN = "2"  !CDS_PN = "2";
BODY = "Q_RES","I48": #LOCATION = "R3493" !CDS_LOCATION = "R3493" &SEC = "1" #&CDS_SEC = "1";
"A":   PN = "1"  !CDS_PN = "1";
"B":   PN = "2"  !CDS_PN = "2";
BODY = "74LVC2G07DW7","I50": #LOCATION = "U257" !CDS_LOCATION = "U257" &SEC = "1" #&CDS_SEC = "1";
"1A":   PN = "1"  !CDS_PN = "1";
"1Y":   PN = "6"  !CDS_PN = "6";
"2A":   PN = "3"  !CDS_PN = "3";
"2Y":   PN = "4"  !CDS_PN = "4";
"GND":   PN = "2"  !CDS_PN = "2";
"VCC":   PN = "5"  !CDS_PN = "5";
BODY = "Q_RES","I53": #LOCATION = "R3497" !CDS_LOCATION = "R3497" &SEC = "1" #&CDS_SEC = "1";
"A":   PN = "1"  !CDS_PN = "1";
"B":   PN = "2"  !CDS_PN = "2";
BODY = "Q_RES","I55": #LOCATION = "R3494" !CDS_LOCATION = "R3494" &SEC = "1" #&CDS_SEC = "1";
"A":   PN = "1"  !CDS_PN = "1";
"B":   PN = "2"  !CDS_PN = "2";
BODY = "Q_RES","I57": #LOCATION = "R3490" !CDS_LOCATION = "R3490" &SEC = "1" #&CDS_SEC = "1";
"A":   PN = "1"  !CDS_PN = "1";
"B":   PN = "2"  !CDS_PN = "2";
BODY = "Q_RES","I62": #LOCATION = "R3495" !CDS_LOCATION = "R3495" &SEC = "1" #&CDS_SEC = "1";
"A":   PN = "1"  !CDS_PN = "1";
"B":   PN = "2"  !CDS_PN = "2";
BODY = "Q_CAP","I67": #LOCATION = "C1979" !CDS_LOCATION = "C1979" &SEC = "1" #&CDS_SEC = "1";
"A":   PN = "1"  !CDS_PN = "1";
"B":   PN = "2"  !CDS_PN = "2";
BODY = "Q_RES","I70": #LOCATION = "R3491" !CDS_LOCATION = "R3491" &SEC = "1" #&CDS_SEC = "1";
"A":   PN = "1"  !CDS_PN = "1";
"B":   PN = "2"  !CDS_PN = "2";
BODY = "Q_RES","I75": #LOCATION = "R3459" !CDS_LOCATION = "R3459" &SEC = "1" #&CDS_SEC = "1";
"A":   PN = "1"  !CDS_PN = "1";
"B":   PN = "2"  !CDS_PN = "2";
DRAWING = "@t6g_mb_lib.t6g(sch_1):page256";
BODY = "74LVC2G17GW","I65": #LOCATION = "U195" !CDS_LOCATION = "U195" &SEC = "1" #&CDS_SEC = "1";
"A0":   PN = "1"  !CDS_PN = "1";
"A1":   PN = "3"  !CDS_PN = "3";
"B0":   PN = "6"  !CDS_PN = "6";
"B1":   PN = "4"  !CDS_PN = "4";
"GND":   PN = "2"  !CDS_PN = "2";
"VCC":   PN = "5"  !CDS_PN = "5";
BODY = "Q_RES","I68": #LOCATION = "R2815" !CDS_LOCATION = "R2815" &SEC = "1" #&CDS_SEC = "1";
"A":   PN = "1"  !CDS_PN = "1";
"B":   PN = "2"  !CDS_PN = "2";
BODY = "Q_RES","I78": #LOCATION = "R2820" !CDS_LOCATION = "R2820" &SEC = "1" #&CDS_SEC = "1";
"A":   PN = "1"  !CDS_PN = "1";
"B":   PN = "2"  !CDS_PN = "2";
BODY = "Q_CAP","I89": #LOCATION = "C1769" !CDS_LOCATION = "C1769" &SEC = "1" #&CDS_SEC = "1";
"A":   PN = "1"  !CDS_PN = "1";
"B":   PN = "2"  !CDS_PN = "2";
BODY = "Q_RES","I92": #LOCATION = "R2915" !CDS_LOCATION = "R2915" &SEC = "1" #&CDS_SEC = "1";
"A":   PN = "1"  !CDS_PN = "1";
"B":   PN = "2"  !CDS_PN = "2";
BODY = "Q_RES","I93": #LOCATION = "R2916" !CDS_LOCATION = "R2916" &SEC = "1" #&CDS_SEC = "1";
"A":   PN = "1"  !CDS_PN = "1";
"B":   PN = "2"  !CDS_PN = "2";
BODY = "Q_RES","I121": #LOCATION = "R2926" !CDS_LOCATION = "R2926" &SEC = "1" #&CDS_SEC = "1";
"A":   PN = "1"  !CDS_PN = "1";
"B":   PN = "2"  !CDS_PN = "2";
BODY = "74LVC2G17GW","I127": #LOCATION = "U196" !CDS_LOCATION = "U196" &SEC = "1" #&CDS_SEC = "1";
"A0":   PN = "1"  !CDS_PN = "1";
"A1":   PN = "3"  !CDS_PN = "3";
"B0":   PN = "6"  !CDS_PN = "6";
"B1":   PN = "4"  !CDS_PN = "4";
"GND":   PN = "2"  !CDS_PN = "2";
"VCC":   PN = "5"  !CDS_PN = "5";
BODY = "Q_CAP","I140": #LOCATION = "C1770" !CDS_LOCATION = "C1770" &SEC = "1" #&CDS_SEC = "1";
"A":   PN = "1"  !CDS_PN = "1";
"B":   PN = "2"  !CDS_PN = "2";
BODY = "Q_RES","I147": #LOCATION = "R2912" !CDS_LOCATION = "R2912" &SEC = "1" #&CDS_SEC = "1";
"A":   PN = "1"  !CDS_PN = "1";
"B":   PN = "2"  !CDS_PN = "2";
BODY = "Q_RES","I153": #LOCATION = "R2911" !CDS_LOCATION = "R2911" &SEC = "1" #&CDS_SEC = "1";
"A":   PN = "1"  !CDS_PN = "1";
"B":   PN = "2"  !CDS_PN = "2";
BODY = "Q_RES","I154": #LOCATION = "R2917" !CDS_LOCATION = "R2917" &SEC = "1" #&CDS_SEC = "1";
"A":   PN = "1"  !CDS_PN = "1";
"B":   PN = "2"  !CDS_PN = "2";
BODY = "Q_RES","I155": #LOCATION = "R2924" !CDS_LOCATION = "R2924" &SEC = "1" #&CDS_SEC = "1";
"A":   PN = "1"  !CDS_PN = "1";
"B":   PN = "2"  !CDS_PN = "2";
BODY = "Q_RES","I156": #LOCATION = "R2925" !CDS_LOCATION = "R2925" &SEC = "1" #&CDS_SEC = "1";
"A":   PN = "1"  !CDS_PN = "1";
"B":   PN = "2"  !CDS_PN = "2";
BODY = "Q_RES","I160": #LOCATION = "R2937" !CDS_LOCATION = "R2937" &SEC = "1" #&CDS_SEC = "1";
"A":   PN = "1"  !CDS_PN = "1";
"B":   PN = "2"  !CDS_PN = "2";
BODY = "Q_RES","I162": #LOCATION = "R2936" !CDS_LOCATION = "R2936" &SEC = "1" #&CDS_SEC = "1";
"A":   PN = "1"  !CDS_PN = "1";
"B":   PN = "2"  !CDS_PN = "2";
BODY = "Q_CAP","I166": #LOCATION = "C1803" !CDS_LOCATION = "C1803" &SEC = "1" #&CDS_SEC = "1";
"A":   PN = "1"  !CDS_PN = "1";
"B":   PN = "2"  !CDS_PN = "2";
BODY = "Q_RES","I170": #LOCATION = "R3033" !CDS_LOCATION = "R3033" &SEC = "1" #&CDS_SEC = "1";
"A":   PN = "1"  !CDS_PN = "1";
"B":   PN = "2"  !CDS_PN = "2";
BODY = "Q_RES","I171": #LOCATION = "R3063" !CDS_LOCATION = "R3063" &SEC = "1" #&CDS_SEC = "1";
"A":   PN = "1"  !CDS_PN = "1";
"B":   PN = "2"  !CDS_PN = "2";
BODY = "Q_RES","I181": #LOCATION = "R3315" !CDS_LOCATION = "R3315" &SEC = "1" #&CDS_SEC = "1";
"A":   PN = "1"  !CDS_PN = "1";
"B":   PN = "2"  !CDS_PN = "2";
BODY = "Q_RES","I190": #LOCATION = "R3317" !CDS_LOCATION = "R3317" &SEC = "1" #&CDS_SEC = "1";
"A":   PN = "1"  !CDS_PN = "1";
"B":   PN = "2"  !CDS_PN = "2";
BODY = "Q_RES","I191": #LOCATION = "R3509" !CDS_LOCATION = "R3509" &SEC = "1" #&CDS_SEC = "1";
"A":   PN = "1"  !CDS_PN = "1";
"B":   PN = "2"  !CDS_PN = "2";
BODY = "Q_RES","I192": #LOCATION = "R3507" !CDS_LOCATION = "R3507" &SEC = "1" #&CDS_SEC = "1";
"A":   PN = "1"  !CDS_PN = "1";
"B":   PN = "2"  !CDS_PN = "2";
BODY = "Q_RES","I193": #LOCATION = "R3506" !CDS_LOCATION = "R3506" &SEC = "1" #&CDS_SEC = "1";
"A":   PN = "1"  !CDS_PN = "1";
"B":   PN = "2"  !CDS_PN = "2";
BODY = "Q_RES","I194": #LOCATION = "R3508" !CDS_LOCATION = "R3508" &SEC = "1" #&CDS_SEC = "1";
"A":   PN = "1"  !CDS_PN = "1";
"B":   PN = "2"  !CDS_PN = "2";
BODY = "74LVC1G126SE7","I195": #LOCATION = "U204" !CDS_LOCATION = "U204" &SEC = "1" #&CDS_SEC = "1";
"A":   PN = "2"  !CDS_PN = "2";
"GND":   PN = "3"  !CDS_PN = "3";
"OE":   PN = "1"  !CDS_PN = "1";
"VCC":   PN = "5"  !CDS_PN = "5";
"Y":   PN = "4"  !CDS_PN = "4";
BODY = "Q_RES","I197": #LOCATION = "R3036" !CDS_LOCATION = "R3036" &SEC = "1" #&CDS_SEC = "1";
"A":   PN = "1"  !CDS_PN = "1";
"B":   PN = "2"  !CDS_PN = "2";
BODY = "Q_RES","I198": #LOCATION = "R2909" !CDS_LOCATION = "R2909" &SEC = "1" #&CDS_SEC = "1";
"A":   PN = "1"  !CDS_PN = "1";
"B":   PN = "2"  !CDS_PN = "2";
BODY = "Q_RES","I200": #LOCATION = "R4515" !CDS_LOCATION = "R4515" &SEC = "1" #&CDS_SEC = "1";
"A":   PN = "1"  !CDS_PN = "1";
"B":   PN = "2"  !CDS_PN = "2";
BODY = "Q_RES","I203": #LOCATION = "R2927" !CDS_LOCATION = "R2927" &SEC = "1" #&CDS_SEC = "1";
"A":   PN = "1"  !CDS_PN = "1";
"B":   PN = "2"  !CDS_PN = "2";
BODY = "Q_RES","I204": #LOCATION = "R4173" !CDS_LOCATION = "R4173" &SEC = "1" #&CDS_SEC = "1";
"A":   PN = "1"  !CDS_PN = "1";
"B":   PN = "2"  !CDS_PN = "2";
DRAWING = "@t6g_mb_lib.t6g(sch_1):page307";
BODY = "Q_RES","I15": #LOCATION = "R3207" !CDS_LOCATION = "R3207" &SEC = "1" #&CDS_SEC = "1";
"A":   PN = "1"  !CDS_PN = "1";
"B":   PN = "2"  !CDS_PN = "2";
BODY = "Q_CAP","I17": #LOCATION = "C1825" !CDS_LOCATION = "C1825" &SEC = "1" #&CDS_SEC = "1";
"A":   PN = "1"  !CDS_PN = "1";
"B":   PN = "2"  !CDS_PN = "2";
BODY = "74CBTLV3126PW","I32": #LOCATION = "U222" !CDS_LOCATION = "U222" &SEC = "1" #&CDS_SEC = "1";
"1A":   PN = "2"  !CDS_PN = "2";
"1B":   PN = "3"  !CDS_PN = "3";
"1OE":   PN = "1"  !CDS_PN = "1";
"2A":   PN = "5"  !CDS_PN = "5";
"2B":   PN = "6"  !CDS_PN = "6";
"2OE":   PN = "4"  !CDS_PN = "4";
"3A":   PN = "9"  !CDS_PN = "9";
"3B":   PN = "8"  !CDS_PN = "8";
"3OE":   PN = "10"  !CDS_PN = "10";
"4A":   PN = "12"  !CDS_PN = "12";
"4B":   PN = "11"  !CDS_PN = "11";
"4OE":   PN = "13"  !CDS_PN = "13";
"GND":   PN = "7"  !CDS_PN = "7";
"VCC":   PN = "14"  !CDS_PN = "14";
BODY = "Q_CAP","I33": #LOCATION = "C1826" !CDS_LOCATION = "C1826" &SEC = "1" #&CDS_SEC = "1";
"A":   PN = "1"  !CDS_PN = "1";
"B":   PN = "2"  !CDS_PN = "2";
BODY = "Q_RES","I37": #LOCATION = "R3208" !CDS_LOCATION = "R3208" &SEC = "1" #&CDS_SEC = "1";
"A":   PN = "1"  !CDS_PN = "1";
"B":   PN = "2"  !CDS_PN = "2";
BODY = "Q_RES","I38": #LOCATION = "R3216" !CDS_LOCATION = "R3216" &SEC = "1" #&CDS_SEC = "1";
"A":   PN = "1"  !CDS_PN = "1";
"B":   PN = "2"  !CDS_PN = "2";
BODY = "Q_RES","I40": #LOCATION = "R3217" !CDS_LOCATION = "R3217" &SEC = "1" #&CDS_SEC = "1";
"A":   PN = "1"  !CDS_PN = "1";
"B":   PN = "2"  !CDS_PN = "2";
BODY = "Q_RES","I56": #LOCATION = "R3215" !CDS_LOCATION = "R3215" &SEC = "1" #&CDS_SEC = "1";
"A":   PN = "1"  !CDS_PN = "1";
"B":   PN = "2"  !CDS_PN = "2";
BODY = "Q_RES","I60": #LOCATION = "R3214" !CDS_LOCATION = "R3214" &SEC = "1" #&CDS_SEC = "1";
"A":   PN = "1"  !CDS_PN = "1";
"B":   PN = "2"  !CDS_PN = "2";
BODY = "Q_RES","I61": #LOCATION = "R3213" !CDS_LOCATION = "R3213" &SEC = "1" #&CDS_SEC = "1";
"A":   PN = "1"  !CDS_PN = "1";
"B":   PN = "2"  !CDS_PN = "2";
BODY = "Q_RES","I62": #LOCATION = "R3212" !CDS_LOCATION = "R3212" &SEC = "1" #&CDS_SEC = "1";
"A":   PN = "1"  !CDS_PN = "1";
"B":   PN = "2"  !CDS_PN = "2";
BODY = "Q_RES","I63": #LOCATION = "R3211" !CDS_LOCATION = "R3211" &SEC = "1" #&CDS_SEC = "1";
"A":   PN = "1"  !CDS_PN = "1";
"B":   PN = "2"  !CDS_PN = "2";
BODY = "Q_RES","I64": #LOCATION = "R3209" !CDS_LOCATION = "R3209" &SEC = "1" #&CDS_SEC = "1";
"A":   PN = "1"  !CDS_PN = "1";
"B":   PN = "2"  !CDS_PN = "2";
BODY = "Q_RES","I65": #LOCATION = "R3210" !CDS_LOCATION = "R3210" &SEC = "1" #&CDS_SEC = "1";
"A":   PN = "1"  !CDS_PN = "1";
"B":   PN = "2"  !CDS_PN = "2";
BODY = "Q_CAP","I77": #LOCATION = "C1827" !CDS_LOCATION = "C1827" &SEC = "1" #&CDS_SEC = "1";
"A":   PN = "1"  !CDS_PN = "1";
"B":   PN = "2"  !CDS_PN = "2";
BODY = "74CBTLV3126PW","I78": #LOCATION = "U223" !CDS_LOCATION = "U223" &SEC = "1" #&CDS_SEC = "1";
"1A":   PN = "2"  !CDS_PN = "2";
"1B":   PN = "3"  !CDS_PN = "3";
"1OE":   PN = "1"  !CDS_PN = "1";
"2A":   PN = "5"  !CDS_PN = "5";
"2B":   PN = "6"  !CDS_PN = "6";
"2OE":   PN = "4"  !CDS_PN = "4";
"3A":   PN = "9"  !CDS_PN = "9";
"3B":   PN = "8"  !CDS_PN = "8";
"3OE":   PN = "10"  !CDS_PN = "10";
"4A":   PN = "12"  !CDS_PN = "12";
"4B":   PN = "11"  !CDS_PN = "11";
"4OE":   PN = "13"  !CDS_PN = "13";
"GND":   PN = "7"  !CDS_PN = "7";
"VCC":   PN = "14"  !CDS_PN = "14";
BODY = "Q_RES","I79": #LOCATION = "R3244" !CDS_LOCATION = "R3244" &SEC = "1" #&CDS_SEC = "1";
"A":   PN = "1"  !CDS_PN = "1";
"B":   PN = "2"  !CDS_PN = "2";
BODY = "74LVC1G126SE7","I80": #LOCATION = "U286" !CDS_LOCATION = "U286" &SEC = "1" #&CDS_SEC = "1";
"A":   PN = "2"  !CDS_PN = "2";
"GND":   PN = "3"  !CDS_PN = "3";
"OE":   PN = "1"  !CDS_PN = "1";
"VCC":   PN = "5"  !CDS_PN = "5";
"Y":   PN = "4"  !CDS_PN = "4";
BODY = "Q_RES","I81": #LOCATION = "R3203" !CDS_LOCATION = "R3203" &SEC = "1" #&CDS_SEC = "1";
"A":   PN = "1"  !CDS_PN = "1";
"B":   PN = "2"  !CDS_PN = "2";
BODY = "Q_RES","I85": #LOCATION = "R3206" !CDS_LOCATION = "R3206" &SEC = "1" #&CDS_SEC = "1";
"A":   PN = "1"  !CDS_PN = "1";
"B":   PN = "2"  !CDS_PN = "2";
BODY = "Q_RES","I86": #LOCATION = "R3205" !CDS_LOCATION = "R3205" &SEC = "1" #&CDS_SEC = "1";
"A":   PN = "1"  !CDS_PN = "1";
"B":   PN = "2"  !CDS_PN = "2";
DRAWING = "@t6g_mb_lib.t6g(sch_1):page335";
BODY = "Q_RES","I2": #LOCATION = "R32" !CDS_LOCATION = "R32" &SEC = "1" #&CDS_SEC = "1";
"A":   PN = "1"  !CDS_PN = "1";
"B":   PN = "2"  !CDS_PN = "2";
BODY = "Q_RES","I6": #LOCATION = "R3132" !CDS_LOCATION = "R3132" &SEC = "1" #&CDS_SEC = "1";
"A":   PN = "1"  !CDS_PN = "1";
"B":   PN = "2"  !CDS_PN = "2";
BODY = "Q_RES","I54": #LOCATION = "R1671" !CDS_LOCATION = "R1671" &SEC = "1" #&CDS_SEC = "1";
"A":   PN = "1"  !CDS_PN = "1";
"B":   PN = "2"  !CDS_PN = "2";
BODY = "Q_CAP","I89": #LOCATION = "C21" !CDS_LOCATION = "C21" &SEC = "1" #&CDS_SEC = "1";
"A":   PN = "1"  !CDS_PN = "1";
"B":   PN = "2"  !CDS_PN = "2";
BODY = "Q_CAP","I90": #LOCATION = "C1235" !CDS_LOCATION = "C1235" &SEC = "1" #&CDS_SEC = "1";
"A":   PN = "1"  !CDS_PN = "1";
"B":   PN = "2"  !CDS_PN = "2";
BODY = "Q_CAP","I110": #LOCATION = "C1237" !CDS_LOCATION = "C1237" &SEC = "1" #&CDS_SEC = "1";
"A":   PN = "1"  !CDS_PN = "1";
"B":   PN = "2"  !CDS_PN = "2";
BODY = "Q_CAP","I111": #LOCATION = "C1238" !CDS_LOCATION = "C1238" &SEC = "1" #&CDS_SEC = "1";
"A":   PN = "1"  !CDS_PN = "1";
"B":   PN = "2"  !CDS_PN = "2";
BODY = "Q_CAP","I114": #LOCATION = "C1240" !CDS_LOCATION = "C1240" &SEC = "1" #&CDS_SEC = "1";
"A":   PN = "1"  !CDS_PN = "1";
"B":   PN = "2"  !CDS_PN = "2";
BODY = "SCONN168_ME1016810202011","I168": #LOCATION = "J38" !CDS_LOCATION = "J38" #SEC = "1" !CDS_SEC = "1";
"+3.3V_EDGE":   PN = "B11"  !CDS_PN = "B11";
"+12V_EDGE_B1":   PN = "B1"  !CDS_PN = "B1";
"+12V_EDGE_B2":   PN = "B2"  !CDS_PN = "B2";
"+12V_EDGE_B3":   PN = "B3"  !CDS_PN = "B3";
"+12V_EDGE_B4":   PN = "B4"  !CDS_PN = "B4";
"+12V_EDGE_B5":   PN = "B5"  !CDS_PN = "B5";
"+12V_EDGE_B6":   PN = "B6"  !CDS_PN = "B6";
"AUX_PWR_EN":   PN = "B12"  !CDS_PN = "B12";
"BIF0#":   PN = "B7"  !CDS_PN = "B7";
"BIF1#":   PN = "B8"  !CDS_PN = "B8";
"BIF2#":   PN = "B9"  !CDS_PN = "B9";
"CLK":   PN = "OB6"  !CDS_PN = "OB6";
"DATA_IN":   PN = "OB4"  !CDS_PN = "OB4";
"DATA_OUT":   PN = "OB5"  !CDS_PN = "OB5";
"G1":   PN = "G1"  !CDS_PN = "G1";
"G2":   PN = "G2"  !CDS_PN = "G2";
"G3":   PN = "G3"  !CDS_PN = "G3";
"G4":   PN = "G4"  !CDS_PN = "G4";
"G5":   PN = "G5"  !CDS_PN = "G5";
"GND_A1":   PN = "A1"  !CDS_PN = "A1";
"GND_A2":   PN = "A2"  !CDS_PN = "A2";
"GND_A3":   PN = "A3"  !CDS_PN = "A3";
"GND_A4":   PN = "A4"  !CDS_PN = "A4";
"GND_A5":   PN = "A5"  !CDS_PN = "A5";
"GND_A6":   PN = "A6"  !CDS_PN = "A6";
"GND_A13":   PN = "A13"  !CDS_PN = "A13";
"GND_A16":   PN = "A16"  !CDS_PN = "A16";
"GND_A19":   PN = "A19"  !CDS_PN = "A19";
"GND_A22":   PN = "A22"  !CDS_PN = "A22";
"GND_A25":   PN = "A25"  !CDS_PN = "A25";
"GND_A28":   PN = "A28"  !CDS_PN = "A28";
"GND_A29":   PN = "A29"  !CDS_PN = "A29";
"GND_A32":   PN = "A32"  !CDS_PN = "A32";
"GND_A35":   PN = "A35"  !CDS_PN = "A35";
"GND_A38":   PN = "A38"  !CDS_PN = "A38";
"GND_A41":   PN = "A41"  !CDS_PN = "A41";
"GND_A43":   PN = "A43"  !CDS_PN = "A43";
"GND_A46":   PN = "A46"  !CDS_PN = "A46";
"GND_A49":   PN = "A49"  !CDS_PN = "A49";
"GND_A52":   PN = "A52"  !CDS_PN = "A52";
"GND_A55":   PN = "A55"  !CDS_PN = "A55";
"GND_A58":   PN = "A58"  !CDS_PN = "A58";
"GND_A61":   PN = "A61"  !CDS_PN = "A61";
"GND_A64":   PN = "A64"  !CDS_PN = "A64";
"GND_A67":   PN = "A67"  !CDS_PN = "A67";
"GND_B13":   PN = "B13"  !CDS_PN = "B13";
"GND_B16":   PN = "B16"  !CDS_PN = "B16";
"GND_B19":   PN = "B19"  !CDS_PN = "B19";
"GND_B22":   PN = "B22"  !CDS_PN = "B22";
"GND_B25":   PN = "B25"  !CDS_PN = "B25";
"GND_B28":   PN = "B28"  !CDS_PN = "B28";
"GND_B29":   PN = "B29"  !CDS_PN = "B29";
"GND_B32":   PN = "B32"  !CDS_PN = "B32";
"GND_B35":   PN = "B35"  !CDS_PN = "B35";
"GND_B38":   PN = "B38"  !CDS_PN = "B38";
"GND_B41":   PN = "B41"  !CDS_PN = "B41";
"GND_B43":   PN = "B43"  !CDS_PN = "B43";
"GND_B46":   PN = "B46"  !CDS_PN = "B46";
"GND_B49":   PN = "B49"  !CDS_PN = "B49";
"GND_B52":   PN = "B52"  !CDS_PN = "B52";
"GND_B55":   PN = "B55"  !CDS_PN = "B55";
"GND_B58":   PN = "B58"  !CDS_PN = "B58";
"GND_B61":   PN = "B61"  !CDS_PN = "B61";
"GND_B64":   PN = "B64"  !CDS_PN = "B64";
"GND_B67":   PN = "B67"  !CDS_PN = "B67";
"GND_OA10":   PN = "OA10"  !CDS_PN = "OA10";
"GND_OA13":   PN = "OA13"  !CDS_PN = "OA13";
"GND_OB10":   PN = "OB10"  !CDS_PN = "OB10";
"GND_OB13":   PN = "OB13"  !CDS_PN = "OB13";
"LD#":   PN = "OB3"  !CDS_PN = "OB3";
"MAIN_PWR_EN":   PN = "OB2"  !CDS_PN = "OB2";
"NIC_PWR_GOOD":   PN = "OB1"  !CDS_PN = "OB1";
"PERN0":   PN = "A17"  !CDS_PN = "A17";
"PERN1":   PN = "A20"  !CDS_PN = "A20";
"PERN2":   PN = "A23"  !CDS_PN = "A23";
"PERN3":   PN = "A26"  !CDS_PN = "A26";
"PERN4":   PN = "A30"  !CDS_PN = "A30";
"PERN5":   PN = "A33"  !CDS_PN = "A33";
"PERN6":   PN = "A36"  !CDS_PN = "A36";
"PERN7":   PN = "A39"  !CDS_PN = "A39";
"PERN8":   PN = "A44"  !CDS_PN = "A44";
"PERN9":   PN = "A47"  !CDS_PN = "A47";
"PERN10":   PN = "A50"  !CDS_PN = "A50";
"PERN11":   PN = "A53"  !CDS_PN = "A53";
"PERN12":   PN = "A56"  !CDS_PN = "A56";
"PERN13":   PN = "A59"  !CDS_PN = "A59";
"PERN14":   PN = "A62"  !CDS_PN = "A62";
"PERN15":   PN = "A65"  !CDS_PN = "A65";
"PERP0":   PN = "A18"  !CDS_PN = "A18";
"PERP1":   PN = "A21"  !CDS_PN = "A21";
"PERP2":   PN = "A24"  !CDS_PN = "A24";
"PERP3":   PN = "A27"  !CDS_PN = "A27";
"PERP4":   PN = "A31"  !CDS_PN = "A31";
"PERP5":   PN = "A34"  !CDS_PN = "A34";
"PERP6":   PN = "A37"  !CDS_PN = "A37";
"PERP7":   PN = "A40"  !CDS_PN = "A40";
"PERP8":   PN = "A45"  !CDS_PN = "A45";
"PERP9":   PN = "A48"  !CDS_PN = "A48";
"PERP10":   PN = "A51"  !CDS_PN = "A51";
"PERP11":   PN = "A54"  !CDS_PN = "A54";
"PERP12":   PN = "A57"  !CDS_PN = "A57";
"PERP13":   PN = "A60"  !CDS_PN = "A60";
"PERP14":   PN = "A63"  !CDS_PN = "A63";
"PERP15":   PN = "A66"  !CDS_PN = "A66";
"PERST0#":   PN = "B10"  !CDS_PN = "B10";
"PERST1#":   PN = "A11"  !CDS_PN = "A11";
"PERST2#":   PN = "OA1"  !CDS_PN = "OA1";
"PERST3#":   PN = "OA2"  !CDS_PN = "OA2";
"PETN0":   PN = "B17"  !CDS_PN = "B17";
"PETN1":   PN = "B20"  !CDS_PN = "B20";
"PETN2":   PN = "B23"  !CDS_PN = "B23";
"PETN3":   PN = "B26"  !CDS_PN = "B26";
"PETN4":   PN = "B30"  !CDS_PN = "B30";
"PETN5":   PN = "B33"  !CDS_PN = "B33";
"PETN6":   PN = "B36"  !CDS_PN = "B36";
"PETN7":   PN = "B39"  !CDS_PN = "B39";
"PETN8":   PN = "B44"  !CDS_PN = "B44";
"PETN9":   PN = "B47"  !CDS_PN = "B47";
"PETN10":   PN = "B50"  !CDS_PN = "B50";
"PETN11":   PN = "B53"  !CDS_PN = "B53";
"PETN12":   PN = "B56"  !CDS_PN = "B56";
"PETN13":   PN = "B59"  !CDS_PN = "B59";
"PETN14":   PN = "B62"  !CDS_PN = "B62";
"PETN15":   PN = "B65"  !CDS_PN = "B65";
"PETP0":   PN = "B18"  !CDS_PN = "B18";
"PETP1":   PN = "B21"  !CDS_PN = "B21";
"PETP2":   PN = "B24"  !CDS_PN = "B24";
"PETP3":   PN = "B27"  !CDS_PN = "B27";
"PETP4":   PN = "B31"  !CDS_PN = "B31";
"PETP5":   PN = "B34"  !CDS_PN = "B34";
"PETP6":   PN = "B37"  !CDS_PN = "B37";
"PETP7":   PN = "B40"  !CDS_PN = "B40";
"PETP8":   PN = "B45"  !CDS_PN = "B45";
"PETP9":   PN = "B48"  !CDS_PN = "B48";
"PETP10":   PN = "B51"  !CDS_PN = "B51";
"PETP11":   PN = "B54"  !CDS_PN = "B54";
"PETP12":   PN = "B57"  !CDS_PN = "B57";
"PETP13":   PN = "B60"  !CDS_PN = "B60";
"PETP14":   PN = "B63"  !CDS_PN = "B63";
"PETP15":   PN = "B66"  !CDS_PN = "B66";
"PRSNTA#":   PN = "A10"  !CDS_PN = "A10";
"PRSNTB0#":   PN = "B42"  !CDS_PN = "B42";
"PRSNTB1#":   PN = "A42"  !CDS_PN = "A42";
"PRSNTB2#":   PN = "A12"  !CDS_PN = "A12";
"PRSNTB3#":   PN = "B70"  !CDS_PN = "B70";
"PWRBRK0#":   PN = "A70"  !CDS_PN = "A70";
"RBT_ARB_IN":   PN = "OA4"  !CDS_PN = "OA4";
"RBT_ARB_OUT":   PN = "OA5"  !CDS_PN = "OA5";
"RBT_CLK_IN":   PN = "OA14"  !CDS_PN = "OA14";
"RBT_CRS_DV":   PN = "OB14"  !CDS_PN = "OB14";
"RBT_RXD0":   PN = "OB9"  !CDS_PN = "OB9";
"RBT_RXD1":   PN = "OB8"  !CDS_PN = "OB8";
"RBT_TX_EN":   PN = "OA7"  !CDS_PN = "OA7";
"RBT_TXD0":   PN = "OA9"  !CDS_PN = "OA9";
"RBT_TXD1":   PN = "OA8"  !CDS_PN = "OA8";
"REFCLKN0":   PN = "B14"  !CDS_PN = "B14";
"REFCLKN1":   PN = "A14"  !CDS_PN = "A14";
"REFCLKN2":   PN = "OB11"  !CDS_PN = "OB11";
"REFCLKN3":   PN = "OA11"  !CDS_PN = "OA11";
"REFCLKP0":   PN = "B15"  !CDS_PN = "B15";
"REFCLKP1":   PN = "A15"  !CDS_PN = "A15";
"REFCLKP2":   PN = "OB12"  !CDS_PN = "OB12";
"REFCLKP3":   PN = "OA12"  !CDS_PN = "OA12";
"RFU1_NC_B68":   PN = "B68"  !CDS_PN = "B68";
"RFU1_NC_B69":   PN = "B69"  !CDS_PN = "B69";
"SLOT_ID0":   PN = "OB7"  !CDS_PN = "OB7";
"SLOT_ID1":   PN = "OA6"  !CDS_PN = "OA6";
"SMCLK":   PN = "A7"  !CDS_PN = "A7";
"SMDAT":   PN = "A8"  !CDS_PN = "A8";
"SMRST#":   PN = "A9"  !CDS_PN = "A9";
"USB_DATN":   PN = "A68"  !CDS_PN = "A68";
"USB_DATP":   PN = "A69"  !CDS_PN = "A69";
"WAKE#":   PN = "OA3"  !CDS_PN = "OA3";
BODY = "Q_RES","I3": #LOCATION = "R31" !CDS_LOCATION = "R31" &SEC = "1" #&CDS_SEC = "1";
"A":   PN = "1"  !CDS_PN = "1";
"B":   PN = "2"  !CDS_PN = "2";
BODY = "Q_RES","I7": #LOCATION = "R1930" !CDS_LOCATION = "R1930" &SEC = "1" #&CDS_SEC = "1";
"A":   PN = "1"  !CDS_PN = "1";
"B":   PN = "2"  !CDS_PN = "2";
BODY = "Q_RES","I8": #LOCATION = "R1929" !CDS_LOCATION = "R1929" &SEC = "1" #&CDS_SEC = "1";
"A":   PN = "1"  !CDS_PN = "1";
"B":   PN = "2"  !CDS_PN = "2";
BODY = "Q_RES","I12": #LOCATION = "R34" !CDS_LOCATION = "R34" &SEC = "1" #&CDS_SEC = "1";
"A":   PN = "1"  !CDS_PN = "1";
"B":   PN = "2"  !CDS_PN = "2";
BODY = "Q_RES","I17": #LOCATION = "R33" !CDS_LOCATION = "R33" &SEC = "1" #&CDS_SEC = "1";
"A":   PN = "1"  !CDS_PN = "1";
"B":   PN = "2"  !CDS_PN = "2";
BODY = "Q_RES","I19": #LOCATION = "R8422" !CDS_LOCATION = "R8422" &SEC = "1" #&CDS_SEC = "1";
"A":   PN = "1"  !CDS_PN = "1";
"B":   PN = "2"  !CDS_PN = "2";
BODY = "Q_RES","I20": #LOCATION = "R8423" !CDS_LOCATION = "R8423" &SEC = "1" #&CDS_SEC = "1";
"A":   PN = "1"  !CDS_PN = "1";
"B":   PN = "2"  !CDS_PN = "2";
BODY = "Q_RES","I21": #LOCATION = "R8421" !CDS_LOCATION = "R8421" &SEC = "1" #&CDS_SEC = "1";
"A":   PN = "1"  !CDS_PN = "1";
"B":   PN = "2"  !CDS_PN = "2";
BODY = "Q_RES","I22": #LOCATION = "R8420" !CDS_LOCATION = "R8420" &SEC = "1" #&CDS_SEC = "1";
"A":   PN = "1"  !CDS_PN = "1";
"B":   PN = "2"  !CDS_PN = "2";
BODY = "Q_RES","I55": #LOCATION = "R41" !CDS_LOCATION = "R41" &SEC = "1" #&CDS_SEC = "1";
"A":   PN = "1"  !CDS_PN = "1";
"B":   PN = "2"  !CDS_PN = "2";
BODY = "Q_RES","I56": #LOCATION = "R40" !CDS_LOCATION = "R40" &SEC = "1" #&CDS_SEC = "1";
"A":   PN = "1"  !CDS_PN = "1";
"B":   PN = "2"  !CDS_PN = "2";
BODY = "Q_RES","I57": #LOCATION = "R39" !CDS_LOCATION = "R39" &SEC = "1" #&CDS_SEC = "1";
"A":   PN = "1"  !CDS_PN = "1";
"B":   PN = "2"  !CDS_PN = "2";
BODY = "Q_RES","I59": #LOCATION = "R38" !CDS_LOCATION = "R38" &SEC = "1" #&CDS_SEC = "1";
"A":   PN = "1"  !CDS_PN = "1";
"B":   PN = "2"  !CDS_PN = "2";
BODY = "Q_CAP","I87": #LOCATION = "C1213" !CDS_LOCATION = "C1213" &SEC = "1" #&CDS_SEC = "1";
"A":   PN = "1"  !CDS_PN = "1";
"B":   PN = "2"  !CDS_PN = "2";
BODY = "Q_CAP","I88": #LOCATION = "C34" !CDS_LOCATION = "C34" &SEC = "1" #&CDS_SEC = "1";
"A":   PN = "1"  !CDS_PN = "1";
"B":   PN = "2"  !CDS_PN = "2";
BODY = "Q_RES","I108": #LOCATION = "R46" !CDS_LOCATION = "R46" &SEC = "1" #&CDS_SEC = "1";
"A":   PN = "1"  !CDS_PN = "1";
"B":   PN = "2"  !CDS_PN = "2";
BODY = "Q_CAP","I112": #LOCATION = "C1239" !CDS_LOCATION = "C1239" &SEC = "1" #&CDS_SEC = "1";
"A":   PN = "1"  !CDS_PN = "1";
"B":   PN = "2"  !CDS_PN = "2";
BODY = "Q_CAP","I163": #LOCATION = "C27" !CDS_LOCATION = "C27" &SEC = "1" #&CDS_SEC = "1";
"A":   PN = "1"  !CDS_PN = "1";
"B":   PN = "2"  !CDS_PN = "2";
BODY = "Q_CAP","I164": #LOCATION = "C1236" !CDS_LOCATION = "C1236" &SEC = "1" #&CDS_SEC = "1";
"A":   PN = "1"  !CDS_PN = "1";
"B":   PN = "2"  !CDS_PN = "2";
BODY = "Q_RES","I166": #LOCATION = "R42" !CDS_LOCATION = "R42" &SEC = "1" #&CDS_SEC = "1";
"A":   PN = "1"  !CDS_PN = "1";
"B":   PN = "2"  !CDS_PN = "2";
BODY = "Q_RES","I169": #LOCATION = "R1895" !CDS_LOCATION = "R1895" &SEC = "1" #&CDS_SEC = "1";
"A":   PN = "1"  !CDS_PN = "1";
"B":   PN = "2"  !CDS_PN = "2";
BODY = "Q_RES","I170": #LOCATION = "R48" !CDS_LOCATION = "R48" #SEC = "1" !CDS_SEC = "1";
"A":   PN = "1"  !CDS_PN = "1";
"B":   PN = "2"  !CDS_PN = "2";
BODY = "Q_RES","I171": #LOCATION = "R47" !CDS_LOCATION = "R47" #SEC = "1" !CDS_SEC = "1";
"A":   PN = "1"  !CDS_PN = "1";
"B":   PN = "2"  !CDS_PN = "2";
DRAWING = "@t6g_mb_lib.t6g(sch_1):page336";
BODY = "74CBTLV3126PW","I1": #LOCATION = "U67" !CDS_LOCATION = "U67" &SEC = "1" #&CDS_SEC = "1";
"1A":   PN = "2"  !CDS_PN = "2";
"1B":   PN = "3"  !CDS_PN = "3";
"1OE":   PN = "1"  !CDS_PN = "1";
"2A":   PN = "5"  !CDS_PN = "5";
"2B":   PN = "6"  !CDS_PN = "6";
"2OE":   PN = "4"  !CDS_PN = "4";
"3A":   PN = "9"  !CDS_PN = "9";
"3B":   PN = "8"  !CDS_PN = "8";
"3OE":   PN = "10"  !CDS_PN = "10";
"4A":   PN = "12"  !CDS_PN = "12";
"4B":   PN = "11"  !CDS_PN = "11";
"4OE":   PN = "13"  !CDS_PN = "13";
"GND":   PN = "7"  !CDS_PN = "7";
"VCC":   PN = "14"  !CDS_PN = "14";
BODY = "74CBTLV3126PW","I2": #LOCATION = "U7" !CDS_LOCATION = "U7" &SEC = "1" #&CDS_SEC = "1";
"1A":   PN = "2"  !CDS_PN = "2";
"1B":   PN = "3"  !CDS_PN = "3";
"1OE":   PN = "1"  !CDS_PN = "1";
"2A":   PN = "5"  !CDS_PN = "5";
"2B":   PN = "6"  !CDS_PN = "6";
"2OE":   PN = "4"  !CDS_PN = "4";
"3A":   PN = "9"  !CDS_PN = "9";
"3B":   PN = "8"  !CDS_PN = "8";
"3OE":   PN = "10"  !CDS_PN = "10";
"4A":   PN = "12"  !CDS_PN = "12";
"4B":   PN = "11"  !CDS_PN = "11";
"4OE":   PN = "13"  !CDS_PN = "13";
"GND":   PN = "7"  !CDS_PN = "7";
"VCC":   PN = "14"  !CDS_PN = "14";
BODY = "Q_CAP","I16": #LOCATION = "C641" !CDS_LOCATION = "C641" &SEC = "1" #&CDS_SEC = "1";
"A":   PN = "1"  !CDS_PN = "1";
"B":   PN = "2"  !CDS_PN = "2";
BODY = "Q_CAP","I47": #LOCATION = "C640" !CDS_LOCATION = "C640" &SEC = "1" #&CDS_SEC = "1";
"A":   PN = "1"  !CDS_PN = "1";
"B":   PN = "2"  !CDS_PN = "2";
BODY = "Q_RES","I56": #LOCATION = "R1289" !CDS_LOCATION = "R1289" &SEC = "1" #&CDS_SEC = "1";
"A":   PN = "1"  !CDS_PN = "1";
"B":   PN = "2"  !CDS_PN = "2";
BODY = "Q_CAP","I59": #LOCATION = "C639" !CDS_LOCATION = "C639" &SEC = "1" #&CDS_SEC = "1";
"A":   PN = "1"  !CDS_PN = "1";
"B":   PN = "2"  !CDS_PN = "2";
BODY = "Q_RES","I98": #LOCATION = "R1290" !CDS_LOCATION = "R1290" &SEC = "1" #&CDS_SEC = "1";
"A":   PN = "1"  !CDS_PN = "1";
"B":   PN = "2"  !CDS_PN = "2";
BODY = "Q_RES","I99": #LOCATION = "R59" !CDS_LOCATION = "R59" &SEC = "1" #&CDS_SEC = "1";
"A":   PN = "1"  !CDS_PN = "1";
"B":   PN = "2"  !CDS_PN = "2";
BODY = "Q_RES","I100": #LOCATION = "R72" !CDS_LOCATION = "R72" &SEC = "1" #&CDS_SEC = "1";
"A":   PN = "1"  !CDS_PN = "1";
"B":   PN = "2"  !CDS_PN = "2";
BODY = "Q_RES","I101": #LOCATION = "R73" !CDS_LOCATION = "R73" &SEC = "1" #&CDS_SEC = "1";
"A":   PN = "1"  !CDS_PN = "1";
"B":   PN = "2"  !CDS_PN = "2";
BODY = "Q_RES","I102": #LOCATION = "R74" !CDS_LOCATION = "R74" &SEC = "1" #&CDS_SEC = "1";
"A":   PN = "1"  !CDS_PN = "1";
"B":   PN = "2"  !CDS_PN = "2";
BODY = "Q_RES","I103": #LOCATION = "R75" !CDS_LOCATION = "R75" &SEC = "1" #&CDS_SEC = "1";
"A":   PN = "1"  !CDS_PN = "1";
"B":   PN = "2"  !CDS_PN = "2";
BODY = "Q_RES","I104": #LOCATION = "R76" !CDS_LOCATION = "R76" &SEC = "1" #&CDS_SEC = "1";
"A":   PN = "1"  !CDS_PN = "1";
"B":   PN = "2"  !CDS_PN = "2";
BODY = "Q_RES","I119": #LOCATION = "R1719" !CDS_LOCATION = "R1719" &SEC = "1" #&CDS_SEC = "1";
"A":   PN = "1"  !CDS_PN = "1";
"B":   PN = "2"  !CDS_PN = "2";
BODY = "Q_RES","I122": #LOCATION = "R1898" !CDS_LOCATION = "R1898" &SEC = "1" #&CDS_SEC = "1";
"A":   PN = "1"  !CDS_PN = "1";
"B":   PN = "2"  !CDS_PN = "2";
BODY = "Q_RES","I123": #LOCATION = "R1896" !CDS_LOCATION = "R1896" &SEC = "1" #&CDS_SEC = "1";
"A":   PN = "1"  !CDS_PN = "1";
"B":   PN = "2"  !CDS_PN = "2";
BODY = "Q_RES","I124": #LOCATION = "R1897" !CDS_LOCATION = "R1897" &SEC = "1" #&CDS_SEC = "1";
"A":   PN = "1"  !CDS_PN = "1";
"B":   PN = "2"  !CDS_PN = "2";
BODY = "Q_RES","I129": #LOCATION = "R84" !CDS_LOCATION = "R84" &SEC = "1" #&CDS_SEC = "1";
"A":   PN = "1"  !CDS_PN = "1";
"B":   PN = "2"  !CDS_PN = "2";
BODY = "Q_RES","I131": #LOCATION = "R77" !CDS_LOCATION = "R77" &SEC = "1" #&CDS_SEC = "1";
"A":   PN = "1"  !CDS_PN = "1";
"B":   PN = "2"  !CDS_PN = "2";
BODY = "Q_RES","I132": #LOCATION = "R79" !CDS_LOCATION = "R79" &SEC = "1" #&CDS_SEC = "1";
"A":   PN = "1"  !CDS_PN = "1";
"B":   PN = "2"  !CDS_PN = "2";
BODY = "Q_RES","I133": #LOCATION = "R80" !CDS_LOCATION = "R80" &SEC = "1" #&CDS_SEC = "1";
"A":   PN = "1"  !CDS_PN = "1";
"B":   PN = "2"  !CDS_PN = "2";
BODY = "Q_RES","I134": #LOCATION = "R82" !CDS_LOCATION = "R82" &SEC = "1" #&CDS_SEC = "1";
"A":   PN = "1"  !CDS_PN = "1";
"B":   PN = "2"  !CDS_PN = "2";
BODY = "Q_RES","I135": #LOCATION = "R83" !CDS_LOCATION = "R83" &SEC = "1" #&CDS_SEC = "1";
"A":   PN = "1"  !CDS_PN = "1";
"B":   PN = "2"  !CDS_PN = "2";
BODY = "Q_RES","I136": #LOCATION = "R87" !CDS_LOCATION = "R87" &SEC = "1" #&CDS_SEC = "1";
"A":   PN = "1"  !CDS_PN = "1";
"B":   PN = "2"  !CDS_PN = "2";
BODY = "Q_CAP","I147": #LOCATION = "C1840" !CDS_LOCATION = "C1840" &SEC = "1" #&CDS_SEC = "1";
"A":   PN = "1"  !CDS_PN = "1";
"B":   PN = "2"  !CDS_PN = "2";
BODY = "Q_RES","I152": #LOCATION = "R3232" !CDS_LOCATION = "R3232" &SEC = "1" #&CDS_SEC = "1";
"A":   PN = "1"  !CDS_PN = "1";
"B":   PN = "2"  !CDS_PN = "2";
BODY = "Q_RES","I153": #LOCATION = "R3233" !CDS_LOCATION = "R3233" &SEC = "1" #&CDS_SEC = "1";
"A":   PN = "1"  !CDS_PN = "1";
"B":   PN = "2"  !CDS_PN = "2";
BODY = "Q_RES","I156": #LOCATION = "R3237" !CDS_LOCATION = "R3237" &SEC = "1" #&CDS_SEC = "1";
"A":   PN = "1"  !CDS_PN = "1";
"B":   PN = "2"  !CDS_PN = "2";
BODY = "74LVC1G126SE7","I157": #LOCATION = "U66" !CDS_LOCATION = "U66" #SEC = "1" !CDS_SEC = "1";
"A":   PN = "2"  !CDS_PN = "2";
"GND":   PN = "3"  !CDS_PN = "3";
"OE":   PN = "1"  !CDS_PN = "1";
"VCC":   PN = "5"  !CDS_PN = "5";
"Y":   PN = "4"  !CDS_PN = "4";
BODY = "74LVC1G126SE7","I159": #LOCATION = "U224" !CDS_LOCATION = "U224" &SEC = "1" #&CDS_SEC = "1";
"A":   PN = "2"  !CDS_PN = "2";
"GND":   PN = "3"  !CDS_PN = "3";
"OE":   PN = "1"  !CDS_PN = "1";
"VCC":   PN = "5"  !CDS_PN = "5";
"Y":   PN = "4"  !CDS_PN = "4";
BODY = "Q_RES","I160": #LOCATION = "R3231" !CDS_LOCATION = "R3231" &SEC = "1" #&CDS_SEC = "1";
"A":   PN = "1"  !CDS_PN = "1";
"B":   PN = "2"  !CDS_PN = "2";
BODY = "Q_RES","I164": #LOCATION = "R2473" !CDS_LOCATION = "R2473" &SEC = "1" #&CDS_SEC = "1";
"A":   PN = "1"  !CDS_PN = "1";
"B":   PN = "2"  !CDS_PN = "2";
BODY = "Q_RES","I165": #LOCATION = "R2474" !CDS_LOCATION = "R2474" &SEC = "1" #&CDS_SEC = "1";
"A":   PN = "1"  !CDS_PN = "1";
"B":   PN = "2"  !CDS_PN = "2";
DRAWING = "@t6g_mb_lib.t6g(sch_1):page337";
BODY = "Q_CAP","I40": #LOCATION = "C72" !CDS_LOCATION = "C72" &SEC = "1" #&CDS_SEC = "1";
"A":   PN = "1"  !CDS_PN = "1";
"B":   PN = "2"  !CDS_PN = "2";
BODY = "Q_RES","I42": #LOCATION = "R53" !CDS_LOCATION = "R53" &SEC = "1" #&CDS_SEC = "1";
"A":   PN = "1"  !CDS_PN = "1";
"B":   PN = "2"  !CDS_PN = "2";
BODY = "Q_RES","I44": #LOCATION = "R1595" !CDS_LOCATION = "R1595" &SEC = "1" #&CDS_SEC = "1";
"A":   PN = "1"  !CDS_PN = "1";
"B":   PN = "2"  !CDS_PN = "2";
BODY = "Q_CAP","I53": #LOCATION = "C2344" !CDS_LOCATION = "C2344" &SEC = "1" #&CDS_SEC = "1";
"A":   PN = "1"  !CDS_PN = "1";
"B":   PN = "2"  !CDS_PN = "2";
BODY = "Q_RES","I56": #LOCATION = "R2487" !CDS_LOCATION = "R2487" &SEC = "1" #&CDS_SEC = "1";
"A":   PN = "1"  !CDS_PN = "1";
"B":   PN = "2"  !CDS_PN = "2";
BODY = "Q_RES","I1": #LOCATION = "R1138" !CDS_LOCATION = "R1138" &SEC = "1" #&CDS_SEC = "1";
"A":   PN = "1"  !CDS_PN = "1";
"B":   PN = "2"  !CDS_PN = "2";
BODY = "Q_CAP","I3": #LOCATION = "C1274" !CDS_LOCATION = "C1274" &SEC = "1" #&CDS_SEC = "1";
"A":   PN = "1"  !CDS_PN = "1";
"B":   PN = "2"  !CDS_PN = "2";
BODY = "Q_OSC4P","I4": #LOCATION = "OSC1" !CDS_LOCATION = "OSC1" &SEC = "1" #&CDS_SEC = "1";
"GND":   PN = "2"  !CDS_PN = "2";
"OE":   PN = "1"  !CDS_PN = "1";
"OUT":   PN = "3"  !CDS_PN = "3";
"VDD":   PN = "4"  !CDS_PN = "4";
BODY = "Q_RES","I7": #LOCATION = "R1139" !CDS_LOCATION = "R1139" &SEC = "1" #&CDS_SEC = "1";
"A":   PN = "1"  !CDS_PN = "1";
"B":   PN = "2"  !CDS_PN = "2";
BODY = "74LVC1G126SE7","I8": #LOCATION = "U8082" !CDS_LOCATION = "U8082" &SEC = "1" #&CDS_SEC = "1";
"A":   PN = "2"  !CDS_PN = "2";
"GND":   PN = "3"  !CDS_PN = "3";
"OE":   PN = "1"  !CDS_PN = "1";
"VCC":   PN = "5"  !CDS_PN = "5";
"Y":   PN = "4"  !CDS_PN = "4";
BODY = "Q_RES","I11": #LOCATION = "R1824" !CDS_LOCATION = "R1824" &SEC = "1" #&CDS_SEC = "1";
"A":   PN = "1"  !CDS_PN = "1";
"B":   PN = "2"  !CDS_PN = "2";
BODY = "Q_RES","I12": #LOCATION = "R45" !CDS_LOCATION = "R45" &SEC = "1" #&CDS_SEC = "1";
"A":   PN = "1"  !CDS_PN = "1";
"B":   PN = "2"  !CDS_PN = "2";
BODY = "PI6CV304LE","I16": #LOCATION = "U90" !CDS_LOCATION = "U90" &SEC = "1" #&CDS_SEC = "1";
"CLK_IN":   PN = "1"  !CDS_PN = "1";
"GND":   PN = "4"  !CDS_PN = "4";
"OE":   PN = "2"  !CDS_PN = "2";
"VDD":   PN = "6"  !CDS_PN = "6";
"Y0":   PN = "3"  !CDS_PN = "3";
"Y1":   PN = "5"  !CDS_PN = "5";
"Y2":   PN = "7"  !CDS_PN = "7";
"Y3":   PN = "8"  !CDS_PN = "8";
BODY = "Q_CAP","I19": #LOCATION = "C1275" !CDS_LOCATION = "C1275" &SEC = "1" #&CDS_SEC = "1";
"A":   PN = "1"  !CDS_PN = "1";
"B":   PN = "2"  !CDS_PN = "2";
BODY = "Q_RES","I20": #LOCATION = "R3181" !CDS_LOCATION = "R3181" &SEC = "1" #&CDS_SEC = "1";
"A":   PN = "1"  !CDS_PN = "1";
"B":   PN = "2"  !CDS_PN = "2";
BODY = "Q_RES","I21": #LOCATION = "R1141" !CDS_LOCATION = "R1141" &SEC = "1" #&CDS_SEC = "1";
"A":   PN = "1"  !CDS_PN = "1";
"B":   PN = "2"  !CDS_PN = "2";
BODY = "Q_RES","I22": #LOCATION = "R1140" !CDS_LOCATION = "R1140" &SEC = "1" #&CDS_SEC = "1";
"A":   PN = "1"  !CDS_PN = "1";
"B":   PN = "2"  !CDS_PN = "2";
BODY = "74LVC1G07GV","I25": #LOCATION = "U157" !CDS_LOCATION = "U157" &SEC = "1" #&CDS_SEC = "1";
"A":   PN = "2"  !CDS_PN = "2";
"GND":   PN = "3"  !CDS_PN = "3";
"NC1":   PN = "1"  !CDS_PN = "1";
"VCC":   PN = "5"  !CDS_PN = "5";
"Y":   PN = "4"  !CDS_PN = "4";
BODY = "Q_RES","I29": #LOCATION = "R4601" !CDS_LOCATION = "R4601" &SEC = "1" #&CDS_SEC = "1";
"A":   PN = "1"  !CDS_PN = "1";
"B":   PN = "2"  !CDS_PN = "2";
BODY = "Q_RES","I31": #LOCATION = "R1594" !CDS_LOCATION = "R1594" &SEC = "1" #&CDS_SEC = "1";
"A":   PN = "1"  !CDS_PN = "1";
"B":   PN = "2"  !CDS_PN = "2";
BODY = "Q_CAP","I33": #LOCATION = "C36" !CDS_LOCATION = "C36" &SEC = "1" #&CDS_SEC = "1";
"A":   PN = "1"  !CDS_PN = "1";
"B":   PN = "2"  !CDS_PN = "2";
BODY = "Q_RES","I35": #LOCATION = "R2488" !CDS_LOCATION = "R2488" &SEC = "1" #&CDS_SEC = "1";
"A":   PN = "1"  !CDS_PN = "1";
"B":   PN = "2"  !CDS_PN = "2";
BODY = "74LVC1G07GV","I38": #LOCATION = "U104" !CDS_LOCATION = "U104" &SEC = "1" #&CDS_SEC = "1";
"A":   PN = "2"  !CDS_PN = "2";
"GND":   PN = "3"  !CDS_PN = "3";
"NC1":   PN = "1"  !CDS_PN = "1";
"VCC":   PN = "5"  !CDS_PN = "5";
"Y":   PN = "4"  !CDS_PN = "4";
BODY = "Q_CAP","I47": #LOCATION = "C1663" !CDS_LOCATION = "C1663" &SEC = "1" #&CDS_SEC = "1";
"A":   PN = "1"  !CDS_PN = "1";
"B":   PN = "2"  !CDS_PN = "2";
BODY = "Q_RES","I50": #LOCATION = "R2489" !CDS_LOCATION = "R2489" &SEC = "1" #&CDS_SEC = "1";
"A":   PN = "1"  !CDS_PN = "1";
"B":   PN = "2"  !CDS_PN = "2";
BODY = "Q_CAP","I61": #LOCATION = "C10" !CDS_LOCATION = "C10" &SEC = "1" #&CDS_SEC = "1";
"A":   PN = "1"  !CDS_PN = "1";
"B":   PN = "2"  !CDS_PN = "2";
BODY = "74LVC1G17GW","I64": #LOCATION = "U75" !CDS_LOCATION = "U75" #SEC = "1" !CDS_SEC = "1";
"A":   PN = "2"  !CDS_PN = "2";
"GND":   PN = "3"  !CDS_PN = "3";
"NC":   PN = "1"  !CDS_PN = "1";
"VCC":   PN = "5"  !CDS_PN = "5";
"Y":   PN = "4"  !CDS_PN = "4";
BODY = "Q_RES","I78": #LOCATION = "R899" !CDS_LOCATION = "R899" &SEC = "1" #&CDS_SEC = "1";
"A":   PN = "1"  !CDS_PN = "1";
"B":   PN = "2"  !CDS_PN = "2";
BODY = "Q_RES","I79": #LOCATION = "R877" !CDS_LOCATION = "R877" &SEC = "1" #&CDS_SEC = "1";
"A":   PN = "1"  !CDS_PN = "1";
"B":   PN = "2"  !CDS_PN = "2";
BODY = "Q_RES","I80": #LOCATION = "R905" !CDS_LOCATION = "R905" &SEC = "1" #&CDS_SEC = "1";
"A":   PN = "1"  !CDS_PN = "1";
"B":   PN = "2"  !CDS_PN = "2";
BODY = "Q_RES","I81": #LOCATION = "R956" !CDS_LOCATION = "R956" &SEC = "1" #&CDS_SEC = "1";
"A":   PN = "1"  !CDS_PN = "1";
"B":   PN = "2"  !CDS_PN = "2";
BODY = "74LVC1G66GV","I82": #LOCATION = "U320" !CDS_LOCATION = "U320" #SEC = "1" !CDS_SEC = "1";
"E":   PN = "4"  !CDS_PN = "4";
"GND":   PN = "3"  !CDS_PN = "3";
"VCC":   PN = "5"  !CDS_PN = "5";
"Y":   PN = "1"  !CDS_PN = "1";
"Z":   PN = "2"  !CDS_PN = "2";
DRAWING = "@t6g_mb_lib.t6g(sch_1):page341";
BODY = "Q_CAP","I20": #LOCATION = "C1834" !CDS_LOCATION = "C1834" &SEC = "1" #&CDS_SEC = "1";
"A":   PN = "1"  !CDS_PN = "1";
"B":   PN = "2"  !CDS_PN = "2";
BODY = "Q_CAP","I23": #LOCATION = "C1837" !CDS_LOCATION = "C1837" &SEC = "1" #&CDS_SEC = "1";
"A":   PN = "1"  !CDS_PN = "1";
"B":   PN = "2"  !CDS_PN = "2";
BODY = "Q_RES","I26": #LOCATION = "R3162" !CDS_LOCATION = "R3162" &SEC = "1" #&CDS_SEC = "1";
"A":   PN = "1"  !CDS_PN = "1";
"B":   PN = "2"  !CDS_PN = "2";
BODY = "Q_RES","I32": #LOCATION = "R3165" !CDS_LOCATION = "R3165" &SEC = "1" #&CDS_SEC = "1";
"A":   PN = "1"  !CDS_PN = "1";
"B":   PN = "2"  !CDS_PN = "2";
BODY = "Q_RES","I33": #LOCATION = "R8413" !CDS_LOCATION = "R8413" &SEC = "1" #&CDS_SEC = "1";
"A":   PN = "1"  !CDS_PN = "1";
"B":   PN = "2"  !CDS_PN = "2";
BODY = "Q_RES","I43": #LOCATION = "R3169" !CDS_LOCATION = "R3169" &SEC = "1" #&CDS_SEC = "1";
"A":   PN = "1"  !CDS_PN = "1";
"B":   PN = "2"  !CDS_PN = "2";
BODY = "SCONN168_ME1016810202011","I168": #LOCATION = "J35" !CDS_LOCATION = "J35" &SEC = "1" #&CDS_SEC = "1";
"+3.3V_EDGE":   PN = "B11"  !CDS_PN = "B11";
"+12V_EDGE_B1":   PN = "B1"  !CDS_PN = "B1";
"+12V_EDGE_B2":   PN = "B2"  !CDS_PN = "B2";
"+12V_EDGE_B3":   PN = "B3"  !CDS_PN = "B3";
"+12V_EDGE_B4":   PN = "B4"  !CDS_PN = "B4";
"+12V_EDGE_B5":   PN = "B5"  !CDS_PN = "B5";
"+12V_EDGE_B6":   PN = "B6"  !CDS_PN = "B6";
"AUX_PWR_EN":   PN = "B12"  !CDS_PN = "B12";
"BIF0#":   PN = "B7"  !CDS_PN = "B7";
"BIF1#":   PN = "B8"  !CDS_PN = "B8";
"BIF2#":   PN = "B9"  !CDS_PN = "B9";
"CLK":   PN = "OB6"  !CDS_PN = "OB6";
"DATA_IN":   PN = "OB4"  !CDS_PN = "OB4";
"DATA_OUT":   PN = "OB5"  !CDS_PN = "OB5";
"G1":   PN = "G1"  !CDS_PN = "G1";
"G2":   PN = "G2"  !CDS_PN = "G2";
"G3":   PN = "G3"  !CDS_PN = "G3";
"G4":   PN = "G4"  !CDS_PN = "G4";
"G5":   PN = "G5"  !CDS_PN = "G5";
"GND_A1":   PN = "A1"  !CDS_PN = "A1";
"GND_A2":   PN = "A2"  !CDS_PN = "A2";
"GND_A3":   PN = "A3"  !CDS_PN = "A3";
"GND_A4":   PN = "A4"  !CDS_PN = "A4";
"GND_A5":   PN = "A5"  !CDS_PN = "A5";
"GND_A6":   PN = "A6"  !CDS_PN = "A6";
"GND_A13":   PN = "A13"  !CDS_PN = "A13";
"GND_A16":   PN = "A16"  !CDS_PN = "A16";
"GND_A19":   PN = "A19"  !CDS_PN = "A19";
"GND_A22":   PN = "A22"  !CDS_PN = "A22";
"GND_A25":   PN = "A25"  !CDS_PN = "A25";
"GND_A28":   PN = "A28"  !CDS_PN = "A28";
"GND_A29":   PN = "A29"  !CDS_PN = "A29";
"GND_A32":   PN = "A32"  !CDS_PN = "A32";
"GND_A35":   PN = "A35"  !CDS_PN = "A35";
"GND_A38":   PN = "A38"  !CDS_PN = "A38";
"GND_A41":   PN = "A41"  !CDS_PN = "A41";
"GND_A43":   PN = "A43"  !CDS_PN = "A43";
"GND_A46":   PN = "A46"  !CDS_PN = "A46";
"GND_A49":   PN = "A49"  !CDS_PN = "A49";
"GND_A52":   PN = "A52"  !CDS_PN = "A52";
"GND_A55":   PN = "A55"  !CDS_PN = "A55";
"GND_A58":   PN = "A58"  !CDS_PN = "A58";
"GND_A61":   PN = "A61"  !CDS_PN = "A61";
"GND_A64":   PN = "A64"  !CDS_PN = "A64";
"GND_A67":   PN = "A67"  !CDS_PN = "A67";
"GND_B13":   PN = "B13"  !CDS_PN = "B13";
"GND_B16":   PN = "B16"  !CDS_PN = "B16";
"GND_B19":   PN = "B19"  !CDS_PN = "B19";
"GND_B22":   PN = "B22"  !CDS_PN = "B22";
"GND_B25":   PN = "B25"  !CDS_PN = "B25";
"GND_B28":   PN = "B28"  !CDS_PN = "B28";
"GND_B29":   PN = "B29"  !CDS_PN = "B29";
"GND_B32":   PN = "B32"  !CDS_PN = "B32";
"GND_B35":   PN = "B35"  !CDS_PN = "B35";
"GND_B38":   PN = "B38"  !CDS_PN = "B38";
"GND_B41":   PN = "B41"  !CDS_PN = "B41";
"GND_B43":   PN = "B43"  !CDS_PN = "B43";
"GND_B46":   PN = "B46"  !CDS_PN = "B46";
"GND_B49":   PN = "B49"  !CDS_PN = "B49";
"GND_B52":   PN = "B52"  !CDS_PN = "B52";
"GND_B55":   PN = "B55"  !CDS_PN = "B55";
"GND_B58":   PN = "B58"  !CDS_PN = "B58";
"GND_B61":   PN = "B61"  !CDS_PN = "B61";
"GND_B64":   PN = "B64"  !CDS_PN = "B64";
"GND_B67":   PN = "B67"  !CDS_PN = "B67";
"GND_OA10":   PN = "OA10"  !CDS_PN = "OA10";
"GND_OA13":   PN = "OA13"  !CDS_PN = "OA13";
"GND_OB10":   PN = "OB10"  !CDS_PN = "OB10";
"GND_OB13":   PN = "OB13"  !CDS_PN = "OB13";
"LD#":   PN = "OB3"  !CDS_PN = "OB3";
"MAIN_PWR_EN":   PN = "OB2"  !CDS_PN = "OB2";
"NIC_PWR_GOOD":   PN = "OB1"  !CDS_PN = "OB1";
"PERN0":   PN = "A17"  !CDS_PN = "A17";
"PERN1":   PN = "A20"  !CDS_PN = "A20";
"PERN2":   PN = "A23"  !CDS_PN = "A23";
"PERN3":   PN = "A26"  !CDS_PN = "A26";
"PERN4":   PN = "A30"  !CDS_PN = "A30";
"PERN5":   PN = "A33"  !CDS_PN = "A33";
"PERN6":   PN = "A36"  !CDS_PN = "A36";
"PERN7":   PN = "A39"  !CDS_PN = "A39";
"PERN8":   PN = "A44"  !CDS_PN = "A44";
"PERN9":   PN = "A47"  !CDS_PN = "A47";
"PERN10":   PN = "A50"  !CDS_PN = "A50";
"PERN11":   PN = "A53"  !CDS_PN = "A53";
"PERN12":   PN = "A56"  !CDS_PN = "A56";
"PERN13":   PN = "A59"  !CDS_PN = "A59";
"PERN14":   PN = "A62"  !CDS_PN = "A62";
"PERN15":   PN = "A65"  !CDS_PN = "A65";
"PERP0":   PN = "A18"  !CDS_PN = "A18";
"PERP1":   PN = "A21"  !CDS_PN = "A21";
"PERP2":   PN = "A24"  !CDS_PN = "A24";
"PERP3":   PN = "A27"  !CDS_PN = "A27";
"PERP4":   PN = "A31"  !CDS_PN = "A31";
"PERP5":   PN = "A34"  !CDS_PN = "A34";
"PERP6":   PN = "A37"  !CDS_PN = "A37";
"PERP7":   PN = "A40"  !CDS_PN = "A40";
"PERP8":   PN = "A45"  !CDS_PN = "A45";
"PERP9":   PN = "A48"  !CDS_PN = "A48";
"PERP10":   PN = "A51"  !CDS_PN = "A51";
"PERP11":   PN = "A54"  !CDS_PN = "A54";
"PERP12":   PN = "A57"  !CDS_PN = "A57";
"PERP13":   PN = "A60"  !CDS_PN = "A60";
"PERP14":   PN = "A63"  !CDS_PN = "A63";
"PERP15":   PN = "A66"  !CDS_PN = "A66";
"PERST0#":   PN = "B10"  !CDS_PN = "B10";
"PERST1#":   PN = "A11"  !CDS_PN = "A11";
"PERST2#":   PN = "OA1"  !CDS_PN = "OA1";
"PERST3#":   PN = "OA2"  !CDS_PN = "OA2";
"PETN0":   PN = "B17"  !CDS_PN = "B17";
"PETN1":   PN = "B20"  !CDS_PN = "B20";
"PETN2":   PN = "B23"  !CDS_PN = "B23";
"PETN3":   PN = "B26"  !CDS_PN = "B26";
"PETN4":   PN = "B30"  !CDS_PN = "B30";
"PETN5":   PN = "B33"  !CDS_PN = "B33";
"PETN6":   PN = "B36"  !CDS_PN = "B36";
"PETN7":   PN = "B39"  !CDS_PN = "B39";
"PETN8":   PN = "B44"  !CDS_PN = "B44";
"PETN9":   PN = "B47"  !CDS_PN = "B47";
"PETN10":   PN = "B50"  !CDS_PN = "B50";
"PETN11":   PN = "B53"  !CDS_PN = "B53";
"PETN12":   PN = "B56"  !CDS_PN = "B56";
"PETN13":   PN = "B59"  !CDS_PN = "B59";
"PETN14":   PN = "B62"  !CDS_PN = "B62";
"PETN15":   PN = "B65"  !CDS_PN = "B65";
"PETP0":   PN = "B18"  !CDS_PN = "B18";
"PETP1":   PN = "B21"  !CDS_PN = "B21";
"PETP2":   PN = "B24"  !CDS_PN = "B24";
"PETP3":   PN = "B27"  !CDS_PN = "B27";
"PETP4":   PN = "B31"  !CDS_PN = "B31";
"PETP5":   PN = "B34"  !CDS_PN = "B34";
"PETP6":   PN = "B37"  !CDS_PN = "B37";
"PETP7":   PN = "B40"  !CDS_PN = "B40";
"PETP8":   PN = "B45"  !CDS_PN = "B45";
"PETP9":   PN = "B48"  !CDS_PN = "B48";
"PETP10":   PN = "B51"  !CDS_PN = "B51";
"PETP11":   PN = "B54"  !CDS_PN = "B54";
"PETP12":   PN = "B57"  !CDS_PN = "B57";
"PETP13":   PN = "B60"  !CDS_PN = "B60";
"PETP14":   PN = "B63"  !CDS_PN = "B63";
"PETP15":   PN = "B66"  !CDS_PN = "B66";
"PRSNTA#":   PN = "A10"  !CDS_PN = "A10";
"PRSNTB0#":   PN = "B42"  !CDS_PN = "B42";
"PRSNTB1#":   PN = "A42"  !CDS_PN = "A42";
"PRSNTB2#":   PN = "A12"  !CDS_PN = "A12";
"PRSNTB3#":   PN = "B70"  !CDS_PN = "B70";
"PWRBRK0#":   PN = "A70"  !CDS_PN = "A70";
"RBT_ARB_IN":   PN = "OA4"  !CDS_PN = "OA4";
"RBT_ARB_OUT":   PN = "OA5"  !CDS_PN = "OA5";
"RBT_CLK_IN":   PN = "OA14"  !CDS_PN = "OA14";
"RBT_CRS_DV":   PN = "OB14"  !CDS_PN = "OB14";
"RBT_RXD0":   PN = "OB9"  !CDS_PN = "OB9";
"RBT_RXD1":   PN = "OB8"  !CDS_PN = "OB8";
"RBT_TX_EN":   PN = "OA7"  !CDS_PN = "OA7";
"RBT_TXD0":   PN = "OA9"  !CDS_PN = "OA9";
"RBT_TXD1":   PN = "OA8"  !CDS_PN = "OA8";
"REFCLKN0":   PN = "B14"  !CDS_PN = "B14";
"REFCLKN1":   PN = "A14"  !CDS_PN = "A14";
"REFCLKN2":   PN = "OB11"  !CDS_PN = "OB11";
"REFCLKN3":   PN = "OA11"  !CDS_PN = "OA11";
"REFCLKP0":   PN = "B15"  !CDS_PN = "B15";
"REFCLKP1":   PN = "A15"  !CDS_PN = "A15";
"REFCLKP2":   PN = "OB12"  !CDS_PN = "OB12";
"REFCLKP3":   PN = "OA12"  !CDS_PN = "OA12";
"RFU1_NC_B68":   PN = "B68"  !CDS_PN = "B68";
"RFU1_NC_B69":   PN = "B69"  !CDS_PN = "B69";
"SLOT_ID0":   PN = "OB7"  !CDS_PN = "OB7";
"SLOT_ID1":   PN = "OA6"  !CDS_PN = "OA6";
"SMCLK":   PN = "A7"  !CDS_PN = "A7";
"SMDAT":   PN = "A8"  !CDS_PN = "A8";
"SMRST#":   PN = "A9"  !CDS_PN = "A9";
"USB_DATN":   PN = "A68"  !CDS_PN = "A68";
"USB_DATP":   PN = "A69"  !CDS_PN = "A69";
"WAKE#":   PN = "OA3"  !CDS_PN = "OA3";
BODY = "Q_RES","I2": #LOCATION = "R3163" !CDS_LOCATION = "R3163" &SEC = "1" #&CDS_SEC = "1";
"A":   PN = "1"  !CDS_PN = "1";
"B":   PN = "2"  !CDS_PN = "2";
BODY = "Q_RES","I3": #LOCATION = "R3167" !CDS_LOCATION = "R3167" &SEC = "1" #&CDS_SEC = "1";
"A":   PN = "1"  !CDS_PN = "1";
"B":   PN = "2"  !CDS_PN = "2";
BODY = "Q_RES","I9": #LOCATION = "R3174" !CDS_LOCATION = "R3174" &SEC = "1" #&CDS_SEC = "1";
"A":   PN = "1"  !CDS_PN = "1";
"B":   PN = "2"  !CDS_PN = "2";
BODY = "Q_RES","I10": #LOCATION = "R3173" !CDS_LOCATION = "R3173" &SEC = "1" #&CDS_SEC = "1";
"A":   PN = "1"  !CDS_PN = "1";
"B":   PN = "2"  !CDS_PN = "2";
BODY = "Q_RES","I11": #LOCATION = "R3175" !CDS_LOCATION = "R3175" &SEC = "1" #&CDS_SEC = "1";
"A":   PN = "1"  !CDS_PN = "1";
"B":   PN = "2"  !CDS_PN = "2";
BODY = "Q_RES","I12": #LOCATION = "R3176" !CDS_LOCATION = "R3176" &SEC = "1" #&CDS_SEC = "1";
"A":   PN = "1"  !CDS_PN = "1";
"B":   PN = "2"  !CDS_PN = "2";
BODY = "Q_CAP","I13": #LOCATION = "C1829" !CDS_LOCATION = "C1829" &SEC = "1" #&CDS_SEC = "1";
"A":   PN = "1"  !CDS_PN = "1";
"B":   PN = "2"  !CDS_PN = "2";
BODY = "Q_CAP","I14": #LOCATION = "C1830" !CDS_LOCATION = "C1830" &SEC = "1" #&CDS_SEC = "1";
"A":   PN = "1"  !CDS_PN = "1";
"B":   PN = "2"  !CDS_PN = "2";
BODY = "Q_CAP","I15": #LOCATION = "C1831" !CDS_LOCATION = "C1831" &SEC = "1" #&CDS_SEC = "1";
"A":   PN = "1"  !CDS_PN = "1";
"B":   PN = "2"  !CDS_PN = "2";
BODY = "Q_CAP","I16": #LOCATION = "C1832" !CDS_LOCATION = "C1832" &SEC = "1" #&CDS_SEC = "1";
"A":   PN = "1"  !CDS_PN = "1";
"B":   PN = "2"  !CDS_PN = "2";
BODY = "Q_CAP","I17": #LOCATION = "C1833" !CDS_LOCATION = "C1833" &SEC = "1" #&CDS_SEC = "1";
"A":   PN = "1"  !CDS_PN = "1";
"B":   PN = "2"  !CDS_PN = "2";
BODY = "Q_CAP","I18": #LOCATION = "C1839" !CDS_LOCATION = "C1839" &SEC = "1" #&CDS_SEC = "1";
"A":   PN = "1"  !CDS_PN = "1";
"B":   PN = "2"  !CDS_PN = "2";
BODY = "Q_CAP","I21": #LOCATION = "C1835" !CDS_LOCATION = "C1835" &SEC = "1" #&CDS_SEC = "1";
"A":   PN = "1"  !CDS_PN = "1";
"B":   PN = "2"  !CDS_PN = "2";
BODY = "Q_CAP","I22": #LOCATION = "C1836" !CDS_LOCATION = "C1836" &SEC = "1" #&CDS_SEC = "1";
"A":   PN = "1"  !CDS_PN = "1";
"B":   PN = "2"  !CDS_PN = "2";
BODY = "Q_CAP","I24": #LOCATION = "C1838" !CDS_LOCATION = "C1838" &SEC = "1" #&CDS_SEC = "1";
"A":   PN = "1"  !CDS_PN = "1";
"B":   PN = "2"  !CDS_PN = "2";
BODY = "Q_RES","I28": #LOCATION = "R3166" !CDS_LOCATION = "R3166" &SEC = "1" #&CDS_SEC = "1";
"A":   PN = "1"  !CDS_PN = "1";
"B":   PN = "2"  !CDS_PN = "2";
BODY = "Q_RES","I34": #LOCATION = "R3164" !CDS_LOCATION = "R3164" &SEC = "1" #&CDS_SEC = "1";
"A":   PN = "1"  !CDS_PN = "1";
"B":   PN = "2"  !CDS_PN = "2";
BODY = "Q_RES","I42": #LOCATION = "R3172" !CDS_LOCATION = "R3172" &SEC = "1" #&CDS_SEC = "1";
"A":   PN = "1"  !CDS_PN = "1";
"B":   PN = "2"  !CDS_PN = "2";
BODY = "Q_RES","I44": #LOCATION = "R3170" !CDS_LOCATION = "R3170" &SEC = "1" #&CDS_SEC = "1";
"A":   PN = "1"  !CDS_PN = "1";
"B":   PN = "2"  !CDS_PN = "2";
BODY = "Q_RES","I45": #LOCATION = "R3171" !CDS_LOCATION = "R3171" &SEC = "1" #&CDS_SEC = "1";
"A":   PN = "1"  !CDS_PN = "1";
"B":   PN = "2"  !CDS_PN = "2";
BODY = "Q_RES","I86": #LOCATION = "R3168" !CDS_LOCATION = "R3168" &SEC = "1" #&CDS_SEC = "1";
"A":   PN = "1"  !CDS_PN = "1";
"B":   PN = "2"  !CDS_PN = "2";
BODY = "Q_RES","I135": #LOCATION = "R3178" !CDS_LOCATION = "R3178" &SEC = "1" #&CDS_SEC = "1";
"A":   PN = "1"  !CDS_PN = "1";
"B":   PN = "2"  !CDS_PN = "2";
BODY = "Q_RES","I136": #LOCATION = "R3177" !CDS_LOCATION = "R3177" &SEC = "1" #&CDS_SEC = "1";
"A":   PN = "1"  !CDS_PN = "1";
"B":   PN = "2"  !CDS_PN = "2";
BODY = "Q_RES","I150": #LOCATION = "R3180" !CDS_LOCATION = "R3180" &SEC = "1" #&CDS_SEC = "1";
"A":   PN = "1"  !CDS_PN = "1";
"B":   PN = "2"  !CDS_PN = "2";
BODY = "Q_RES","I170": #LOCATION = "R3229" !CDS_LOCATION = "R3229" #SEC = "1" !CDS_SEC = "1";
"A":   PN = "1"  !CDS_PN = "1";
"B":   PN = "2"  !CDS_PN = "2";
BODY = "Q_RES","I171": #LOCATION = "R3228" !CDS_LOCATION = "R3228" #SEC = "1" !CDS_SEC = "1";
"A":   PN = "1"  !CDS_PN = "1";
"B":   PN = "2"  !CDS_PN = "2";
DRAWING = "@t6g_mb_lib.t6g(sch_1):page342";
BODY = "Q_RES","I6": #LOCATION = "R3234" !CDS_LOCATION = "R3234" &SEC = "1" #&CDS_SEC = "1";
"A":   PN = "1"  !CDS_PN = "1";
"B":   PN = "2"  !CDS_PN = "2";
BODY = "Q_CAP","I12": #LOCATION = "C1841" !CDS_LOCATION = "C1841" &SEC = "1" #&CDS_SEC = "1";
"A":   PN = "1"  !CDS_PN = "1";
"B":   PN = "2"  !CDS_PN = "2";
BODY = "Q_RES","I24": #LOCATION = "R3235" !CDS_LOCATION = "R3235" &SEC = "1" #&CDS_SEC = "1";
"A":   PN = "1"  !CDS_PN = "1";
"B":   PN = "2"  !CDS_PN = "2";
BODY = "Q_CAP","I31": #LOCATION = "C1823" !CDS_LOCATION = "C1823" &SEC = "1" #&CDS_SEC = "1";
"A":   PN = "1"  !CDS_PN = "1";
"B":   PN = "2"  !CDS_PN = "2";
BODY = "Q_RES","I33": #LOCATION = "R3191" !CDS_LOCATION = "R3191" &SEC = "1" #&CDS_SEC = "1";
"A":   PN = "1"  !CDS_PN = "1";
"B":   PN = "2"  !CDS_PN = "2";
BODY = "Q_CAP","I41": #LOCATION = "C1824" !CDS_LOCATION = "C1824" &SEC = "1" #&CDS_SEC = "1";
"A":   PN = "1"  !CDS_PN = "1";
"B":   PN = "2"  !CDS_PN = "2";
BODY = "Q_RES","I44": #LOCATION = "R3192" !CDS_LOCATION = "R3192" &SEC = "1" #&CDS_SEC = "1";
"A":   PN = "1"  !CDS_PN = "1";
"B":   PN = "2"  !CDS_PN = "2";
BODY = "Q_CAP","I47": #LOCATION = "C38" !CDS_LOCATION = "C38" &SEC = "1" #&CDS_SEC = "1";
"A":   PN = "1"  !CDS_PN = "1";
"B":   PN = "2"  !CDS_PN = "2";
BODY = "Q_RES","I3": #LOCATION = "R3182" !CDS_LOCATION = "R3182" &SEC = "1" #&CDS_SEC = "1";
"A":   PN = "1"  !CDS_PN = "1";
"B":   PN = "2"  !CDS_PN = "2";
BODY = "Q_RES","I4": #LOCATION = "R3183" !CDS_LOCATION = "R3183" &SEC = "1" #&CDS_SEC = "1";
"A":   PN = "1"  !CDS_PN = "1";
"B":   PN = "2"  !CDS_PN = "2";
BODY = "74LVC1G126SE7","I9": #LOCATION = "U225" !CDS_LOCATION = "U225" &SEC = "1" #&CDS_SEC = "1";
"A":   PN = "2"  !CDS_PN = "2";
"GND":   PN = "3"  !CDS_PN = "3";
"OE":   PN = "1"  !CDS_PN = "1";
"VCC":   PN = "5"  !CDS_PN = "5";
"Y":   PN = "4"  !CDS_PN = "4";
BODY = "74LVC1G126SE7","I14": #LOCATION = "U217" !CDS_LOCATION = "U217" &SEC = "1" #&CDS_SEC = "1";
"A":   PN = "2"  !CDS_PN = "2";
"GND":   PN = "3"  !CDS_PN = "3";
"OE":   PN = "1"  !CDS_PN = "1";
"VCC":   PN = "5"  !CDS_PN = "5";
"Y":   PN = "4"  !CDS_PN = "4";
BODY = "Q_CAP","I16": #LOCATION = "C1822" !CDS_LOCATION = "C1822" &SEC = "1" #&CDS_SEC = "1";
"A":   PN = "1"  !CDS_PN = "1";
"B":   PN = "2"  !CDS_PN = "2";
BODY = "Q_RES","I18": #LOCATION = "R3184" !CDS_LOCATION = "R3184" &SEC = "1" #&CDS_SEC = "1";
"A":   PN = "1"  !CDS_PN = "1";
"B":   PN = "2"  !CDS_PN = "2";
BODY = "74LVC1G07GV","I22": #LOCATION = "U218" !CDS_LOCATION = "U218" &SEC = "1" #&CDS_SEC = "1";
"A":   PN = "2"  !CDS_PN = "2";
"GND":   PN = "3"  !CDS_PN = "3";
"NC1":   PN = "1"  !CDS_PN = "1";
"VCC":   PN = "5"  !CDS_PN = "5";
"Y":   PN = "4"  !CDS_PN = "4";
BODY = "Q_RES","I25": #LOCATION = "R3236" !CDS_LOCATION = "R3236" &SEC = "1" #&CDS_SEC = "1";
"A":   PN = "1"  !CDS_PN = "1";
"B":   PN = "2"  !CDS_PN = "2";
BODY = "Q_RES","I29": #LOCATION = "R3185" !CDS_LOCATION = "R3185" &SEC = "1" #&CDS_SEC = "1";
"A":   PN = "1"  !CDS_PN = "1";
"B":   PN = "2"  !CDS_PN = "2";
BODY = "74LVC1G07GV","I32": #LOCATION = "U219" !CDS_LOCATION = "U219" &SEC = "1" #&CDS_SEC = "1";
"A":   PN = "2"  !CDS_PN = "2";
"GND":   PN = "3"  !CDS_PN = "3";
"NC1":   PN = "1"  !CDS_PN = "1";
"VCC":   PN = "5"  !CDS_PN = "5";
"Y":   PN = "4"  !CDS_PN = "4";
BODY = "Q_RES","I34": #LOCATION = "R3190" !CDS_LOCATION = "R3190" &SEC = "1" #&CDS_SEC = "1";
"A":   PN = "1"  !CDS_PN = "1";
"B":   PN = "2"  !CDS_PN = "2";
BODY = "Q_RES","I36": #LOCATION = "R4602" !CDS_LOCATION = "R4602" &SEC = "1" #&CDS_SEC = "1";
"A":   PN = "1"  !CDS_PN = "1";
"B":   PN = "2"  !CDS_PN = "2";
BODY = "Q_RES","I43": #LOCATION = "R3193" !CDS_LOCATION = "R3193" &SEC = "1" #&CDS_SEC = "1";
"A":   PN = "1"  !CDS_PN = "1";
"B":   PN = "2"  !CDS_PN = "2";
BODY = "Q_CAP","I55": #LOCATION = "C1821" !CDS_LOCATION = "C1821" &SEC = "1" #&CDS_SEC = "1";
"A":   PN = "1"  !CDS_PN = "1";
"B":   PN = "2"  !CDS_PN = "2";
BODY = "74LVC1G17GW","I58": #LOCATION = "U207" !CDS_LOCATION = "U207" #SEC = "1" !CDS_SEC = "1";
"A":   PN = "2"  !CDS_PN = "2";
"GND":   PN = "3"  !CDS_PN = "3";
"NC":   PN = "1"  !CDS_PN = "1";
"VCC":   PN = "5"  !CDS_PN = "5";
"Y":   PN = "4"  !CDS_PN = "4";
BODY = "Q_RES","I72": #LOCATION = "R6056" !CDS_LOCATION = "R6056" &SEC = "1" #&CDS_SEC = "1";
"A":   PN = "1"  !CDS_PN = "1";
"B":   PN = "2"  !CDS_PN = "2";
BODY = "Q_RES","I73": #LOCATION = "R6057" !CDS_LOCATION = "R6057" &SEC = "1" #&CDS_SEC = "1";
"A":   PN = "1"  !CDS_PN = "1";
"B":   PN = "2"  !CDS_PN = "2";
BODY = "Q_RES","I74": #LOCATION = "R6058" !CDS_LOCATION = "R6058" &SEC = "1" #&CDS_SEC = "1";
"A":   PN = "1"  !CDS_PN = "1";
"B":   PN = "2"  !CDS_PN = "2";
BODY = "Q_RES","I75": #LOCATION = "R6059" !CDS_LOCATION = "R6059" &SEC = "1" #&CDS_SEC = "1";
"A":   PN = "1"  !CDS_PN = "1";
"B":   PN = "2"  !CDS_PN = "2";
BODY = "74LVC1G66GV","I76": #LOCATION = "U321" !CDS_LOCATION = "U321" #SEC = "1" !CDS_SEC = "1";
"E":   PN = "4"  !CDS_PN = "4";
"GND":   PN = "3"  !CDS_PN = "3";
"VCC":   PN = "5"  !CDS_PN = "5";
"Y":   PN = "1"  !CDS_PN = "1";
"Z":   PN = "2"  !CDS_PN = "2";
DRAWING = "@t6g_mb_lib.t6g(sch_1):page343";
BODY = "Q_RES","I6": #LOCATION = "R3136" !CDS_LOCATION = "R3136" &SEC = "1" #&CDS_SEC = "1";
"A":   PN = "1"  !CDS_PN = "1";
"B":   PN = "2"  !CDS_PN = "2";
BODY = "MOSFET_NCH_DUAL","I10": #LOCATION = "Q118" !CDS_LOCATION = "Q118" &SEC = "1" #&CDS_SEC = "1";
"D1":   PN = "6"  !CDS_PN = "6";
"G1":   PN = "2"  !CDS_PN = "2";
"S1":   PN = "1"  !CDS_PN = "1";
BODY = "Q_RES","I14": #LOCATION = "R3133" !CDS_LOCATION = "R3133" &SEC = "1" #&CDS_SEC = "1";
"A":   PN = "1"  !CDS_PN = "1";
"B":   PN = "2"  !CDS_PN = "2";
BODY = "Q_RES","I16": #LOCATION = "R3135" !CDS_LOCATION = "R3135" &SEC = "1" #&CDS_SEC = "1";
"A":   PN = "1"  !CDS_PN = "1";
"B":   PN = "2"  !CDS_PN = "2";
BODY = "MOSFET_NCH_DUAL","I19": #LOCATION = "Q118" !CDS_LOCATION = "Q118" &SEC = "2" #&CDS_SEC = "2";
"D2":   PN = "3"  !CDS_PN = "3";
"G2":   PN = "5"  !CDS_PN = "5";
"S2":   PN = "4"  !CDS_PN = "4";
BODY = "74LVC2G07DW7","I28": #LOCATION = "U58" !CDS_LOCATION = "U58" &SEC = "1" #&CDS_SEC = "1";
"1A":   PN = "1"  !CDS_PN = "1";
"1Y":   PN = "6"  !CDS_PN = "6";
"2A":   PN = "3"  !CDS_PN = "3";
"2Y":   PN = "4"  !CDS_PN = "4";
"GND":   PN = "2"  !CDS_PN = "2";
"VCC":   PN = "5"  !CDS_PN = "5";
BODY = "Q_RES","I33": #LOCATION = "R3827" !CDS_LOCATION = "R3827" &SEC = "1" #&CDS_SEC = "1";
"A":   PN = "1"  !CDS_PN = "1";
"B":   PN = "2"  !CDS_PN = "2";
BODY = "Q_RES","I35": #LOCATION = "PR3806" !CDS_LOCATION = "PR3806" &SEC = "1" #&CDS_SEC = "1";
"A":   PN = "1"  !CDS_PN = "1";
"B":   PN = "2"  !CDS_PN = "2";
BODY = "Q_RES","I36": #LOCATION = "PR3805" !CDS_LOCATION = "PR3805" &SEC = "1" #&CDS_SEC = "1";
"A":   PN = "1"  !CDS_PN = "1";
"B":   PN = "2"  !CDS_PN = "2";
BODY = "MOSFET_NCH_DUAL","I42": #LOCATION = "Q119" !CDS_LOCATION = "Q119" &SEC = "1" #&CDS_SEC = "1";
"D1":   PN = "6"  !CDS_PN = "6";
"G1":   PN = "2"  !CDS_PN = "2";
"S1":   PN = "1"  !CDS_PN = "1";
BODY = "Q_RES","I43": #LOCATION = "R4067" !CDS_LOCATION = "R4067" &SEC = "1" #&CDS_SEC = "1";
"A":   PN = "1"  !CDS_PN = "1";
"B":   PN = "2"  !CDS_PN = "2";
BODY = "MOSFET_NCH_DUAL","I45": #LOCATION = "Q119" !CDS_LOCATION = "Q119" &SEC = "2" #&CDS_SEC = "2";
"D2":   PN = "3"  !CDS_PN = "3";
"G2":   PN = "5"  !CDS_PN = "5";
"S2":   PN = "4"  !CDS_PN = "4";
BODY = "DIODE_TVS","I47": #LOCATION = "PD107" !CDS_LOCATION = "PD107" &SEC = "1" #&CDS_SEC = "1";
"A":   PN = "A"  !CDS_PN = "A";
"C":   PN = "C"  !CDS_PN = "C";
BODY = "Q_CAP","I49": #LOCATION = "PC2139" !CDS_LOCATION = "PC2139" &SEC = "1" #&CDS_SEC = "1";
"A":   PN = "1"  !CDS_PN = "1";
"B":   PN = "2"  !CDS_PN = "2";
BODY = "Q_RES","I51": #LOCATION = "PR3812" !CDS_LOCATION = "PR3812" &SEC = "1" #&CDS_SEC = "1";
"A":   PN = "1"  !CDS_PN = "1";
"B":   PN = "2"  !CDS_PN = "2";
BODY = "Q_RES","I56": #LOCATION = "PR3795" !CDS_LOCATION = "PR3795" &SEC = "1" #&CDS_SEC = "1";
"A":   PN = "1"  !CDS_PN = "1";
"B":   PN = "2"  !CDS_PN = "2";
BODY = "Q_RES","I59": #LOCATION = "R3142" !CDS_LOCATION = "R3142" &SEC = "1" #&CDS_SEC = "1";
"A":   PN = "1"  !CDS_PN = "1";
"B":   PN = "2"  !CDS_PN = "2";
BODY = "Q_RES","I63": #LOCATION = "PR3821" !CDS_LOCATION = "PR3821" &SEC = "1" #&CDS_SEC = "1";
"A":   PN = "1"  !CDS_PN = "1";
"B":   PN = "2"  !CDS_PN = "2";
BODY = "Q_CAP","I65": #LOCATION = "PC2098" !CDS_LOCATION = "PC2098" &SEC = "1" #&CDS_SEC = "1";
"A":   PN = "1"  !CDS_PN = "1";
"B":   PN = "2"  !CDS_PN = "2";
BODY = "Q_CAP","I66": #LOCATION = "PC2146" !CDS_LOCATION = "PC2146" &SEC = "1" #&CDS_SEC = "1";
"A":   PN = "1"  !CDS_PN = "1";
"B":   PN = "2"  !CDS_PN = "2";
BODY = "MAX15090BEWIT","I67": #LOCATION = "PU201" !CDS_LOCATION = "PU201" &SEC = "1" #&CDS_SEC = "1";
"CB":   PN = "B1"  !CDS_PN = "B1";
"CDLY":   PN = "A7"  !CDS_PN = "A7";
"EN#":   PN = "B7"  !CDS_PN = "B7";
"FAULT#":   PN = "C7"  !CDS_PN = "C7";
"GATE":   PN = "A6"  !CDS_PN = "A6";
"GND_B2":   PN = "B2"  !CDS_PN = "B2";
"GND_C1":   PN = "C1"  !CDS_PN = "C1";
"GND_C2":   PN = "C2"  !CDS_PN = "C2";
"IN_A3":   PN = "A3"  !CDS_PN = "A3";
"IN_A5":   PN = "A5"  !CDS_PN = "A5";
"IN_B3":   PN = "B3"  !CDS_PN = "B3";
"IN_B5":   PN = "B5"  !CDS_PN = "B5";
"IN_C3":   PN = "C3"  !CDS_PN = "C3";
"IN_C5":   PN = "C5"  !CDS_PN = "C5";
"IN_D5":   PN = "D5"  !CDS_PN = "D5";
"ISENSE":   PN = "A1"  !CDS_PN = "A1";
"OUT_A4":   PN = "A4"  !CDS_PN = "A4";
"OUT_B4":   PN = "B4"  !CDS_PN = "B4";
"OUT_B6":   PN = "B6"  !CDS_PN = "B6";
"OUT_C4":   PN = "C4"  !CDS_PN = "C4";
"OUT_C6":   PN = "C6"  !CDS_PN = "C6";
"OUT_D4":   PN = "D4"  !CDS_PN = "D4";
"OUT_D6":   PN = "D6"  !CDS_PN = "D6";
"OV":   PN = "D3"  !CDS_PN = "D3";
"PG":   PN = "D7"  !CDS_PN = "D7";
"REG":   PN = "D1"  !CDS_PN = "D1";
"UV":   PN = "D2"  !CDS_PN = "D2";
"VCC":   PN = "A2"  !CDS_PN = "A2";
BODY = "Q_RES","I69": #LOCATION = "R3147" !CDS_LOCATION = "R3147" &SEC = "1" #&CDS_SEC = "1";
"A":   PN = "1"  !CDS_PN = "1";
"B":   PN = "2"  !CDS_PN = "2";
BODY = "Q_RES","I71": #LOCATION = "PR3823" !CDS_LOCATION = "PR3823" &SEC = "1" #&CDS_SEC = "1";
"A":   PN = "1"  !CDS_PN = "1";
"B":   PN = "2"  !CDS_PN = "2";
BODY = "Q_RES","I73": #LOCATION = "R3868" !CDS_LOCATION = "R3868" &SEC = "1" #&CDS_SEC = "1";
"A":   PN = "1"  !CDS_PN = "1";
"B":   PN = "2"  !CDS_PN = "2";
BODY = "Q_RES","I74": #LOCATION = "R3867" !CDS_LOCATION = "R3867" &SEC = "1" #&CDS_SEC = "1";
"A":   PN = "1"  !CDS_PN = "1";
"B":   PN = "2"  !CDS_PN = "2";
BODY = "Q_RES","I80": #LOCATION = "R3825" !CDS_LOCATION = "R3825" &SEC = "1" #&CDS_SEC = "1";
"A":   PN = "1"  !CDS_PN = "1";
"B":   PN = "2"  !CDS_PN = "2";
BODY = "Q_RES","I84": #LOCATION = "PR3830" !CDS_LOCATION = "PR3830" &SEC = "1" #&CDS_SEC = "1";
"A":   PN = "1"  !CDS_PN = "1";
"B":   PN = "2"  !CDS_PN = "2";
BODY = "Q_CAP","I86": #LOCATION = "PC2147" !CDS_LOCATION = "PC2147" &SEC = "1" #&CDS_SEC = "1";
"A":   PN = "1"  !CDS_PN = "1";
"B":   PN = "2"  !CDS_PN = "2";
BODY = "Q_RES","I88": #LOCATION = "PR3822" !CDS_LOCATION = "PR3822" &SEC = "1" #&CDS_SEC = "1";
"A":   PN = "1"  !CDS_PN = "1";
"B":   PN = "2"  !CDS_PN = "2";
BODY = "MAX15090BEWIT","I89": #LOCATION = "PU200" !CDS_LOCATION = "PU200" &SEC = "1" #&CDS_SEC = "1";
"CB":   PN = "B1"  !CDS_PN = "B1";
"CDLY":   PN = "A7"  !CDS_PN = "A7";
"EN#":   PN = "B7"  !CDS_PN = "B7";
"FAULT#":   PN = "C7"  !CDS_PN = "C7";
"GATE":   PN = "A6"  !CDS_PN = "A6";
"GND_B2":   PN = "B2"  !CDS_PN = "B2";
"GND_C1":   PN = "C1"  !CDS_PN = "C1";
"GND_C2":   PN = "C2"  !CDS_PN = "C2";
"IN_A3":   PN = "A3"  !CDS_PN = "A3";
"IN_A5":   PN = "A5"  !CDS_PN = "A5";
"IN_B3":   PN = "B3"  !CDS_PN = "B3";
"IN_B5":   PN = "B5"  !CDS_PN = "B5";
"IN_C3":   PN = "C3"  !CDS_PN = "C3";
"IN_C5":   PN = "C5"  !CDS_PN = "C5";
"IN_D5":   PN = "D5"  !CDS_PN = "D5";
"ISENSE":   PN = "A1"  !CDS_PN = "A1";
"OUT_A4":   PN = "A4"  !CDS_PN = "A4";
"OUT_B4":   PN = "B4"  !CDS_PN = "B4";
"OUT_B6":   PN = "B6"  !CDS_PN = "B6";
"OUT_C4":   PN = "C4"  !CDS_PN = "C4";
"OUT_C6":   PN = "C6"  !CDS_PN = "C6";
"OUT_D4":   PN = "D4"  !CDS_PN = "D4";
"OUT_D6":   PN = "D6"  !CDS_PN = "D6";
"OV":   PN = "D3"  !CDS_PN = "D3";
"PG":   PN = "D7"  !CDS_PN = "D7";
"REG":   PN = "D1"  !CDS_PN = "D1";
"UV":   PN = "D2"  !CDS_PN = "D2";
"VCC":   PN = "A2"  !CDS_PN = "A2";
BODY = "Q_CAP","I90": #LOCATION = "C39" !CDS_LOCATION = "C39" &SEC = "1" #&CDS_SEC = "1";
"A":   PN = "1"  !CDS_PN = "1";
"B":   PN = "2"  !CDS_PN = "2";
BODY = "SCHOTTKY_AC","I92": #LOCATION = "PD108" !CDS_LOCATION = "PD108" &SEC = "1" #&CDS_SEC = "1";
"A":   PN = "A"  !CDS_PN = "A";
"C":   PN = "C"  !CDS_PN = "C";
BODY = "Q_RES","I94": #LOCATION = "PR3824" !CDS_LOCATION = "PR3824" &SEC = "1" #&CDS_SEC = "1";
"A":   PN = "1"  !CDS_PN = "1";
"B":   PN = "2"  !CDS_PN = "2";
BODY = "Q_CAP","I97": #LOCATION = "PC2152" !CDS_LOCATION = "PC2152" &SEC = "1" #&CDS_SEC = "1";
"A":   PN = "1"  !CDS_PN = "1";
"B":   PN = "2"  !CDS_PN = "2";
BODY = "Q_CAP","I99": #LOCATION = "PC2141" !CDS_LOCATION = "PC2141" &SEC = "1" #&CDS_SEC = "1";
"A":   PN = "1"  !CDS_PN = "1";
"B":   PN = "2"  !CDS_PN = "2";
BODY = "Q_CAP","I101": #LOCATION = "PC2143" !CDS_LOCATION = "PC2143" &SEC = "1" #&CDS_SEC = "1";
"A":   PN = "1"  !CDS_PN = "1";
"B":   PN = "2"  !CDS_PN = "2";
BODY = "Q_RES","I105": #LOCATION = "PR4523" !CDS_LOCATION = "PR4523" &SEC = "1" #&CDS_SEC = "1";
"A":   PN = "1"  !CDS_PN = "1";
"B":   PN = "2"  !CDS_PN = "2";
BODY = "Q_RES","I107": #LOCATION = "R3833" !CDS_LOCATION = "R3833" &SEC = "1" #&CDS_SEC = "1";
"A":   PN = "1"  !CDS_PN = "1";
"B":   PN = "2"  !CDS_PN = "2";
BODY = "Q_RES","I4": #LOCATION = "R3134" !CDS_LOCATION = "R3134" &SEC = "1" #&CDS_SEC = "1";
"A":   PN = "1"  !CDS_PN = "1";
"B":   PN = "2"  !CDS_PN = "2";
BODY = "Q_RES","I17": #LOCATION = "R4065" !CDS_LOCATION = "R4065" &SEC = "1" #&CDS_SEC = "1";
"A":   PN = "1"  !CDS_PN = "1";
"B":   PN = "2"  !CDS_PN = "2";
BODY = "74LVC2G07DW7","I22": #LOCATION = "U59" !CDS_LOCATION = "U59" &SEC = "1" #&CDS_SEC = "1";
"1A":   PN = "1"  !CDS_PN = "1";
"1Y":   PN = "6"  !CDS_PN = "6";
"2A":   PN = "3"  !CDS_PN = "3";
"2Y":   PN = "4"  !CDS_PN = "4";
"GND":   PN = "2"  !CDS_PN = "2";
"VCC":   PN = "5"  !CDS_PN = "5";
BODY = "Q_CAP","I23": #LOCATION = "C1810" !CDS_LOCATION = "C1810" &SEC = "1" #&CDS_SEC = "1";
"A":   PN = "1"  !CDS_PN = "1";
"B":   PN = "2"  !CDS_PN = "2";
BODY = "Q_CAP","I29": #LOCATION = "C1809" !CDS_LOCATION = "C1809" &SEC = "1" #&CDS_SEC = "1";
"A":   PN = "1"  !CDS_PN = "1";
"B":   PN = "2"  !CDS_PN = "2";
BODY = "Q_RES","I31": #LOCATION = "PR3828" !CDS_LOCATION = "PR3828" &SEC = "1" #&CDS_SEC = "1";
"A":   PN = "1"  !CDS_PN = "1";
"B":   PN = "2"  !CDS_PN = "2";
BODY = "Q_RES","I50": #LOCATION = "R3807" !CDS_LOCATION = "R3807" &SEC = "1" #&CDS_SEC = "1";
"A":   PN = "1"  !CDS_PN = "1";
"B":   PN = "2"  !CDS_PN = "2";
BODY = "Q_RES","I53": #LOCATION = "PR3829" !CDS_LOCATION = "PR3829" &SEC = "1" #&CDS_SEC = "1";
"A":   PN = "1"  !CDS_PN = "1";
"B":   PN = "2"  !CDS_PN = "2";
BODY = "Q_CAP","I55": #LOCATION = "PC2140" !CDS_LOCATION = "PC2140" &SEC = "1" #&CDS_SEC = "1";
"A":   PN = "1"  !CDS_PN = "1";
"B":   PN = "2"  !CDS_PN = "2";
BODY = "Q_CAP","I72": #LOCATION = "C40" !CDS_LOCATION = "C40" &SEC = "1" #&CDS_SEC = "1";
"A":   PN = "1"  !CDS_PN = "1";
"B":   PN = "2"  !CDS_PN = "2";
BODY = "Q_CAP","I75": #LOCATION = "PC2150" !CDS_LOCATION = "PC2150" &SEC = "1" #&CDS_SEC = "1";
"A":   PN = "1"  !CDS_PN = "1";
"B":   PN = "2"  !CDS_PN = "2";
BODY = "Q_RES","I76": #LOCATION = "PR4522" !CDS_LOCATION = "PR4522" &SEC = "1" #&CDS_SEC = "1";
"A":   PN = "1"  !CDS_PN = "1";
"B":   PN = "2"  !CDS_PN = "2";
BODY = "Q_RES","I77": #LOCATION = "R3831" !CDS_LOCATION = "R3831" &SEC = "1" #&CDS_SEC = "1";
"A":   PN = "1"  !CDS_PN = "1";
"B":   PN = "2"  !CDS_PN = "2";
BODY = "Q_RES","I79": #LOCATION = "R3816" !CDS_LOCATION = "R3816" &SEC = "1" #&CDS_SEC = "1";
"A":   PN = "1"  !CDS_PN = "1";
"B":   PN = "2"  !CDS_PN = "2";
BODY = "Q_RES","I91": #LOCATION = "PR3782" !CDS_LOCATION = "PR3782" &SEC = "1" #&CDS_SEC = "1";
"A":   PN = "1"  !CDS_PN = "1";
"B":   PN = "2"  !CDS_PN = "2";
BODY = "Q_CAP","I95": #LOCATION = "PC2151" !CDS_LOCATION = "PC2151" &SEC = "1" #&CDS_SEC = "1";
"A":   PN = "1"  !CDS_PN = "1";
"B":   PN = "2"  !CDS_PN = "2";
BODY = "Q_CAP","I104": #LOCATION = "PC2149" !CDS_LOCATION = "PC2149" &SEC = "1" #&CDS_SEC = "1";
"A":   PN = "1"  !CDS_PN = "1";
"B":   PN = "2"  !CDS_PN = "2";
BODY = "SCHOTTKY_AC","I106": #LOCATION = "PD109" !CDS_LOCATION = "PD109" &SEC = "1" #&CDS_SEC = "1";
"A":   PN = "A"  !CDS_PN = "A";
"C":   PN = "C"  !CDS_PN = "C";
BODY = "Q_CAP","I108": #LOCATION = "PC2137" !CDS_LOCATION = "PC2137" &SEC = "1" #&CDS_SEC = "1";
"A":   PN = "1"  !CDS_PN = "1";
"B":   PN = "2"  !CDS_PN = "2";
BODY = "Q_CAP","I112": #LOCATION = "PC2142" !CDS_LOCATION = "PC2142" &SEC = "1" #&CDS_SEC = "1";
"A":   PN = "1"  !CDS_PN = "1";
"B":   PN = "2"  !CDS_PN = "2";
BODY = "Q_RES","I116": #LOCATION = "R1191" !CDS_LOCATION = "R1191" &SEC = "1" #&CDS_SEC = "1";
"A":   PN = "1"  !CDS_PN = "1";
"B":   PN = "2"  !CDS_PN = "2";
BODY = "Q_RES","I118": #LOCATION = "R1192" !CDS_LOCATION = "R1192" &SEC = "1" #&CDS_SEC = "1";
"A":   PN = "1"  !CDS_PN = "1";
"B":   PN = "2"  !CDS_PN = "2";
BODY = "Q_RES","I119": #LOCATION = "R4059" !CDS_LOCATION = "R4059" &SEC = "1" #&CDS_SEC = "1";
"A":   PN = "1"  !CDS_PN = "1";
"B":   PN = "2"  !CDS_PN = "2";
BODY = "Q_RES","I120": #LOCATION = "R6060" !CDS_LOCATION = "R6060" &SEC = "1" #&CDS_SEC = "1";
"A":   PN = "1"  !CDS_PN = "1";
"B":   PN = "2"  !CDS_PN = "2";
BODY = "Q_RES","I121": #LOCATION = "R4066" !CDS_LOCATION = "R4066" &SEC = "1" #&CDS_SEC = "1";
"A":   PN = "1"  !CDS_PN = "1";
"B":   PN = "2"  !CDS_PN = "2";
BODY = "Q_RES","I122": #LOCATION = "R4060" !CDS_LOCATION = "R4060" &SEC = "1" #&CDS_SEC = "1";
"A":   PN = "1"  !CDS_PN = "1";
"B":   PN = "2"  !CDS_PN = "2";
BODY = "Q_RES","I123": #LOCATION = "R1181" !CDS_LOCATION = "R1181" &SEC = "1" #&CDS_SEC = "1";
"A":   PN = "1"  !CDS_PN = "1";
"B":   PN = "2"  !CDS_PN = "2";
BODY = "Q_RES","I127": #LOCATION = "R3832" !CDS_LOCATION = "R3832" &SEC = "1" #&CDS_SEC = "1";
"A":   PN = "1"  !CDS_PN = "1";
"B":   PN = "2"  !CDS_PN = "2";
BODY = "Q_RES","I128": #LOCATION = "R3826" !CDS_LOCATION = "R3826" &SEC = "1" #&CDS_SEC = "1";
"A":   PN = "1"  !CDS_PN = "1";
"B":   PN = "2"  !CDS_PN = "2";
BODY = "Q_RES","I129": #LOCATION = "R1182" !CDS_LOCATION = "R1182" &SEC = "1" #&CDS_SEC = "1";
"A":   PN = "1"  !CDS_PN = "1";
"B":   PN = "2"  !CDS_PN = "2";
BODY = "Q_RES","I130": #LOCATION = "R1520" !CDS_LOCATION = "R1520" &SEC = "1" #&CDS_SEC = "1";
"A":   PN = "1"  !CDS_PN = "1";
"B":   PN = "2"  !CDS_PN = "2";
DRAWING = "@t6g_mb_lib.t6g(sch_1):page344";
BODY = "Q_CAP","I2": #LOCATION = "PC2164" !CDS_LOCATION = "PC2164" &SEC = "1" #&CDS_SEC = "1";
"A":   PN = "1"  !CDS_PN = "1";
"B":   PN = "2"  !CDS_PN = "2";
BODY = "Q_RES","I4": #LOCATION = "PR3847" !CDS_LOCATION = "PR3847" &SEC = "1" #&CDS_SEC = "1";
"A":   PN = "1"  !CDS_PN = "1";
"B":   PN = "2"  !CDS_PN = "2";
BODY = "Q_CAP","I6": #LOCATION = "PC2166" !CDS_LOCATION = "PC2166" &SEC = "1" #&CDS_SEC = "1";
"A":   PN = "1"  !CDS_PN = "1";
"B":   PN = "2"  !CDS_PN = "2";
BODY = "Q_CAP","I13": #LOCATION = "PC2165" !CDS_LOCATION = "PC2165" &SEC = "1" #&CDS_SEC = "1";
"A":   PN = "1"  !CDS_PN = "1";
"B":   PN = "2"  !CDS_PN = "2";
BODY = "Q_RES","I15": #LOCATION = "PR3849" !CDS_LOCATION = "PR3849" &SEC = "1" #&CDS_SEC = "1";
"A":   PN = "1"  !CDS_PN = "1";
"B":   PN = "2"  !CDS_PN = "2";
BODY = "Q_RES","I18": #LOCATION = "PR3851" !CDS_LOCATION = "PR3851" &SEC = "1" #&CDS_SEC = "1";
"A":   PN = "1"  !CDS_PN = "1";
"B":   PN = "2"  !CDS_PN = "2";
BODY = "Q_RES","I20": #LOCATION = "PR3854" !CDS_LOCATION = "PR3854" &SEC = "1" #&CDS_SEC = "1";
"A":   PN = "1"  !CDS_PN = "1";
"B":   PN = "2"  !CDS_PN = "2";
BODY = "Q_RES","I22": #LOCATION = "R3874" !CDS_LOCATION = "R3874" &SEC = "1" #&CDS_SEC = "1";
"A":   PN = "1"  !CDS_PN = "1";
"B":   PN = "2"  !CDS_PN = "2";
BODY = "Q_RES","I23": #LOCATION = "R3873" !CDS_LOCATION = "R3873" &SEC = "1" #&CDS_SEC = "1";
"A":   PN = "1"  !CDS_PN = "1";
"B":   PN = "2"  !CDS_PN = "2";
BODY = "Q_CAP","I24": #LOCATION = "PC1320" !CDS_LOCATION = "PC1320" &SEC = "1" #&CDS_SEC = "1";
"A":   PN = "1"  !CDS_PN = "1";
"B":   PN = "2"  !CDS_PN = "2";
BODY = "Q_RES","I27": #LOCATION = "R3848" !CDS_LOCATION = "R3848" &SEC = "1" #&CDS_SEC = "1";
"A":   PN = "1"  !CDS_PN = "1";
"B":   PN = "2"  !CDS_PN = "2";
BODY = "Q_RES","I30": #LOCATION = "PR3850" !CDS_LOCATION = "PR3850" &SEC = "1" #&CDS_SEC = "1";
"A":   PN = "1"  !CDS_PN = "1";
"B":   PN = "2"  !CDS_PN = "2";
BODY = "Q_RES","I31": #LOCATION = "PR3852" !CDS_LOCATION = "PR3852" &SEC = "1" #&CDS_SEC = "1";
"A":   PN = "1"  !CDS_PN = "1";
"B":   PN = "2"  !CDS_PN = "2";
BODY = "Q_CAP","I35": #LOCATION = "PC2168" !CDS_LOCATION = "PC2168" &SEC = "1" #&CDS_SEC = "1";
"A":   PN = "1"  !CDS_PN = "1";
"B":   PN = "2"  !CDS_PN = "2";
BODY = "Q_RES","I36": #LOCATION = "PR3853" !CDS_LOCATION = "PR3853" &SEC = "1" #&CDS_SEC = "1";
"A":   PN = "1"  !CDS_PN = "1";
"B":   PN = "2"  !CDS_PN = "2";
BODY = "Q_RES","I37": #LOCATION = "PR3857" !CDS_LOCATION = "PR3857" &SEC = "1" #&CDS_SEC = "1";
"A":   PN = "1"  !CDS_PN = "1";
"B":   PN = "2"  !CDS_PN = "2";
BODY = "Q_CAP","I40": #LOCATION = "PC2174" !CDS_LOCATION = "PC2174" &SEC = "1" #&CDS_SEC = "1";
"A":   PN = "1"  !CDS_PN = "1";
"B":   PN = "2"  !CDS_PN = "2";
BODY = "Q_RES","I43": #LOCATION = "PR3855" !CDS_LOCATION = "PR3855" &SEC = "1" #&CDS_SEC = "1";
"A":   PN = "1"  !CDS_PN = "1";
"B":   PN = "2"  !CDS_PN = "2";
BODY = "Q_RES","I46": #LOCATION = "PR3856" !CDS_LOCATION = "PR3856" &SEC = "1" #&CDS_SEC = "1";
"A":   PN = "1"  !CDS_PN = "1";
"B":   PN = "2"  !CDS_PN = "2";
BODY = "Q_CAP","I48": #LOCATION = "PC2169" !CDS_LOCATION = "PC2169" &SEC = "1" #&CDS_SEC = "1";
"A":   PN = "1"  !CDS_PN = "1";
"B":   PN = "2"  !CDS_PN = "2";
BODY = "Q_CAP","I50": #LOCATION = "PC1321" !CDS_LOCATION = "PC1321" &SEC = "1" #&CDS_SEC = "1";
"A":   PN = "1"  !CDS_PN = "1";
"B":   PN = "2"  !CDS_PN = "2";
BODY = "MP5016GQHLZ","I51": #LOCATION = "PU207" !CDS_LOCATION = "PU207" &SEC = "1" #&CDS_SEC = "1";
"DV_DT":   PN = "10"  !CDS_PN = "10";
"EN":   PN = "9"  !CDS_PN = "9";
"GATE":   PN = "8"  !CDS_PN = "8";
"GND":   PN = "3"  !CDS_PN = "3";
"ILIMIT":   PN = "4"  !CDS_PN = "4";
"MODE":   PN = "5"  !CDS_PN = "5";
"SOURCE":   PN = "6_7"  !CDS_PN = "6_7";
"VCC":   PN = "1_2"  !CDS_PN = "1_2";
BODY = "Q_CAP","I54": #LOCATION = "PC1322" !CDS_LOCATION = "PC1322" &SEC = "1" #&CDS_SEC = "1";
"A":   PN = "1"  !CDS_PN = "1";
"B":   PN = "2"  !CDS_PN = "2";
BODY = "Q_CAP","I56": #LOCATION = "PC2173" !CDS_LOCATION = "PC2173" &SEC = "1" #&CDS_SEC = "1";
"A":   PN = "1"  !CDS_PN = "1";
"B":   PN = "2"  !CDS_PN = "2";
BODY = "Q_CAP","I58": #LOCATION = "PC2167" !CDS_LOCATION = "PC2167" &SEC = "1" #&CDS_SEC = "1";
"A":   PN = "1"  !CDS_PN = "1";
"B":   PN = "2"  !CDS_PN = "2";
BODY = "Q_RES","I73": #LOCATION = "R3630" !CDS_LOCATION = "R3630" &SEC = "1" #&CDS_SEC = "1";
"A":   PN = "1"  !CDS_PN = "1";
"B":   PN = "2"  !CDS_PN = "2";
BODY = "Q_RES","I74": #LOCATION = "R3631" !CDS_LOCATION = "R3631" &SEC = "1" #&CDS_SEC = "1";
"A":   PN = "1"  !CDS_PN = "1";
"B":   PN = "2"  !CDS_PN = "2";
BODY = "Q_RES","I76": #LOCATION = "R1193" !CDS_LOCATION = "R1193" &SEC = "1" #&CDS_SEC = "1";
"A":   PN = "1"  !CDS_PN = "1";
"B":   PN = "2"  !CDS_PN = "2";
BODY = "Q_RES","I79": #LOCATION = "R1196" !CDS_LOCATION = "R1196" &SEC = "1" #&CDS_SEC = "1";
"A":   PN = "1"  !CDS_PN = "1";
"B":   PN = "2"  !CDS_PN = "2";
BODY = "Q_RES","I80": #LOCATION = "R1521" !CDS_LOCATION = "R1521" &SEC = "1" #&CDS_SEC = "1";
"A":   PN = "1"  !CDS_PN = "1";
"B":   PN = "2"  !CDS_PN = "2";
BODY = "RS31312R","I82": #LOCATION = "PU206" !CDS_LOCATION = "PU206" #SEC = "1" !CDS_SEC = "1";
"AVIN":   PN = "12"  !CDS_PN = "12";
"EN":   PN = "1"  !CDS_PN = "1";
"ENTM":   PN = "3"  !CDS_PN = "3";
"FLTB":   PN = "9"  !CDS_PN = "9";
"GND":   PN = "7"  !CDS_PN = "7";
"IMON":   PN = "8"  !CDS_PN = "8";
"ISET":   PN = "5"  !CDS_PN = "5";
"LOADEN":   PN = "2"  !CDS_PN = "2";
"OV":   PN = "11"  !CDS_PN = "11";
"PG":   PN = "10"  !CDS_PN = "10";
"SS":   PN = "6"  !CDS_PN = "6";
"TIMER":   PN = "4"  !CDS_PN = "4";
"VIN_21_22":   PN = "21_22"  !CDS_PN = "21_22";
"VIN_23":   PN = "23"  !CDS_PN = "23";
"VIN_24":   PN = "24"  !CDS_PN = "24";
"VIN_25":   PN = "25"  !CDS_PN = "25";
"VIN_26":   PN = "26"  !CDS_PN = "26";
"VOUT_13":   PN = "13"  !CDS_PN = "13";
"VOUT_14":   PN = "14"  !CDS_PN = "14";
"VOUT_15":   PN = "15"  !CDS_PN = "15";
"VOUT_16":   PN = "16"  !CDS_PN = "16";
"VOUT_17":   PN = "17"  !CDS_PN = "17";
"VOUT_18":   PN = "18"  !CDS_PN = "18";
"VOUT_19":   PN = "19"  !CDS_PN = "19";
"VOUT_20":   PN = "20"  !CDS_PN = "20";
DRAWING = "@t6g_mb_lib.t6g(sch_1):page258";
BODY = "74LVC2G08DP","I1": #LOCATION = "U241" !CDS_LOCATION = "U241" &SEC = "1" #&CDS_SEC = "1";
"1A":   PN = "1"  !CDS_PN = "1";
"1B":   PN = "2"  !CDS_PN = "2";
"1Y":   PN = "7"  !CDS_PN = "7";
"GND":   PN = "4"  !CDS_PN = "4";
"VCC":   PN = "8"  !CDS_PN = "8";
BODY = "74LVC2G08DP","I2": #LOCATION = "U241" !CDS_LOCATION = "U241" &SEC = "2" #&CDS_SEC = "2";
"2A":   PN = "5"  !CDS_PN = "5";
"2B":   PN = "6"  !CDS_PN = "6";
"2Y":   PN = "3"  !CDS_PN = "3";
BODY = "74LVC2G08DP","I11": #LOCATION = "U240" !CDS_LOCATION = "U240" &SEC = "1" #&CDS_SEC = "1";
"1A":   PN = "1"  !CDS_PN = "1";
"1B":   PN = "2"  !CDS_PN = "2";
"1Y":   PN = "7"  !CDS_PN = "7";
"GND":   PN = "4"  !CDS_PN = "4";
"VCC":   PN = "8"  !CDS_PN = "8";
BODY = "74LVC2G08DP","I12": #LOCATION = "U240" !CDS_LOCATION = "U240" &SEC = "2" #&CDS_SEC = "2";
"2A":   PN = "5"  !CDS_PN = "5";
"2B":   PN = "6"  !CDS_PN = "6";
"2Y":   PN = "3"  !CDS_PN = "3";
BODY = "74LVC2G08DP","I13": #LOCATION = "U242" !CDS_LOCATION = "U242" &SEC = "1" #&CDS_SEC = "1";
"1A":   PN = "1"  !CDS_PN = "1";
"1B":   PN = "2"  !CDS_PN = "2";
"1Y":   PN = "7"  !CDS_PN = "7";
"GND":   PN = "4"  !CDS_PN = "4";
"VCC":   PN = "8"  !CDS_PN = "8";
BODY = "74LVC2G08DP","I14": #LOCATION = "U242" !CDS_LOCATION = "U242" &SEC = "2" #&CDS_SEC = "2";
"2A":   PN = "5"  !CDS_PN = "5";
"2B":   PN = "6"  !CDS_PN = "6";
"2Y":   PN = "3"  !CDS_PN = "3";
BODY = "NC7SB3157","I15": #LOCATION = "U243" !CDS_LOCATION = "U243" &SEC = "1" #&CDS_SEC = "1";
"A":   PN = "4"  !CDS_PN = "4";
"B0":   PN = "3"  !CDS_PN = "3";
"B1":   PN = "1"  !CDS_PN = "1";
"GND":   PN = "2"  !CDS_PN = "2";
"S":   PN = "6"  !CDS_PN = "6";
"VCC":   PN = "5"  !CDS_PN = "5";
BODY = "NC7SB3157","I16": #LOCATION = "U244" !CDS_LOCATION = "U244" &SEC = "1" #&CDS_SEC = "1";
"A":   PN = "4"  !CDS_PN = "4";
"B0":   PN = "3"  !CDS_PN = "3";
"B1":   PN = "1"  !CDS_PN = "1";
"GND":   PN = "2"  !CDS_PN = "2";
"S":   PN = "6"  !CDS_PN = "6";
"VCC":   PN = "5"  !CDS_PN = "5";
BODY = "NC7SB3157","I17": #LOCATION = "U246" !CDS_LOCATION = "U246" &SEC = "1" #&CDS_SEC = "1";
"A":   PN = "4"  !CDS_PN = "4";
"B0":   PN = "3"  !CDS_PN = "3";
"B1":   PN = "1"  !CDS_PN = "1";
"GND":   PN = "2"  !CDS_PN = "2";
"S":   PN = "6"  !CDS_PN = "6";
"VCC":   PN = "5"  !CDS_PN = "5";
BODY = "NC7SB3157","I18": #LOCATION = "U245" !CDS_LOCATION = "U245" &SEC = "1" #&CDS_SEC = "1";
"A":   PN = "4"  !CDS_PN = "4";
"B0":   PN = "3"  !CDS_PN = "3";
"B1":   PN = "1"  !CDS_PN = "1";
"GND":   PN = "2"  !CDS_PN = "2";
"S":   PN = "6"  !CDS_PN = "6";
"VCC":   PN = "5"  !CDS_PN = "5";
BODY = "Q_CAP","I21": #LOCATION = "C1875" !CDS_LOCATION = "C1875" &SEC = "1" #&CDS_SEC = "1";
"A":   PN = "1"  !CDS_PN = "1";
"B":   PN = "2"  !CDS_PN = "2";
BODY = "Q_CAP","I22": #LOCATION = "C1874" !CDS_LOCATION = "C1874" &SEC = "1" #&CDS_SEC = "1";
"A":   PN = "1"  !CDS_PN = "1";
"B":   PN = "2"  !CDS_PN = "2";
BODY = "Q_CAP","I27": #LOCATION = "C1880" !CDS_LOCATION = "C1880" &SEC = "1" #&CDS_SEC = "1";
"A":   PN = "1"  !CDS_PN = "1";
"B":   PN = "2"  !CDS_PN = "2";
BODY = "Q_CAP","I31": #LOCATION = "C1879" !CDS_LOCATION = "C1879" &SEC = "1" #&CDS_SEC = "1";
"A":   PN = "1"  !CDS_PN = "1";
"B":   PN = "2"  !CDS_PN = "2";
BODY = "Q_CAP","I34": #LOCATION = "C1877" !CDS_LOCATION = "C1877" &SEC = "1" #&CDS_SEC = "1";
"A":   PN = "1"  !CDS_PN = "1";
"B":   PN = "2"  !CDS_PN = "2";
BODY = "Q_CAP","I37": #LOCATION = "C1878" !CDS_LOCATION = "C1878" &SEC = "1" #&CDS_SEC = "1";
"A":   PN = "1"  !CDS_PN = "1";
"B":   PN = "2"  !CDS_PN = "2";
BODY = "Q_CAP","I41": #LOCATION = "C1876" !CDS_LOCATION = "C1876" &SEC = "1" #&CDS_SEC = "1";
"A":   PN = "1"  !CDS_PN = "1";
"B":   PN = "2"  !CDS_PN = "2";
BODY = "Q_RES","I44": #LOCATION = "R3303" !CDS_LOCATION = "R3303" &SEC = "1" #&CDS_SEC = "1";
"A":   PN = "1"  !CDS_PN = "1";
"B":   PN = "2"  !CDS_PN = "2";
BODY = "Q_RES","I45": #LOCATION = "R3304" !CDS_LOCATION = "R3304" &SEC = "1" #&CDS_SEC = "1";
"A":   PN = "1"  !CDS_PN = "1";
"B":   PN = "2"  !CDS_PN = "2";
BODY = "Q_RES","I46": #LOCATION = "R3308" !CDS_LOCATION = "R3308" &SEC = "1" #&CDS_SEC = "1";
"A":   PN = "1"  !CDS_PN = "1";
"B":   PN = "2"  !CDS_PN = "2";
BODY = "Q_RES","I47": #LOCATION = "R3306" !CDS_LOCATION = "R3306" &SEC = "1" #&CDS_SEC = "1";
"A":   PN = "1"  !CDS_PN = "1";
"B":   PN = "2"  !CDS_PN = "2";
BODY = "Q_RES","I50": #LOCATION = "R3305" !CDS_LOCATION = "R3305" &SEC = "1" #&CDS_SEC = "1";
"A":   PN = "1"  !CDS_PN = "1";
"B":   PN = "2"  !CDS_PN = "2";
BODY = "Q_RES","I52": #LOCATION = "R3307" !CDS_LOCATION = "R3307" &SEC = "1" #&CDS_SEC = "1";
"A":   PN = "1"  !CDS_PN = "1";
"B":   PN = "2"  !CDS_PN = "2";
BODY = "Q_RES","I64": #LOCATION = "R8013" !CDS_LOCATION = "R8013" #SEC = "1" !CDS_SEC = "1";
"A":   PN = "1"  !CDS_PN = "1";
"B":   PN = "2"  !CDS_PN = "2";
BODY = "Q_RES","I65": #LOCATION = "R8014" !CDS_LOCATION = "R8014" #SEC = "1" !CDS_SEC = "1";
"A":   PN = "1"  !CDS_PN = "1";
"B":   PN = "2"  !CDS_PN = "2";
BODY = "Q_RES","I66": #LOCATION = "R8015" !CDS_LOCATION = "R8015" #SEC = "1" !CDS_SEC = "1";
"A":   PN = "1"  !CDS_PN = "1";
"B":   PN = "2"  !CDS_PN = "2";
BODY = "Q_RES","I67": #LOCATION = "R8016" !CDS_LOCATION = "R8016" #SEC = "1" !CDS_SEC = "1";
"A":   PN = "1"  !CDS_PN = "1";
"B":   PN = "2"  !CDS_PN = "2";
BODY = "Q_CAP","I68": #LOCATION = "C8001" !CDS_LOCATION = "C8001" #SEC = "1" !CDS_SEC = "1";
"A":   PN = "1"  !CDS_PN = "1";
"B":   PN = "2"  !CDS_PN = "2";
BODY = "Q_CAP","I70": #LOCATION = "C8002" !CDS_LOCATION = "C8002" &SEC = "1" #&CDS_SEC = "1";
"A":   PN = "1"  !CDS_PN = "1";
"B":   PN = "2"  !CDS_PN = "2";
BODY = "Q_CAP","I72": #LOCATION = "C8003" !CDS_LOCATION = "C8003" &SEC = "1" #&CDS_SEC = "1";
"A":   PN = "1"  !CDS_PN = "1";
"B":   PN = "2"  !CDS_PN = "2";
BODY = "Q_CAP","I74": #LOCATION = "C8004" !CDS_LOCATION = "C8004" &SEC = "1" #&CDS_SEC = "1";
"A":   PN = "1"  !CDS_PN = "1";
"B":   PN = "2"  !CDS_PN = "2";
DRAWING = "@t6g_mb_lib.t6g(sch_1):page323";
BODY = "Q_CAP","I3": #LOCATION = "PC2197" !CDS_LOCATION = "PC2197" &SEC = "1" #&CDS_SEC = "1";
"A":   PN = "1"  !CDS_PN = "1";
"B":   PN = "2"  !CDS_PN = "2";
BODY = "Q_RES","I4": #LOCATION = "PR3945" !CDS_LOCATION = "PR3945" &SEC = "1" #&CDS_SEC = "1";
"A":   PN = "1"  !CDS_PN = "1";
"B":   PN = "2"  !CDS_PN = "2";
BODY = "Q_RES","I5": #LOCATION = "R3946" !CDS_LOCATION = "R3946" &SEC = "1" #&CDS_SEC = "1";
"A":   PN = "1"  !CDS_PN = "1";
"B":   PN = "2"  !CDS_PN = "2";
BODY = "Q_RES","I6": #LOCATION = "PR3947" !CDS_LOCATION = "PR3947" &SEC = "1" #&CDS_SEC = "1";
"A":   PN = "1"  !CDS_PN = "1";
"B":   PN = "2"  !CDS_PN = "2";
BODY = "Q_CAP","I9": #LOCATION = "PC2200" !CDS_LOCATION = "PC2200" &SEC = "1" #&CDS_SEC = "1";
"A":   PN = "1"  !CDS_PN = "1";
"B":   PN = "2"  !CDS_PN = "2";
BODY = "Q_CAP","I13": #LOCATION = "PC2196" !CDS_LOCATION = "PC2196" &SEC = "1" #&CDS_SEC = "1";
"A":   PN = "1"  !CDS_PN = "1";
"B":   PN = "2"  !CDS_PN = "2";
BODY = "Q_RES","I15": #LOCATION = "PR3944" !CDS_LOCATION = "PR3944" &SEC = "1" #&CDS_SEC = "1";
"A":   PN = "1"  !CDS_PN = "1";
"B":   PN = "2"  !CDS_PN = "2";
BODY = "Q_CAP","I17": #LOCATION = "PC2341" !CDS_LOCATION = "PC2341" &SEC = "1" #&CDS_SEC = "1";
"A":   PN = "1"  !CDS_PN = "1";
"B":   PN = "2"  !CDS_PN = "2";
BODY = "Q_RES","I18": #LOCATION = "PR4541" !CDS_LOCATION = "PR4541" &SEC = "1" #&CDS_SEC = "1";
"A":   PN = "1"  !CDS_PN = "1";
"B":   PN = "2"  !CDS_PN = "2";
BODY = "Q_RES","I19": #LOCATION = "R3943" !CDS_LOCATION = "R3943" &SEC = "1" #&CDS_SEC = "1";
"A":   PN = "1"  !CDS_PN = "1";
"B":   PN = "2"  !CDS_PN = "2";
BODY = "Q_CAP","I22": #LOCATION = "PC2281" !CDS_LOCATION = "PC2281" &SEC = "1" #&CDS_SEC = "1";
"A":   PN = "1"  !CDS_PN = "1";
"B":   PN = "2"  !CDS_PN = "2";
BODY = "Q_CAP","I25": #LOCATION = "PC2198" !CDS_LOCATION = "PC2198" &SEC = "1" #&CDS_SEC = "1";
"A":   PN = "1"  !CDS_PN = "1";
"B":   PN = "2"  !CDS_PN = "2";
BODY = "Q_CAP","I30": #LOCATION = "PC2201" !CDS_LOCATION = "PC2201" &SEC = "1" #&CDS_SEC = "1";
"A":   PN = "1"  !CDS_PN = "1";
"B":   PN = "2"  !CDS_PN = "2";
BODY = "MP5016GQHLZ","I31": #LOCATION = "PU293" !CDS_LOCATION = "PU293" &SEC = "1" #&CDS_SEC = "1";
"DV_DT":   PN = "10"  !CDS_PN = "10";
"EN":   PN = "9"  !CDS_PN = "9";
"GATE":   PN = "8"  !CDS_PN = "8";
"GND":   PN = "3"  !CDS_PN = "3";
"ILIMIT":   PN = "4"  !CDS_PN = "4";
"MODE":   PN = "5"  !CDS_PN = "5";
"SOURCE":   PN = "6_7"  !CDS_PN = "6_7";
"VCC":   PN = "1_2"  !CDS_PN = "1_2";
BODY = "Q_CAP","I32": #LOCATION = "PC2203" !CDS_LOCATION = "PC2203" &SEC = "1" #&CDS_SEC = "1";
"A":   PN = "1"  !CDS_PN = "1";
"B":   PN = "2"  !CDS_PN = "2";
BODY = "Q_CAP","I34": #LOCATION = "PC2204" !CDS_LOCATION = "PC2204" &SEC = "1" #&CDS_SEC = "1";
"A":   PN = "1"  !CDS_PN = "1";
"B":   PN = "2"  !CDS_PN = "2";
BODY = "Q_RES","I36": #LOCATION = "PR3949" !CDS_LOCATION = "PR3949" &SEC = "1" #&CDS_SEC = "1";
"A":   PN = "1"  !CDS_PN = "1";
"B":   PN = "2"  !CDS_PN = "2";
BODY = "Q_RES","I37": #LOCATION = "R3948" !CDS_LOCATION = "R3948" &SEC = "1" #&CDS_SEC = "1";
"A":   PN = "1"  !CDS_PN = "1";
"B":   PN = "2"  !CDS_PN = "2";
BODY = "Q_CAP","I39": #LOCATION = "PC2202" !CDS_LOCATION = "PC2202" &SEC = "1" #&CDS_SEC = "1";
"A":   PN = "1"  !CDS_PN = "1";
"B":   PN = "2"  !CDS_PN = "2";
BODY = "Q_RES","I40": #LOCATION = "PR3951" !CDS_LOCATION = "PR3951" &SEC = "1" #&CDS_SEC = "1";
"A":   PN = "1"  !CDS_PN = "1";
"B":   PN = "2"  !CDS_PN = "2";
BODY = "Q_RES","I42": #LOCATION = "PR3950" !CDS_LOCATION = "PR3950" &SEC = "1" #&CDS_SEC = "1";
"A":   PN = "1"  !CDS_PN = "1";
"B":   PN = "2"  !CDS_PN = "2";
BODY = "Q_RES","I45": #LOCATION = "PR3952" !CDS_LOCATION = "PR3952" &SEC = "1" #&CDS_SEC = "1";
"A":   PN = "1"  !CDS_PN = "1";
"B":   PN = "2"  !CDS_PN = "2";
BODY = "Q_RES","I47": #LOCATION = "R3956" !CDS_LOCATION = "R3956" &SEC = "1" #&CDS_SEC = "1";
"A":   PN = "1"  !CDS_PN = "1";
"B":   PN = "2"  !CDS_PN = "2";
BODY = "Q_RES","I48": #LOCATION = "R3955" !CDS_LOCATION = "R3955" &SEC = "1" #&CDS_SEC = "1";
"A":   PN = "1"  !CDS_PN = "1";
"B":   PN = "2"  !CDS_PN = "2";
BODY = "Q_RES","I49": #LOCATION = "PR3954" !CDS_LOCATION = "PR3954" &SEC = "1" #&CDS_SEC = "1";
"A":   PN = "1"  !CDS_PN = "1";
"B":   PN = "2"  !CDS_PN = "2";
BODY = "Q_CAP","I51": #LOCATION = "PC2205" !CDS_LOCATION = "PC2205" &SEC = "1" #&CDS_SEC = "1";
"A":   PN = "1"  !CDS_PN = "1";
"B":   PN = "2"  !CDS_PN = "2";
BODY = "Q_RES","I52": #LOCATION = "PR3953" !CDS_LOCATION = "PR3953" &SEC = "1" #&CDS_SEC = "1";
"A":   PN = "1"  !CDS_PN = "1";
"B":   PN = "2"  !CDS_PN = "2";
BODY = "Q_RES","I54": #LOCATION = "PR3957" !CDS_LOCATION = "PR3957" &SEC = "1" #&CDS_SEC = "1";
"A":   PN = "1"  !CDS_PN = "1";
"B":   PN = "2"  !CDS_PN = "2";
BODY = "Q_CAP","I56": #LOCATION = "PC2206" !CDS_LOCATION = "PC2206" &SEC = "1" #&CDS_SEC = "1";
"A":   PN = "1"  !CDS_PN = "1";
"B":   PN = "2"  !CDS_PN = "2";
BODY = "Q_CAP","I64": #LOCATION = "C8010" !CDS_LOCATION = "C8010" &SEC = "1" #&CDS_SEC = "1";
"A":   PN = "1"  !CDS_PN = "1";
"B":   PN = "2"  !CDS_PN = "2";
BODY = "APX80929SAG7","I65": #LOCATION = "U8003" !CDS_LOCATION = "U8003" &SEC = "1" #&CDS_SEC = "1";
"GND":   PN = "1"  !CDS_PN = "1";
"RESET_L":   PN = "2"  !CDS_PN = "2";
"VCC":   PN = "3"  !CDS_PN = "3";
BODY = "Q_RES","I68": #LOCATION = "R8099" !CDS_LOCATION = "R8099" &SEC = "1" #&CDS_SEC = "1";
"A":   PN = "1"  !CDS_PN = "1";
"B":   PN = "2"  !CDS_PN = "2";
BODY = "Q_RES","I70": #LOCATION = "R8098" !CDS_LOCATION = "R8098" &SEC = "1" #&CDS_SEC = "1";
"A":   PN = "1"  !CDS_PN = "1";
"B":   PN = "2"  !CDS_PN = "2";
BODY = "Q_RES","I71": #LOCATION = "R8100" !CDS_LOCATION = "R8100" &SEC = "1" #&CDS_SEC = "1";
"A":   PN = "1"  !CDS_PN = "1";
"B":   PN = "2"  !CDS_PN = "2";
BODY = "RS31312R","I76": #LOCATION = "PU292" !CDS_LOCATION = "PU292" #SEC = "1" !CDS_SEC = "1";
"AVIN":   PN = "12"  !CDS_PN = "12";
"EN":   PN = "1"  !CDS_PN = "1";
"ENTM":   PN = "3"  !CDS_PN = "3";
"FLTB":   PN = "9"  !CDS_PN = "9";
"GND":   PN = "7"  !CDS_PN = "7";
"IMON":   PN = "8"  !CDS_PN = "8";
"ISET":   PN = "5"  !CDS_PN = "5";
"LOADEN":   PN = "2"  !CDS_PN = "2";
"OV":   PN = "11"  !CDS_PN = "11";
"PG":   PN = "10"  !CDS_PN = "10";
"SS":   PN = "6"  !CDS_PN = "6";
"TIMER":   PN = "4"  !CDS_PN = "4";
"VIN_21_22":   PN = "21_22"  !CDS_PN = "21_22";
"VIN_23":   PN = "23"  !CDS_PN = "23";
"VIN_24":   PN = "24"  !CDS_PN = "24";
"VIN_25":   PN = "25"  !CDS_PN = "25";
"VIN_26":   PN = "26"  !CDS_PN = "26";
"VOUT_13":   PN = "13"  !CDS_PN = "13";
"VOUT_14":   PN = "14"  !CDS_PN = "14";
"VOUT_15":   PN = "15"  !CDS_PN = "15";
"VOUT_16":   PN = "16"  !CDS_PN = "16";
"VOUT_17":   PN = "17"  !CDS_PN = "17";
"VOUT_18":   PN = "18"  !CDS_PN = "18";
"VOUT_19":   PN = "19"  !CDS_PN = "19";
"VOUT_20":   PN = "20"  !CDS_PN = "20";
DRAWING = "@t6g_mb_lib.t6g(sch_1):page324";
BODY = "Q_RES","I2": #LOCATION = "R4063" !CDS_LOCATION = "R4063" &SEC = "1" #&CDS_SEC = "1";
"A":   PN = "1"  !CDS_PN = "1";
"B":   PN = "2"  !CDS_PN = "2";
BODY = "Q_RES","I4": #LOCATION = "R6049" !CDS_LOCATION = "R6049" &SEC = "1" #&CDS_SEC = "1";
"A":   PN = "1"  !CDS_PN = "1";
"B":   PN = "2"  !CDS_PN = "2";
BODY = "MOSFET_NCH_DUAL","I6": #LOCATION = "Q126" !CDS_LOCATION = "Q126" &SEC = "1" #&CDS_SEC = "1";
"D1":   PN = "6"  !CDS_PN = "6";
"G1":   PN = "2"  !CDS_PN = "2";
"S1":   PN = "1"  !CDS_PN = "1";
BODY = "Q_RES","I11": #LOCATION = "R4073" !CDS_LOCATION = "R4073" &SEC = "1" #&CDS_SEC = "1";
"A":   PN = "1"  !CDS_PN = "1";
"B":   PN = "2"  !CDS_PN = "2";
BODY = "Q_RES","I16": #LOCATION = "PR3965" !CDS_LOCATION = "PR3965" &SEC = "1" #&CDS_SEC = "1";
"A":   PN = "1"  !CDS_PN = "1";
"B":   PN = "2"  !CDS_PN = "2";
BODY = "Q_RES","I17": #LOCATION = "PR3964" !CDS_LOCATION = "PR3964" &SEC = "1" #&CDS_SEC = "1";
"A":   PN = "1"  !CDS_PN = "1";
"B":   PN = "2"  !CDS_PN = "2";
BODY = "Q_CAP","I20": #LOCATION = "PC2208" !CDS_LOCATION = "PC2208" &SEC = "1" #&CDS_SEC = "1";
"A":   PN = "1"  !CDS_PN = "1";
"B":   PN = "2"  !CDS_PN = "2";
BODY = "Q_RES","I21": #LOCATION = "PR3963" !CDS_LOCATION = "PR3963" &SEC = "1" #&CDS_SEC = "1";
"A":   PN = "1"  !CDS_PN = "1";
"B":   PN = "2"  !CDS_PN = "2";
BODY = "Q_RES","I25": #LOCATION = "R4074" !CDS_LOCATION = "R4074" &SEC = "1" #&CDS_SEC = "1";
"A":   PN = "1"  !CDS_PN = "1";
"B":   PN = "2"  !CDS_PN = "2";
BODY = "MOSFET_NCH_DUAL","I27": #LOCATION = "Q127" !CDS_LOCATION = "Q127" &SEC = "2" #&CDS_SEC = "2";
"D2":   PN = "3"  !CDS_PN = "3";
"G2":   PN = "5"  !CDS_PN = "5";
"S2":   PN = "4"  !CDS_PN = "4";
BODY = "Q_RES","I29": #LOCATION = "R3958" !CDS_LOCATION = "R3958" &SEC = "1" #&CDS_SEC = "1";
"A":   PN = "1"  !CDS_PN = "1";
"B":   PN = "2"  !CDS_PN = "2";
BODY = "Q_RES","I31": #LOCATION = "PR3962" !CDS_LOCATION = "PR3962" &SEC = "1" #&CDS_SEC = "1";
"A":   PN = "1"  !CDS_PN = "1";
"B":   PN = "2"  !CDS_PN = "2";
BODY = "DIODE_TVS","I33": #LOCATION = "PD114" !CDS_LOCATION = "PD114" &SEC = "1" #&CDS_SEC = "1";
"A":   PN = "A"  !CDS_PN = "A";
"C":   PN = "C"  !CDS_PN = "C";
BODY = "Q_CAP","I36": #LOCATION = "PC2207" !CDS_LOCATION = "PC2207" &SEC = "1" #&CDS_SEC = "1";
"A":   PN = "1"  !CDS_PN = "1";
"B":   PN = "2"  !CDS_PN = "2";
BODY = "Q_RES","I37": #LOCATION = "PR3960" !CDS_LOCATION = "PR3960" &SEC = "1" #&CDS_SEC = "1";
"A":   PN = "1"  !CDS_PN = "1";
"B":   PN = "2"  !CDS_PN = "2";
BODY = "Q_RES","I39": #LOCATION = "PR3969" !CDS_LOCATION = "PR3969" &SEC = "1" #&CDS_SEC = "1";
"A":   PN = "1"  !CDS_PN = "1";
"B":   PN = "2"  !CDS_PN = "2";
BODY = "Q_CAP","I41": #LOCATION = "PC2210" !CDS_LOCATION = "PC2210" &SEC = "1" #&CDS_SEC = "1";
"A":   PN = "1"  !CDS_PN = "1";
"B":   PN = "2"  !CDS_PN = "2";
BODY = "Q_RES","I43": #LOCATION = "PR3967" !CDS_LOCATION = "PR3967" &SEC = "1" #&CDS_SEC = "1";
"A":   PN = "1"  !CDS_PN = "1";
"B":   PN = "2"  !CDS_PN = "2";
BODY = "Q_RES","I45": #LOCATION = "PR3971" !CDS_LOCATION = "PR3971" &SEC = "1" #&CDS_SEC = "1";
"A":   PN = "1"  !CDS_PN = "1";
"B":   PN = "2"  !CDS_PN = "2";
BODY = "Q_CAP","I46": #LOCATION = "PC2213" !CDS_LOCATION = "PC2213" &SEC = "1" #&CDS_SEC = "1";
"A":   PN = "1"  !CDS_PN = "1";
"B":   PN = "2"  !CDS_PN = "2";
BODY = "Q_RES","I47": #LOCATION = "PR4527" !CDS_LOCATION = "PR4527" &SEC = "1" #&CDS_SEC = "1";
"A":   PN = "1"  !CDS_PN = "1";
"B":   PN = "2"  !CDS_PN = "2";
BODY = "Q_RES","I48": #LOCATION = "R3973" !CDS_LOCATION = "R3973" &SEC = "1" #&CDS_SEC = "1";
"A":   PN = "1"  !CDS_PN = "1";
"B":   PN = "2"  !CDS_PN = "2";
BODY = "SCHOTTKY_AC","I50": #LOCATION = "PD113" !CDS_LOCATION = "PD113" &SEC = "1" #&CDS_SEC = "1";
"A":   PN = "A"  !CDS_PN = "A";
"C":   PN = "C"  !CDS_PN = "C";
BODY = "Q_RES","I54": #LOCATION = "R3979" !CDS_LOCATION = "R3979" &SEC = "1" #&CDS_SEC = "1";
"A":   PN = "1"  !CDS_PN = "1";
"B":   PN = "2"  !CDS_PN = "2";
BODY = "Q_CAP","I58": #LOCATION = "PC2220" !CDS_LOCATION = "PC2220" &SEC = "1" #&CDS_SEC = "1";
"A":   PN = "1"  !CDS_PN = "1";
"B":   PN = "2"  !CDS_PN = "2";
BODY = "Q_CAP","I61": #LOCATION = "PC2211" !CDS_LOCATION = "PC2211" &SEC = "1" #&CDS_SEC = "1";
"A":   PN = "1"  !CDS_PN = "1";
"B":   PN = "2"  !CDS_PN = "2";
BODY = "Q_RES","I63": #LOCATION = "PR3968" !CDS_LOCATION = "PR3968" &SEC = "1" #&CDS_SEC = "1";
"A":   PN = "1"  !CDS_PN = "1";
"B":   PN = "2"  !CDS_PN = "2";
BODY = "Q_RES","I65": #LOCATION = "PR3966" !CDS_LOCATION = "PR3966" &SEC = "1" #&CDS_SEC = "1";
"A":   PN = "1"  !CDS_PN = "1";
"B":   PN = "2"  !CDS_PN = "2";
BODY = "MAX15090BEWIT","I66": #LOCATION = "PU294" !CDS_LOCATION = "PU294" &SEC = "1" #&CDS_SEC = "1";
"CB":   PN = "B1"  !CDS_PN = "B1";
"CDLY":   PN = "A7"  !CDS_PN = "A7";
"EN#":   PN = "B7"  !CDS_PN = "B7";
"FAULT#":   PN = "C7"  !CDS_PN = "C7";
"GATE":   PN = "A6"  !CDS_PN = "A6";
"GND_B2":   PN = "B2"  !CDS_PN = "B2";
"GND_C1":   PN = "C1"  !CDS_PN = "C1";
"GND_C2":   PN = "C2"  !CDS_PN = "C2";
"IN_A3":   PN = "A3"  !CDS_PN = "A3";
"IN_A5":   PN = "A5"  !CDS_PN = "A5";
"IN_B3":   PN = "B3"  !CDS_PN = "B3";
"IN_B5":   PN = "B5"  !CDS_PN = "B5";
"IN_C3":   PN = "C3"  !CDS_PN = "C3";
"IN_C5":   PN = "C5"  !CDS_PN = "C5";
"IN_D5":   PN = "D5"  !CDS_PN = "D5";
"ISENSE":   PN = "A1"  !CDS_PN = "A1";
"OUT_A4":   PN = "A4"  !CDS_PN = "A4";
"OUT_B4":   PN = "B4"  !CDS_PN = "B4";
"OUT_B6":   PN = "B6"  !CDS_PN = "B6";
"OUT_C4":   PN = "C4"  !CDS_PN = "C4";
"OUT_C6":   PN = "C6"  !CDS_PN = "C6";
"OUT_D4":   PN = "D4"  !CDS_PN = "D4";
"OUT_D6":   PN = "D6"  !CDS_PN = "D6";
"OV":   PN = "D3"  !CDS_PN = "D3";
"PG":   PN = "D7"  !CDS_PN = "D7";
"REG":   PN = "D1"  !CDS_PN = "D1";
"UV":   PN = "D2"  !CDS_PN = "D2";
"VCC":   PN = "A2"  !CDS_PN = "A2";
BODY = "Q_RES","I68": #LOCATION = "PR3970" !CDS_LOCATION = "PR3970" &SEC = "1" #&CDS_SEC = "1";
"A":   PN = "1"  !CDS_PN = "1";
"B":   PN = "2"  !CDS_PN = "2";
BODY = "Q_CAP","I69": #LOCATION = "PC2215" !CDS_LOCATION = "PC2215" &SEC = "1" #&CDS_SEC = "1";
"A":   PN = "1"  !CDS_PN = "1";
"B":   PN = "2"  !CDS_PN = "2";
BODY = "Q_RES","I70": #LOCATION = "R3974" !CDS_LOCATION = "R3974" &SEC = "1" #&CDS_SEC = "1";
"A":   PN = "1"  !CDS_PN = "1";
"B":   PN = "2"  !CDS_PN = "2";
BODY = "Q_RES","I71": #LOCATION = "R3972" !CDS_LOCATION = "R3972" &SEC = "1" #&CDS_SEC = "1";
"A":   PN = "1"  !CDS_PN = "1";
"B":   PN = "2"  !CDS_PN = "2";
BODY = "Q_CAP","I72": #LOCATION = "PC2214" !CDS_LOCATION = "PC2214" &SEC = "1" #&CDS_SEC = "1";
"A":   PN = "1"  !CDS_PN = "1";
"B":   PN = "2"  !CDS_PN = "2";
BODY = "SCHOTTKY_AC","I74": #LOCATION = "PD112" !CDS_LOCATION = "PD112" &SEC = "1" #&CDS_SEC = "1";
"A":   PN = "A"  !CDS_PN = "A";
"C":   PN = "C"  !CDS_PN = "C";
BODY = "Q_RES","I76": #LOCATION = "R3976" !CDS_LOCATION = "R3976" &SEC = "1" #&CDS_SEC = "1";
"A":   PN = "1"  !CDS_PN = "1";
"B":   PN = "2"  !CDS_PN = "2";
BODY = "Q_CAP","I78": #LOCATION = "PC2217" !CDS_LOCATION = "PC2217" &SEC = "1" #&CDS_SEC = "1";
"A":   PN = "1"  !CDS_PN = "1";
"B":   PN = "2"  !CDS_PN = "2";
BODY = "Q_CAP","I80": #LOCATION = "PC2280" !CDS_LOCATION = "PC2280" &SEC = "1" #&CDS_SEC = "1";
"A":   PN = "1"  !CDS_PN = "1";
"B":   PN = "2"  !CDS_PN = "2";
BODY = "MOSFET_NCH_DUAL","I7": #LOCATION = "Q126" !CDS_LOCATION = "Q126" &SEC = "2" #&CDS_SEC = "2";
"D2":   PN = "3"  !CDS_PN = "3";
"G2":   PN = "5"  !CDS_PN = "5";
"S2":   PN = "4"  !CDS_PN = "4";
BODY = "Q_RES","I8": #LOCATION = "R4072" !CDS_LOCATION = "R4072" &SEC = "1" #&CDS_SEC = "1";
"A":   PN = "1"  !CDS_PN = "1";
"B":   PN = "2"  !CDS_PN = "2";
BODY = "MOSFET_NCH_DUAL","I12": #LOCATION = "Q127" !CDS_LOCATION = "Q127" &SEC = "1" #&CDS_SEC = "1";
"D1":   PN = "6"  !CDS_PN = "6";
"G1":   PN = "2"  !CDS_PN = "2";
"S1":   PN = "1"  !CDS_PN = "1";
BODY = "Q_RES","I18": #LOCATION = "R3959" !CDS_LOCATION = "R3959" &SEC = "1" #&CDS_SEC = "1";
"A":   PN = "1"  !CDS_PN = "1";
"B":   PN = "2"  !CDS_PN = "2";
BODY = "Q_RES","I24": #LOCATION = "R4064" !CDS_LOCATION = "R4064" &SEC = "1" #&CDS_SEC = "1";
"A":   PN = "1"  !CDS_PN = "1";
"B":   PN = "2"  !CDS_PN = "2";
BODY = "Q_RES","I32": #LOCATION = "PR3961" !CDS_LOCATION = "PR3961" &SEC = "1" #&CDS_SEC = "1";
"A":   PN = "1"  !CDS_PN = "1";
"B":   PN = "2"  !CDS_PN = "2";
BODY = "Q_CAP","I42": #LOCATION = "PC2212" !CDS_LOCATION = "PC2212" &SEC = "1" #&CDS_SEC = "1";
"A":   PN = "1"  !CDS_PN = "1";
"B":   PN = "2"  !CDS_PN = "2";
BODY = "Q_CAP","I49": #LOCATION = "PC2216" !CDS_LOCATION = "PC2216" &SEC = "1" #&CDS_SEC = "1";
"A":   PN = "1"  !CDS_PN = "1";
"B":   PN = "2"  !CDS_PN = "2";
BODY = "Q_RES","I52": #LOCATION = "R3977" !CDS_LOCATION = "R3977" &SEC = "1" #&CDS_SEC = "1";
"A":   PN = "1"  !CDS_PN = "1";
"B":   PN = "2"  !CDS_PN = "2";
BODY = "Q_CAP","I57": #LOCATION = "PC2218" !CDS_LOCATION = "PC2218" &SEC = "1" #&CDS_SEC = "1";
"A":   PN = "1"  !CDS_PN = "1";
"B":   PN = "2"  !CDS_PN = "2";
BODY = "Q_CAP","I64": #LOCATION = "PC2209" !CDS_LOCATION = "PC2209" &SEC = "1" #&CDS_SEC = "1";
"A":   PN = "1"  !CDS_PN = "1";
"B":   PN = "2"  !CDS_PN = "2";
BODY = "Q_RES","I73": #LOCATION = "PR4528" !CDS_LOCATION = "PR4528" &SEC = "1" #&CDS_SEC = "1";
"A":   PN = "1"  !CDS_PN = "1";
"B":   PN = "2"  !CDS_PN = "2";
BODY = "Q_CAP","I79": #LOCATION = "PC2219" !CDS_LOCATION = "PC2219" &SEC = "1" #&CDS_SEC = "1";
"A":   PN = "1"  !CDS_PN = "1";
"B":   PN = "2"  !CDS_PN = "2";
BODY = "Q_RES","I86": #LOCATION = "R3978" !CDS_LOCATION = "R3978" &SEC = "1" #&CDS_SEC = "1";
"A":   PN = "1"  !CDS_PN = "1";
"B":   PN = "2"  !CDS_PN = "2";
BODY = "Q_RES","I87": #LOCATION = "R3975" !CDS_LOCATION = "R3975" &SEC = "1" #&CDS_SEC = "1";
"A":   PN = "1"  !CDS_PN = "1";
"B":   PN = "2"  !CDS_PN = "2";
BODY = "MAX15090BEWIT","I88": #LOCATION = "PU295" !CDS_LOCATION = "PU295" &SEC = "1" #&CDS_SEC = "1";
"CB":   PN = "B1"  !CDS_PN = "B1";
"CDLY":   PN = "A7"  !CDS_PN = "A7";
"EN#":   PN = "B7"  !CDS_PN = "B7";
"FAULT#":   PN = "C7"  !CDS_PN = "C7";
"GATE":   PN = "A6"  !CDS_PN = "A6";
"GND_B2":   PN = "B2"  !CDS_PN = "B2";
"GND_C1":   PN = "C1"  !CDS_PN = "C1";
"GND_C2":   PN = "C2"  !CDS_PN = "C2";
"IN_A3":   PN = "A3"  !CDS_PN = "A3";
"IN_A5":   PN = "A5"  !CDS_PN = "A5";
"IN_B3":   PN = "B3"  !CDS_PN = "B3";
"IN_B5":   PN = "B5"  !CDS_PN = "B5";
"IN_C3":   PN = "C3"  !CDS_PN = "C3";
"IN_C5":   PN = "C5"  !CDS_PN = "C5";
"IN_D5":   PN = "D5"  !CDS_PN = "D5";
"ISENSE":   PN = "A1"  !CDS_PN = "A1";
"OUT_A4":   PN = "A4"  !CDS_PN = "A4";
"OUT_B4":   PN = "B4"  !CDS_PN = "B4";
"OUT_B6":   PN = "B6"  !CDS_PN = "B6";
"OUT_C4":   PN = "C4"  !CDS_PN = "C4";
"OUT_C6":   PN = "C6"  !CDS_PN = "C6";
"OUT_D4":   PN = "D4"  !CDS_PN = "D4";
"OUT_D6":   PN = "D6"  !CDS_PN = "D6";
"OV":   PN = "D3"  !CDS_PN = "D3";
"PG":   PN = "D7"  !CDS_PN = "D7";
"REG":   PN = "D1"  !CDS_PN = "D1";
"UV":   PN = "D2"  !CDS_PN = "D2";
"VCC":   PN = "A2"  !CDS_PN = "A2";
DRAWING = "@t6g_mb_lib.t6g(sch_1):page345";
BODY = "SCONN75K_APCI0155P004A","I88": #LOCATION = "J59" !CDS_LOCATION = "J59" &SEC = "1" #&CDS_SEC = "1";
"3.3V_1":   PN = "2"  !CDS_PN = "2";
"3.3V_2":   PN = "4"  !CDS_PN = "4";
"3.3V_3":   PN = "12"  !CDS_PN = "12";
"3.3V_4":   PN = "14"  !CDS_PN = "14";
"3.3V_5":   PN = "16"  !CDS_PN = "16";
"3.3V_6":   PN = "18"  !CDS_PN = "18";
"3.3V_7":   PN = "70"  !CDS_PN = "70";
"3.3V_8":   PN = "72"  !CDS_PN = "72";
"3.3V_9":   PN = "74"  !CDS_PN = "74";
"CLKREQ#":   PN = "52"  !CDS_PN = "52";
"DAS_DSS#||LED1#":   PN = "10"  !CDS_PN = "10";
"DEVSLP":   PN = "38"  !CDS_PN = "38";
"G1":   PN = "G1"  !CDS_PN = "G1";
"G2":   PN = "G2"  !CDS_PN = "G2";
"GND1":   PN = "1"  !CDS_PN = "1";
"GND2":   PN = "3"  !CDS_PN = "3";
"GND3":   PN = "9"  !CDS_PN = "9";
"GND4":   PN = "15"  !CDS_PN = "15";
"GND5":   PN = "21"  !CDS_PN = "21";
"GND6":   PN = "27"  !CDS_PN = "27";
"GND7":   PN = "33"  !CDS_PN = "33";
"GND8":   PN = "39"  !CDS_PN = "39";
"GND9":   PN = "45"  !CDS_PN = "45";
"GND10":   PN = "51"  !CDS_PN = "51";
"GND11":   PN = "57"  !CDS_PN = "57";
"GND12":   PN = "71"  !CDS_PN = "71";
"GND13":   PN = "73"  !CDS_PN = "73";
"GND14":   PN = "75"  !CDS_PN = "75";
"NC1":   PN = "6"  !CDS_PN = "6";
"NC2":   PN = "8"  !CDS_PN = "8";
"NC3":   PN = "20"  !CDS_PN = "20";
"NC4":   PN = "22"  !CDS_PN = "22";
"NC5":   PN = "24"  !CDS_PN = "24";
"NC6":   PN = "26"  !CDS_PN = "26";
"NC7":   PN = "28"  !CDS_PN = "28";
"NC8":   PN = "30"  !CDS_PN = "30";
"NC9":   PN = "32"  !CDS_PN = "32";
"NC10":   PN = "34"  !CDS_PN = "34";
"NC11":   PN = "36"  !CDS_PN = "36";
"NC12":   PN = "40"  !CDS_PN = "40";
"NC13":   PN = "42"  !CDS_PN = "42";
"NC14":   PN = "44"  !CDS_PN = "44";
"NC15":   PN = "46"  !CDS_PN = "46";
"NC16":   PN = "48"  !CDS_PN = "48";
"NC17":   PN = "56"  !CDS_PN = "56";
"NC18":   PN = "58"  !CDS_PN = "58";
"NC19":   PN = "67"  !CDS_PN = "67";
"PEDET":   PN = "69"  !CDS_PN = "69";
"PERN0||SATA-B+":   PN = "41"  !CDS_PN = "41";
"PERN1":   PN = "29"  !CDS_PN = "29";
"PERN2":   PN = "17"  !CDS_PN = "17";
"PERN3":   PN = "5"  !CDS_PN = "5";
"PERP0||SATA-B-":   PN = "43"  !CDS_PN = "43";
"PERP1":   PN = "31"  !CDS_PN = "31";
"PERP2":   PN = "19"  !CDS_PN = "19";
"PERP3":   PN = "7"  !CDS_PN = "7";
"PERST#":   PN = "50"  !CDS_PN = "50";
"PETN0||SATA-A-":   PN = "47"  !CDS_PN = "47";
"PETN1":   PN = "35"  !CDS_PN = "35";
"PETN2":   PN = "23"  !CDS_PN = "23";
"PETN3":   PN = "11"  !CDS_PN = "11";
"PETP0||SATA-A+":   PN = "49"  !CDS_PN = "49";
"PETP1":   PN = "37"  !CDS_PN = "37";
"PETP2":   PN = "25"  !CDS_PN = "25";
"PETP3":   PN = "13"  !CDS_PN = "13";
"PEWAKE#":   PN = "54"  !CDS_PN = "54";
"REFCLKN":   PN = "53"  !CDS_PN = "53";
"REFCLKP":   PN = "55"  !CDS_PN = "55";
"SUSCLK":   PN = "68"  !CDS_PN = "68";
BODY = "SN74LVC2G07DCKR","I5": #LOCATION = "U259" !CDS_LOCATION = "U259" &SEC = "1" #&CDS_SEC = "1";
"1A":   PN = "1"  !CDS_PN = "1";
"1Y":   PN = "6"  !CDS_PN = "6";
"2A":   PN = "3"  !CDS_PN = "3";
"2Y":   PN = "4"  !CDS_PN = "4";
"GND":   PN = "2"  !CDS_PN = "2";
"VCC":   PN = "5"  !CDS_PN = "5";
BODY = "Q_CAP","I6": #LOCATION = "C2007" !CDS_LOCATION = "C2007" &SEC = "1" #&CDS_SEC = "1";
"A":   PN = "1"  !CDS_PN = "1";
"B":   PN = "2"  !CDS_PN = "2";
BODY = "MOSFET_NCH_DUAL","I8": #LOCATION = "Q95" !CDS_LOCATION = "Q95" #SEC = "1" !CDS_SEC = "1";
"D1":   PN = "6"  !CDS_PN = "6";
"G1":   PN = "2"  !CDS_PN = "2";
"S1":   PN = "1"  !CDS_PN = "1";
BODY = "Q_RES","I10": #LOCATION = "R2121" !CDS_LOCATION = "R2121" &SEC = "1" #&CDS_SEC = "1";
"A":   PN = "1"  !CDS_PN = "1";
"B":   PN = "2"  !CDS_PN = "2";
BODY = "Q_RES","I12": #LOCATION = "R2113" !CDS_LOCATION = "R2113" &SEC = "1" #&CDS_SEC = "1";
"A":   PN = "1"  !CDS_PN = "1";
"B":   PN = "2"  !CDS_PN = "2";
BODY = "Q_RES","I15": #LOCATION = "R138" !CDS_LOCATION = "R138" &SEC = "1" #&CDS_SEC = "1";
"A":   PN = "1"  !CDS_PN = "1";
"B":   PN = "2"  !CDS_PN = "2";
BODY = "Q_RES","I19": #LOCATION = "R3294" !CDS_LOCATION = "R3294" &SEC = "1" #&CDS_SEC = "1";
"A":   PN = "1"  !CDS_PN = "1";
"B":   PN = "2"  !CDS_PN = "2";
BODY = "Q_RES","I21": #LOCATION = "R3295" !CDS_LOCATION = "R3295" &SEC = "1" #&CDS_SEC = "1";
"A":   PN = "1"  !CDS_PN = "1";
"B":   PN = "2"  !CDS_PN = "2";
BODY = "Q_RES","I24": #LOCATION = "R178" !CDS_LOCATION = "R178" &SEC = "1" #&CDS_SEC = "1";
"A":   PN = "1"  !CDS_PN = "1";
"B":   PN = "2"  !CDS_PN = "2";
BODY = "Q_RES","I27": #LOCATION = "R153" !CDS_LOCATION = "R153" &SEC = "1" #&CDS_SEC = "1";
"A":   PN = "1"  !CDS_PN = "1";
"B":   PN = "2"  !CDS_PN = "2";
BODY = "Q_RES","I30": #LOCATION = "R3301" !CDS_LOCATION = "R3301" &SEC = "1" #&CDS_SEC = "1";
"A":   PN = "1"  !CDS_PN = "1";
"B":   PN = "2"  !CDS_PN = "2";
BODY = "Q_RES","I32": #LOCATION = "R155" !CDS_LOCATION = "R155" &SEC = "1" #&CDS_SEC = "1";
"A":   PN = "1"  !CDS_PN = "1";
"B":   PN = "2"  !CDS_PN = "2";
BODY = "Q_RES","I51": #LOCATION = "R3296" !CDS_LOCATION = "R3296" &SEC = "1" #&CDS_SEC = "1";
"A":   PN = "1"  !CDS_PN = "1";
"B":   PN = "2"  !CDS_PN = "2";
BODY = "74LVC1G126SE7","I53": #LOCATION = "U239" !CDS_LOCATION = "U239" &SEC = "1" #&CDS_SEC = "1";
"A":   PN = "2"  !CDS_PN = "2";
"GND":   PN = "3"  !CDS_PN = "3";
"OE":   PN = "1"  !CDS_PN = "1";
"VCC":   PN = "5"  !CDS_PN = "5";
"Y":   PN = "4"  !CDS_PN = "4";
BODY = "Q_CAP","I56": #LOCATION = "C1873" !CDS_LOCATION = "C1873" &SEC = "1" #&CDS_SEC = "1";
"A":   PN = "1"  !CDS_PN = "1";
"B":   PN = "2"  !CDS_PN = "2";
BODY = "Q_RES","I58": #LOCATION = "R3298" !CDS_LOCATION = "R3298" &SEC = "1" #&CDS_SEC = "1";
"A":   PN = "1"  !CDS_PN = "1";
"B":   PN = "2"  !CDS_PN = "2";
BODY = "Q_RES","I60": #LOCATION = "R3297" !CDS_LOCATION = "R3297" &SEC = "1" #&CDS_SEC = "1";
"A":   PN = "1"  !CDS_PN = "1";
"B":   PN = "2"  !CDS_PN = "2";
BODY = "Q_RES","I62": #LOCATION = "R5377" !CDS_LOCATION = "R5377" &SEC = "1" #&CDS_SEC = "1";
"A":   PN = "1"  !CDS_PN = "1";
"B":   PN = "2"  !CDS_PN = "2";
BODY = "Q_RES","I66": #LOCATION = "R1396" !CDS_LOCATION = "R1396" &SEC = "1" #&CDS_SEC = "1";
"A":   PN = "1"  !CDS_PN = "1";
"B":   PN = "2"  !CDS_PN = "2";
BODY = "Q_CAP","I77": #LOCATION = "C1920" !CDS_LOCATION = "C1920" &SEC = "1" #&CDS_SEC = "1";
"A":   PN = "1"  !CDS_PN = "1";
"B":   PN = "2"  !CDS_PN = "2";
BODY = "Q_CAP","I78": #LOCATION = "C1921" !CDS_LOCATION = "C1921" &SEC = "1" #&CDS_SEC = "1";
"A":   PN = "1"  !CDS_PN = "1";
"B":   PN = "2"  !CDS_PN = "2";
BODY = "Q_CAP","I79": #LOCATION = "C9922" !CDS_LOCATION = "C9922" &SEC = "1" #&CDS_SEC = "1";
"A":   PN = "1"  !CDS_PN = "1";
"B":   PN = "2"  !CDS_PN = "2";
BODY = "Q_RES","I83": #LOCATION = "R1605" !CDS_LOCATION = "R1605" &SEC = "1" #&CDS_SEC = "1";
"A":   PN = "1"  !CDS_PN = "1";
"B":   PN = "2"  !CDS_PN = "2";
BODY = "Q_CAP","I84": #LOCATION = "C1923" !CDS_LOCATION = "C1923" &SEC = "1" #&CDS_SEC = "1";
"A":   PN = "1"  !CDS_PN = "1";
"B":   PN = "2"  !CDS_PN = "2";
BODY = "Q_CAP","I85": #LOCATION = "C1924" !CDS_LOCATION = "C1924" &SEC = "1" #&CDS_SEC = "1";
"A":   PN = "1"  !CDS_PN = "1";
"B":   PN = "2"  !CDS_PN = "2";
BODY = "Q_CAP","I86": #LOCATION = "C1925" !CDS_LOCATION = "C1925" &SEC = "1" #&CDS_SEC = "1";
"A":   PN = "1"  !CDS_PN = "1";
"B":   PN = "2"  !CDS_PN = "2";
BODY = "MOSFET_NCH_DUAL","I89": #LOCATION = "Q95" !CDS_LOCATION = "Q95" &SEC = "2" #&CDS_SEC = "2";
"D2":   PN = "3"  !CDS_PN = "3";
"G2":   PN = "5"  !CDS_PN = "5";
"S2":   PN = "4"  !CDS_PN = "4";
DRAWING = "@t6g_mb_lib.t6g(sch_1):page346";
BODY = "PCA9306DP1","I27": #LOCATION = "U98" !CDS_LOCATION = "U98" &SEC = "1" #&CDS_SEC = "1";
"EN":   PN = "8"  !CDS_PN = "8";
"GND":   PN = "1"  !CDS_PN = "1";
"SCL1":   PN = "3"  !CDS_PN = "3";
"SCL2":   PN = "6"  !CDS_PN = "6";
"SDA1":   PN = "4"  !CDS_PN = "4";
"SDA2":   PN = "5"  !CDS_PN = "5";
"VREF1":   PN = "2"  !CDS_PN = "2";
"VREF2":   PN = "7"  !CDS_PN = "7";
BODY = "Q_CAP","I28": #LOCATION = "C1323" !CDS_LOCATION = "C1323" &SEC = "1" #&CDS_SEC = "1";
"A":   PN = "1"  !CDS_PN = "1";
"B":   PN = "2"  !CDS_PN = "2";
BODY = "Q_RES","I43": #LOCATION = "R1702" !CDS_LOCATION = "R1702" &SEC = "1" #&CDS_SEC = "1";
"A":   PN = "1"  !CDS_PN = "1";
"B":   PN = "2"  !CDS_PN = "2";
BODY = "Q_RES","I45": #LOCATION = "R1703" !CDS_LOCATION = "R1703" &SEC = "1" #&CDS_SEC = "1";
"A":   PN = "1"  !CDS_PN = "1";
"B":   PN = "2"  !CDS_PN = "2";
BODY = "Q_CAP","I52": #LOCATION = "C1305" !CDS_LOCATION = "C1305" &SEC = "1" #&CDS_SEC = "1";
"A":   PN = "1"  !CDS_PN = "1";
"B":   PN = "2"  !CDS_PN = "2";
BODY = "Q_RES","I65": #LOCATION = "R2410" !CDS_LOCATION = "R2410" &SEC = "1" #&CDS_SEC = "1";
"A":   PN = "1"  !CDS_PN = "1";
"B":   PN = "2"  !CDS_PN = "2";
BODY = "Q_RES","I66": #LOCATION = "R2411" !CDS_LOCATION = "R2411" &SEC = "1" #&CDS_SEC = "1";
"A":   PN = "1"  !CDS_PN = "1";
"B":   PN = "2"  !CDS_PN = "2";
BODY = "Q_RES","I70": #LOCATION = "R2476" !CDS_LOCATION = "R2476" &SEC = "1" #&CDS_SEC = "1";
"A":   PN = "1"  !CDS_PN = "1";
"B":   PN = "2"  !CDS_PN = "2";
BODY = "Q_RES","I72": #LOCATION = "R1700" !CDS_LOCATION = "R1700" &SEC = "1" #&CDS_SEC = "1";
"A":   PN = "1"  !CDS_PN = "1";
"B":   PN = "2"  !CDS_PN = "2";
BODY = "Q_RES","I76": #LOCATION = "R3533" !CDS_LOCATION = "R3533" &SEC = "1" #&CDS_SEC = "1";
"A":   PN = "1"  !CDS_PN = "1";
"B":   PN = "2"  !CDS_PN = "2";
BODY = "Q_RES","I77": #LOCATION = "R3534" !CDS_LOCATION = "R3534" &SEC = "1" #&CDS_SEC = "1";
"A":   PN = "1"  !CDS_PN = "1";
"B":   PN = "2"  !CDS_PN = "2";
BODY = "Q_RES","I78": #LOCATION = "R3532" !CDS_LOCATION = "R3532" &SEC = "1" #&CDS_SEC = "1";
"A":   PN = "1"  !CDS_PN = "1";
"B":   PN = "2"  !CDS_PN = "2";
BODY = "Q_RES","I80": #LOCATION = "R3530" !CDS_LOCATION = "R3530" &SEC = "1" #&CDS_SEC = "1";
"A":   PN = "1"  !CDS_PN = "1";
"B":   PN = "2"  !CDS_PN = "2";
BODY = "Q_CAP","I82": #LOCATION = "C1998" !CDS_LOCATION = "C1998" &SEC = "1" #&CDS_SEC = "1";
"A":   PN = "1"  !CDS_PN = "1";
"B":   PN = "2"  !CDS_PN = "2";
BODY = "Q_CAP","I89": #LOCATION = "C1997" !CDS_LOCATION = "C1997" &SEC = "1" #&CDS_SEC = "1";
"A":   PN = "1"  !CDS_PN = "1";
"B":   PN = "2"  !CDS_PN = "2";
BODY = "PCA9617ADP","I93": #LOCATION = "U279" !CDS_LOCATION = "U279" &SEC = "1" #&CDS_SEC = "1";
"EN":   PN = "5"  !CDS_PN = "5";
"GND":   PN = "4"  !CDS_PN = "4";
"SCLA":   PN = "2"  !CDS_PN = "2";
"SCLB":   PN = "7"  !CDS_PN = "7";
"SDAA":   PN = "3"  !CDS_PN = "3";
"SDAB":   PN = "6"  !CDS_PN = "6";
"VCCA":   PN = "1"  !CDS_PN = "1";
"VCCB":   PN = "8"  !CDS_PN = "8";
BODY = "Q_RES","I96": #LOCATION = "R3531" !CDS_LOCATION = "R3531" &SEC = "1" #&CDS_SEC = "1";
"A":   PN = "1"  !CDS_PN = "1";
"B":   PN = "2"  !CDS_PN = "2";
BODY = "Q_RES","I99": #LOCATION = "R3529" !CDS_LOCATION = "R3529" &SEC = "1" #&CDS_SEC = "1";
"A":   PN = "1"  !CDS_PN = "1";
"B":   PN = "2"  !CDS_PN = "2";
DRAWING = "@t6g_mb_lib.t6g(sch_1):page350";
BODY = "Q_RES","I2": #LOCATION = "R1854" !CDS_LOCATION = "R1854" &SEC = "1" #&CDS_SEC = "1";
"A":   PN = "1"  !CDS_PN = "1";
"B":   PN = "2"  !CDS_PN = "2";
BODY = "Q_RES","I3": #LOCATION = "R1856" !CDS_LOCATION = "R1856" &SEC = "1" #&CDS_SEC = "1";
"A":   PN = "1"  !CDS_PN = "1";
"B":   PN = "2"  !CDS_PN = "2";
BODY = "Q_CAP","I8": #LOCATION = "PC2229" !CDS_LOCATION = "PC2229" &SEC = "1" #&CDS_SEC = "1";
"A":   PN = "1"  !CDS_PN = "1";
"B":   PN = "2"  !CDS_PN = "2";
BODY = "Q_RES","I11": #LOCATION = "PR3999" !CDS_LOCATION = "PR3999" &SEC = "1" #&CDS_SEC = "1";
"A":   PN = "1"  !CDS_PN = "1";
"B":   PN = "2"  !CDS_PN = "2";
BODY = "Q_RES","I12": #LOCATION = "PR4540" !CDS_LOCATION = "PR4540" &SEC = "1" #&CDS_SEC = "1";
"A":   PN = "1"  !CDS_PN = "1";
"B":   PN = "2"  !CDS_PN = "2";
BODY = "Q_RES","I14": #LOCATION = "R3998" !CDS_LOCATION = "R3998" &SEC = "1" #&CDS_SEC = "1";
"A":   PN = "1"  !CDS_PN = "1";
"B":   PN = "2"  !CDS_PN = "2";
BODY = "Q_RES","I17": #LOCATION = "R3996" !CDS_LOCATION = "R3996" &SEC = "1" #&CDS_SEC = "1";
"A":   PN = "1"  !CDS_PN = "1";
"B":   PN = "2"  !CDS_PN = "2";
BODY = "Q_RES","I18": #LOCATION = "R1857" !CDS_LOCATION = "R1857" &SEC = "1" #&CDS_SEC = "1";
"A":   PN = "1"  !CDS_PN = "1";
"B":   PN = "2"  !CDS_PN = "2";
BODY = "Q_RES","I20": #LOCATION = "R4062" !CDS_LOCATION = "R4062" &SEC = "1" #&CDS_SEC = "1";
"A":   PN = "1"  !CDS_PN = "1";
"B":   PN = "2"  !CDS_PN = "2";
BODY = "Q_RES","I25": #LOCATION = "R4071" !CDS_LOCATION = "R4071" &SEC = "1" #&CDS_SEC = "1";
"A":   PN = "1"  !CDS_PN = "1";
"B":   PN = "2"  !CDS_PN = "2";
BODY = "Q_RES","I27": #LOCATION = "R3997" !CDS_LOCATION = "R3997" &SEC = "1" #&CDS_SEC = "1";
"A":   PN = "1"  !CDS_PN = "1";
"B":   PN = "2"  !CDS_PN = "2";
BODY = "Q_CAP","I31": #LOCATION = "PC2230" !CDS_LOCATION = "PC2230" &SEC = "1" #&CDS_SEC = "1";
"A":   PN = "1"  !CDS_PN = "1";
"B":   PN = "2"  !CDS_PN = "2";
BODY = "Q_CAP","I33": #LOCATION = "PC2232" !CDS_LOCATION = "PC2232" &SEC = "1" #&CDS_SEC = "1";
"A":   PN = "1"  !CDS_PN = "1";
"B":   PN = "2"  !CDS_PN = "2";
BODY = "Q_CAP","I37": #LOCATION = "PC2231" !CDS_LOCATION = "PC2231" &SEC = "1" #&CDS_SEC = "1";
"A":   PN = "1"  !CDS_PN = "1";
"B":   PN = "2"  !CDS_PN = "2";
BODY = "Q_RES","I40": #LOCATION = "PR4007" !CDS_LOCATION = "PR4007" &SEC = "1" #&CDS_SEC = "1";
"A":   PN = "1"  !CDS_PN = "1";
"B":   PN = "2"  !CDS_PN = "2";
BODY = "Q_CAP","I45": #LOCATION = "PC2235" !CDS_LOCATION = "PC2235" &SEC = "1" #&CDS_SEC = "1";
"A":   PN = "1"  !CDS_PN = "1";
"B":   PN = "2"  !CDS_PN = "2";
BODY = "Q_RES","I50": #LOCATION = "PR4009" !CDS_LOCATION = "PR4009" &SEC = "1" #&CDS_SEC = "1";
"A":   PN = "1"  !CDS_PN = "1";
"B":   PN = "2"  !CDS_PN = "2";
BODY = "Q_RES","I51": #LOCATION = "PR4010" !CDS_LOCATION = "PR4010" &SEC = "1" #&CDS_SEC = "1";
"A":   PN = "1"  !CDS_PN = "1";
"B":   PN = "2"  !CDS_PN = "2";
BODY = "Q_CAP","I52": #LOCATION = "PC2239" !CDS_LOCATION = "PC2239" &SEC = "1" #&CDS_SEC = "1";
"A":   PN = "1"  !CDS_PN = "1";
"B":   PN = "2"  !CDS_PN = "2";
BODY = "Q_RES","I62": #LOCATION = "PR4004" !CDS_LOCATION = "PR4004" &SEC = "1" #&CDS_SEC = "1";
"A":   PN = "1"  !CDS_PN = "1";
"B":   PN = "2"  !CDS_PN = "2";
BODY = "Q_RES","I65": #LOCATION = "PR4000" !CDS_LOCATION = "PR4000" &SEC = "1" #&CDS_SEC = "1";
"A":   PN = "1"  !CDS_PN = "1";
"B":   PN = "2"  !CDS_PN = "2";
BODY = "Q_CAP","I66": #LOCATION = "PC2233" !CDS_LOCATION = "PC2233" &SEC = "1" #&CDS_SEC = "1";
"A":   PN = "1"  !CDS_PN = "1";
"B":   PN = "2"  !CDS_PN = "2";
BODY = "Q_CAP","I67": #LOCATION = "PC2234" !CDS_LOCATION = "PC2234" &SEC = "1" #&CDS_SEC = "1";
"A":   PN = "1"  !CDS_PN = "1";
"B":   PN = "2"  !CDS_PN = "2";
BODY = "Q_RES","I70": #LOCATION = "PR4008" !CDS_LOCATION = "PR4008" &SEC = "1" #&CDS_SEC = "1";
"A":   PN = "1"  !CDS_PN = "1";
"B":   PN = "2"  !CDS_PN = "2";
BODY = "Q_CAP","I71": #LOCATION = "PC2236" !CDS_LOCATION = "PC2236" &SEC = "1" #&CDS_SEC = "1";
"A":   PN = "1"  !CDS_PN = "1";
"B":   PN = "2"  !CDS_PN = "2";
BODY = "Q_CAP","I72": #LOCATION = "PC2237" !CDS_LOCATION = "PC2237" &SEC = "1" #&CDS_SEC = "1";
"A":   PN = "1"  !CDS_PN = "1";
"B":   PN = "2"  !CDS_PN = "2";
BODY = "Q_RES","I73": #LOCATION = "PR4012" !CDS_LOCATION = "PR4012" &SEC = "1" #&CDS_SEC = "1";
"A":   PN = "1"  !CDS_PN = "1";
"B":   PN = "2"  !CDS_PN = "2";
BODY = "Q_RES","I78": #LOCATION = "R4015" !CDS_LOCATION = "R4015" &SEC = "1" #&CDS_SEC = "1";
"A":   PN = "1"  !CDS_PN = "1";
"B":   PN = "2"  !CDS_PN = "2";
BODY = "SCHOTTKY_AC","I79": #LOCATION = "PD116" !CDS_LOCATION = "PD116" &SEC = "1" #&CDS_SEC = "1";
"A":   PN = "A"  !CDS_PN = "A";
"C":   PN = "C"  !CDS_PN = "C";
BODY = "Q_CAP","I80": #LOCATION = "PC2238" !CDS_LOCATION = "PC2238" &SEC = "1" #&CDS_SEC = "1";
"A":   PN = "1"  !CDS_PN = "1";
"B":   PN = "2"  !CDS_PN = "2";
BODY = "Q_CAP","I6": #LOCATION = "PC2340" !CDS_LOCATION = "PC2340" &SEC = "1" #&CDS_SEC = "1";
"A":   PN = "1"  !CDS_PN = "1";
"B":   PN = "2"  !CDS_PN = "2";
BODY = "MOSFET_NCH_GDS_ESD_PROTECTED","I9": #LOCATION = "Q39" !CDS_LOCATION = "Q39" &SEC = "1" #&CDS_SEC = "1";
"D":   PN = "D"  !CDS_PN = "D";
"G":   PN = "G"  !CDS_PN = "G";
"S":   PN = "S"  !CDS_PN = "S";
BODY = "MOSFET_NCH_DUAL","I22": #LOCATION = "Q125" !CDS_LOCATION = "Q125" &SEC = "1" #&CDS_SEC = "1";
"D1":   PN = "6"  !CDS_PN = "6";
"G1":   PN = "2"  !CDS_PN = "2";
"S1":   PN = "1"  !CDS_PN = "1";
BODY = "MOSFET_NCH_DUAL","I24": #LOCATION = "Q125" !CDS_LOCATION = "Q125" &SEC = "2" #&CDS_SEC = "2";
"D2":   PN = "3"  !CDS_PN = "3";
"G2":   PN = "5"  !CDS_PN = "5";
"S2":   PN = "4"  !CDS_PN = "4";
BODY = "DIODE_TVS","I28": #LOCATION = "PD115" !CDS_LOCATION = "PD115" &SEC = "1" #&CDS_SEC = "1";
"A":   PN = "A"  !CDS_PN = "A";
"C":   PN = "C"  !CDS_PN = "C";
BODY = "Q_RES","I35": #LOCATION = "PR4005" !CDS_LOCATION = "PR4005" &SEC = "1" #&CDS_SEC = "1";
"A":   PN = "1"  !CDS_PN = "1";
"B":   PN = "2"  !CDS_PN = "2";
BODY = "Q_RES","I41": #LOCATION = "PR4006" !CDS_LOCATION = "PR4006" &SEC = "1" #&CDS_SEC = "1";
"A":   PN = "1"  !CDS_PN = "1";
"B":   PN = "2"  !CDS_PN = "2";
BODY = "Q_RES","I43": #LOCATION = "R3836" !CDS_LOCATION = "R3836" &SEC = "1" #&CDS_SEC = "1";
"A":   PN = "1"  !CDS_PN = "1";
"B":   PN = "2"  !CDS_PN = "2";
BODY = "Q_RES","I49": #LOCATION = "PR4011" !CDS_LOCATION = "PR4011" &SEC = "1" #&CDS_SEC = "1";
"A":   PN = "1"  !CDS_PN = "1";
"B":   PN = "2"  !CDS_PN = "2";
BODY = "MAX15090BEWIT","I86": #LOCATION = "PU300" !CDS_LOCATION = "PU300" &SEC = "1" #&CDS_SEC = "1";
"CB":   PN = "B1"  !CDS_PN = "B1";
"CDLY":   PN = "A7"  !CDS_PN = "A7";
"EN#":   PN = "B7"  !CDS_PN = "B7";
"FAULT#":   PN = "C7"  !CDS_PN = "C7";
"GATE":   PN = "A6"  !CDS_PN = "A6";
"GND_B2":   PN = "B2"  !CDS_PN = "B2";
"GND_C1":   PN = "C1"  !CDS_PN = "C1";
"GND_C2":   PN = "C2"  !CDS_PN = "C2";
"IN_A3":   PN = "A3"  !CDS_PN = "A3";
"IN_A5":   PN = "A5"  !CDS_PN = "A5";
"IN_B3":   PN = "B3"  !CDS_PN = "B3";
"IN_B5":   PN = "B5"  !CDS_PN = "B5";
"IN_C3":   PN = "C3"  !CDS_PN = "C3";
"IN_C5":   PN = "C5"  !CDS_PN = "C5";
"IN_D5":   PN = "D5"  !CDS_PN = "D5";
"ISENSE":   PN = "A1"  !CDS_PN = "A1";
"OUT_A4":   PN = "A4"  !CDS_PN = "A4";
"OUT_B4":   PN = "B4"  !CDS_PN = "B4";
"OUT_B6":   PN = "B6"  !CDS_PN = "B6";
"OUT_C4":   PN = "C4"  !CDS_PN = "C4";
"OUT_C6":   PN = "C6"  !CDS_PN = "C6";
"OUT_D4":   PN = "D4"  !CDS_PN = "D4";
"OUT_D6":   PN = "D6"  !CDS_PN = "D6";
"OV":   PN = "D3"  !CDS_PN = "D3";
"PG":   PN = "D7"  !CDS_PN = "D7";
"REG":   PN = "D1"  !CDS_PN = "D1";
"UV":   PN = "D2"  !CDS_PN = "D2";
"VCC":   PN = "A2"  !CDS_PN = "A2";
BODY = "Q_RES","I53": #LOCATION = "PR4014" !CDS_LOCATION = "PR4014" &SEC = "1" #&CDS_SEC = "1";
"A":   PN = "1"  !CDS_PN = "1";
"B":   PN = "2"  !CDS_PN = "2";
BODY = "Q_CAP","I56": #LOCATION = "PC2241" !CDS_LOCATION = "PC2241" &SEC = "1" #&CDS_SEC = "1";
"A":   PN = "1"  !CDS_PN = "1";
"B":   PN = "2"  !CDS_PN = "2";
BODY = "Q_RES","I60": #LOCATION = "PR4002" !CDS_LOCATION = "PR4002" &SEC = "1" #&CDS_SEC = "1";
"A":   PN = "1"  !CDS_PN = "1";
"B":   PN = "2"  !CDS_PN = "2";
BODY = "Q_RES","I63": #LOCATION = "PR4001" !CDS_LOCATION = "PR4001" &SEC = "1" #&CDS_SEC = "1";
"A":   PN = "1"  !CDS_PN = "1";
"B":   PN = "2"  !CDS_PN = "2";
BODY = "Q_RES","I68": #LOCATION = "PR4003" !CDS_LOCATION = "PR4003" &SEC = "1" #&CDS_SEC = "1";
"A":   PN = "1"  !CDS_PN = "1";
"B":   PN = "2"  !CDS_PN = "2";
BODY = "Q_RES","I74": #LOCATION = "PR4526" !CDS_LOCATION = "PR4526" &SEC = "1" #&CDS_SEC = "1";
"A":   PN = "1"  !CDS_PN = "1";
"B":   PN = "2"  !CDS_PN = "2";
BODY = "Q_RES","I76": #LOCATION = "R4013" !CDS_LOCATION = "R4013" &SEC = "1" #&CDS_SEC = "1";
"A":   PN = "1"  !CDS_PN = "1";
"B":   PN = "2"  !CDS_PN = "2";
BODY = "Q_CAP","I81": #LOCATION = "PC2240" !CDS_LOCATION = "PC2240" &SEC = "1" #&CDS_SEC = "1";
"A":   PN = "1"  !CDS_PN = "1";
"B":   PN = "2"  !CDS_PN = "2";
BODY = "Q_CAP","I84": #LOCATION = "PC2242" !CDS_LOCATION = "PC2242" &SEC = "1" #&CDS_SEC = "1";
"A":   PN = "1"  !CDS_PN = "1";
"B":   PN = "2"  !CDS_PN = "2";
BODY = "Q_RES","I89": #LOCATION = "R8012" !CDS_LOCATION = "R8012" #SEC = "1" !CDS_SEC = "1";
"A":   PN = "1"  !CDS_PN = "1";
"B":   PN = "2"  !CDS_PN = "2";
BODY = "Q_RES","I91": #LOCATION = "R8030" !CDS_LOCATION = "R8030" &SEC = "1" #&CDS_SEC = "1";
"A":   PN = "1"  !CDS_PN = "1";
"B":   PN = "2"  !CDS_PN = "2";
BODY = "Q_RES","I93": #LOCATION = "R8031" !CDS_LOCATION = "R8031" &SEC = "1" #&CDS_SEC = "1";
"A":   PN = "1"  !CDS_PN = "1";
"B":   PN = "2"  !CDS_PN = "2";
BODY = "RS31312R","I95": #LOCATION = "PU299" !CDS_LOCATION = "PU299" #SEC = "1" !CDS_SEC = "1";
"AVIN":   PN = "12"  !CDS_PN = "12";
"EN":   PN = "1"  !CDS_PN = "1";
"ENTM":   PN = "3"  !CDS_PN = "3";
"FLTB":   PN = "9"  !CDS_PN = "9";
"GND":   PN = "7"  !CDS_PN = "7";
"IMON":   PN = "8"  !CDS_PN = "8";
"ISET":   PN = "5"  !CDS_PN = "5";
"LOADEN":   PN = "2"  !CDS_PN = "2";
"OV":   PN = "11"  !CDS_PN = "11";
"PG":   PN = "10"  !CDS_PN = "10";
"SS":   PN = "6"  !CDS_PN = "6";
"TIMER":   PN = "4"  !CDS_PN = "4";
"VIN_21_22":   PN = "21_22"  !CDS_PN = "21_22";
"VIN_23":   PN = "23"  !CDS_PN = "23";
"VIN_24":   PN = "24"  !CDS_PN = "24";
"VIN_25":   PN = "25"  !CDS_PN = "25";
"VIN_26":   PN = "26"  !CDS_PN = "26";
"VOUT_13":   PN = "13"  !CDS_PN = "13";
"VOUT_14":   PN = "14"  !CDS_PN = "14";
"VOUT_15":   PN = "15"  !CDS_PN = "15";
"VOUT_16":   PN = "16"  !CDS_PN = "16";
"VOUT_17":   PN = "17"  !CDS_PN = "17";
"VOUT_18":   PN = "18"  !CDS_PN = "18";
"VOUT_19":   PN = "19"  !CDS_PN = "19";
"VOUT_20":   PN = "20"  !CDS_PN = "20";
DRAWING = "@t6g_mb_lib.t6g(sch_1):page351";
BODY = "Q_CAP_DIFFBUS","I21": #LOCATION = "C932" !CDS_LOCATION = "C932" &SEC = "1" #&CDS_SEC = "1";
"1":   PN = "1"  !CDS_PN = "1";
"2":   PN = "2"  !CDS_PN = "2";
BODY = "Q_CAP_DIFFBUS","I22": #LOCATION = "C933" !CDS_LOCATION = "C933" &SEC = "1" #&CDS_SEC = "1";
"1":   PN = "1"  !CDS_PN = "1";
"2":   PN = "2"  !CDS_PN = "2";
BODY = "Q_CAP_DIFFBUS","I23": #LOCATION = "C931" !CDS_LOCATION = "C931" &SEC = "1" #&CDS_SEC = "1";
"1":   PN = "1"  !CDS_PN = "1";
"2":   PN = "2"  !CDS_PN = "2";
BODY = "Q_CAP_DIFFBUS","I24": #LOCATION = "C930" !CDS_LOCATION = "C930" &SEC = "1" #&CDS_SEC = "1";
"1":   PN = "1"  !CDS_PN = "1";
"2":   PN = "2"  !CDS_PN = "2";
BODY = "Q_CAP_DIFFBUS","I25": #LOCATION = "C928" !CDS_LOCATION = "C928" &SEC = "1" #&CDS_SEC = "1";
"1":   PN = "1"  !CDS_PN = "1";
"2":   PN = "2"  !CDS_PN = "2";
BODY = "Q_CAP_DIFFBUS","I26": #LOCATION = "C929" !CDS_LOCATION = "C929" &SEC = "1" #&CDS_SEC = "1";
"1":   PN = "1"  !CDS_PN = "1";
"2":   PN = "2"  !CDS_PN = "2";
BODY = "Q_CAP_DIFFBUS","I27": #LOCATION = "C927" !CDS_LOCATION = "C927" &SEC = "1" #&CDS_SEC = "1";
"1":   PN = "1"  !CDS_PN = "1";
"2":   PN = "2"  !CDS_PN = "2";
BODY = "Q_CAP_DIFFBUS","I28": #LOCATION = "C926" !CDS_LOCATION = "C926" &SEC = "1" #&CDS_SEC = "1";
"1":   PN = "1"  !CDS_PN = "1";
"2":   PN = "2"  !CDS_PN = "2";
BODY = "Q_CAP_DIFFBUS","I29": #LOCATION = "C925" !CDS_LOCATION = "C925" &SEC = "1" #&CDS_SEC = "1";
"1":   PN = "1"  !CDS_PN = "1";
"2":   PN = "2"  !CDS_PN = "2";
BODY = "Q_CAP_DIFFBUS","I30": #LOCATION = "C924" !CDS_LOCATION = "C924" &SEC = "1" #&CDS_SEC = "1";
"1":   PN = "1"  !CDS_PN = "1";
"2":   PN = "2"  !CDS_PN = "2";
BODY = "Q_CAP_DIFFBUS","I31": #LOCATION = "C923" !CDS_LOCATION = "C923" &SEC = "1" #&CDS_SEC = "1";
"1":   PN = "1"  !CDS_PN = "1";
"2":   PN = "2"  !CDS_PN = "2";
BODY = "Q_CAP_DIFFBUS","I32": #LOCATION = "C922" !CDS_LOCATION = "C922" &SEC = "1" #&CDS_SEC = "1";
"1":   PN = "1"  !CDS_PN = "1";
"2":   PN = "2"  !CDS_PN = "2";
BODY = "Q_CAP_DIFFBUS","I33": #LOCATION = "C921" !CDS_LOCATION = "C921" &SEC = "1" #&CDS_SEC = "1";
"1":   PN = "1"  !CDS_PN = "1";
"2":   PN = "2"  !CDS_PN = "2";
BODY = "Q_CAP_DIFFBUS","I34": #LOCATION = "C920" !CDS_LOCATION = "C920" &SEC = "1" #&CDS_SEC = "1";
"1":   PN = "1"  !CDS_PN = "1";
"2":   PN = "2"  !CDS_PN = "2";
BODY = "Q_CAP_DIFFBUS","I35": #LOCATION = "C918" !CDS_LOCATION = "C918" &SEC = "1" #&CDS_SEC = "1";
"1":   PN = "1"  !CDS_PN = "1";
"2":   PN = "2"  !CDS_PN = "2";
BODY = "Q_CAP_DIFFBUS","I36": #LOCATION = "C919" !CDS_LOCATION = "C919" &SEC = "1" #&CDS_SEC = "1";
"1":   PN = "1"  !CDS_PN = "1";
"2":   PN = "2"  !CDS_PN = "2";
BODY = "Q_CAP_DIFFBUS","I53": #LOCATION = "C916" !CDS_LOCATION = "C916" &SEC = "1" #&CDS_SEC = "1";
"1":   PN = "1"  !CDS_PN = "1";
"2":   PN = "2"  !CDS_PN = "2";
BODY = "Q_CAP_DIFFBUS","I54": #LOCATION = "C917" !CDS_LOCATION = "C917" &SEC = "1" #&CDS_SEC = "1";
"1":   PN = "1"  !CDS_PN = "1";
"2":   PN = "2"  !CDS_PN = "2";
BODY = "Q_CAP_DIFFBUS","I55": #LOCATION = "C915" !CDS_LOCATION = "C915" &SEC = "1" #&CDS_SEC = "1";
"1":   PN = "1"  !CDS_PN = "1";
"2":   PN = "2"  !CDS_PN = "2";
BODY = "Q_CAP_DIFFBUS","I56": #LOCATION = "C914" !CDS_LOCATION = "C914" &SEC = "1" #&CDS_SEC = "1";
"1":   PN = "1"  !CDS_PN = "1";
"2":   PN = "2"  !CDS_PN = "2";
BODY = "Q_CAP_DIFFBUS","I57": #LOCATION = "C913" !CDS_LOCATION = "C913" &SEC = "1" #&CDS_SEC = "1";
"1":   PN = "1"  !CDS_PN = "1";
"2":   PN = "2"  !CDS_PN = "2";
BODY = "Q_CAP_DIFFBUS","I58": #LOCATION = "C912" !CDS_LOCATION = "C912" &SEC = "1" #&CDS_SEC = "1";
"1":   PN = "1"  !CDS_PN = "1";
"2":   PN = "2"  !CDS_PN = "2";
BODY = "Q_CAP_DIFFBUS","I59": #LOCATION = "C911" !CDS_LOCATION = "C911" &SEC = "1" #&CDS_SEC = "1";
"1":   PN = "1"  !CDS_PN = "1";
"2":   PN = "2"  !CDS_PN = "2";
BODY = "Q_CAP_DIFFBUS","I60": #LOCATION = "C910" !CDS_LOCATION = "C910" &SEC = "1" #&CDS_SEC = "1";
"1":   PN = "1"  !CDS_PN = "1";
"2":   PN = "2"  !CDS_PN = "2";
BODY = "Q_CAP_DIFFBUS","I61": #LOCATION = "C909" !CDS_LOCATION = "C909" &SEC = "1" #&CDS_SEC = "1";
"1":   PN = "1"  !CDS_PN = "1";
"2":   PN = "2"  !CDS_PN = "2";
BODY = "Q_CAP_DIFFBUS","I62": #LOCATION = "C908" !CDS_LOCATION = "C908" &SEC = "1" #&CDS_SEC = "1";
"1":   PN = "1"  !CDS_PN = "1";
"2":   PN = "2"  !CDS_PN = "2";
BODY = "Q_CAP_DIFFBUS","I63": #LOCATION = "C906" !CDS_LOCATION = "C906" &SEC = "1" #&CDS_SEC = "1";
"1":   PN = "1"  !CDS_PN = "1";
"2":   PN = "2"  !CDS_PN = "2";
BODY = "Q_CAP_DIFFBUS","I64": #LOCATION = "C907" !CDS_LOCATION = "C907" &SEC = "1" #&CDS_SEC = "1";
"1":   PN = "1"  !CDS_PN = "1";
"2":   PN = "2"  !CDS_PN = "2";
BODY = "Q_CAP_DIFFBUS","I65": #LOCATION = "C905" !CDS_LOCATION = "C905" &SEC = "1" #&CDS_SEC = "1";
"1":   PN = "1"  !CDS_PN = "1";
"2":   PN = "2"  !CDS_PN = "2";
BODY = "Q_CAP_DIFFBUS","I66": #LOCATION = "C904" !CDS_LOCATION = "C904" &SEC = "1" #&CDS_SEC = "1";
"1":   PN = "1"  !CDS_PN = "1";
"2":   PN = "2"  !CDS_PN = "2";
BODY = "Q_CAP_DIFFBUS","I67": #LOCATION = "C903" !CDS_LOCATION = "C903" &SEC = "1" #&CDS_SEC = "1";
"1":   PN = "1"  !CDS_PN = "1";
"2":   PN = "2"  !CDS_PN = "2";
BODY = "Q_CAP_DIFFBUS","I68": #LOCATION = "C902" !CDS_LOCATION = "C902" &SEC = "1" #&CDS_SEC = "1";
"1":   PN = "1"  !CDS_PN = "1";
"2":   PN = "2"  !CDS_PN = "2";
BODY = "Q_CAP_DIFFBUS","I121": #LOCATION = "C965" !CDS_LOCATION = "C965" &SEC = "1" #&CDS_SEC = "1";
"1":   PN = "1"  !CDS_PN = "1";
"2":   PN = "2"  !CDS_PN = "2";
BODY = "Q_CAP_DIFFBUS","I122": #LOCATION = "C964" !CDS_LOCATION = "C964" &SEC = "1" #&CDS_SEC = "1";
"1":   PN = "1"  !CDS_PN = "1";
"2":   PN = "2"  !CDS_PN = "2";
BODY = "Q_CAP_DIFFBUS","I123": #LOCATION = "C963" !CDS_LOCATION = "C963" &SEC = "1" #&CDS_SEC = "1";
"1":   PN = "1"  !CDS_PN = "1";
"2":   PN = "2"  !CDS_PN = "2";
BODY = "Q_CAP_DIFFBUS","I124": #LOCATION = "C962" !CDS_LOCATION = "C962" &SEC = "1" #&CDS_SEC = "1";
"1":   PN = "1"  !CDS_PN = "1";
"2":   PN = "2"  !CDS_PN = "2";
BODY = "Q_CAP_DIFFBUS","I125": #LOCATION = "C961" !CDS_LOCATION = "C961" &SEC = "1" #&CDS_SEC = "1";
"1":   PN = "1"  !CDS_PN = "1";
"2":   PN = "2"  !CDS_PN = "2";
BODY = "Q_CAP_DIFFBUS","I126": #LOCATION = "C960" !CDS_LOCATION = "C960" &SEC = "1" #&CDS_SEC = "1";
"1":   PN = "1"  !CDS_PN = "1";
"2":   PN = "2"  !CDS_PN = "2";
BODY = "Q_CAP_DIFFBUS","I127": #LOCATION = "C959" !CDS_LOCATION = "C959" &SEC = "1" #&CDS_SEC = "1";
"1":   PN = "1"  !CDS_PN = "1";
"2":   PN = "2"  !CDS_PN = "2";
BODY = "Q_CAP_DIFFBUS","I128": #LOCATION = "C958" !CDS_LOCATION = "C958" &SEC = "1" #&CDS_SEC = "1";
"1":   PN = "1"  !CDS_PN = "1";
"2":   PN = "2"  !CDS_PN = "2";
BODY = "Q_CAP_DIFFBUS","I133": #LOCATION = "C954" !CDS_LOCATION = "C954" &SEC = "1" #&CDS_SEC = "1";
"1":   PN = "1"  !CDS_PN = "1";
"2":   PN = "2"  !CDS_PN = "2";
BODY = "Q_CAP_DIFFBUS","I134": #LOCATION = "C953" !CDS_LOCATION = "C953" &SEC = "1" #&CDS_SEC = "1";
"1":   PN = "1"  !CDS_PN = "1";
"2":   PN = "2"  !CDS_PN = "2";
BODY = "Q_CAP_DIFFBUS","I135": #LOCATION = "C952" !CDS_LOCATION = "C952" &SEC = "1" #&CDS_SEC = "1";
"1":   PN = "1"  !CDS_PN = "1";
"2":   PN = "2"  !CDS_PN = "2";
BODY = "Q_CAP_DIFFBUS","I136": #LOCATION = "C951" !CDS_LOCATION = "C951" &SEC = "1" #&CDS_SEC = "1";
"1":   PN = "1"  !CDS_PN = "1";
"2":   PN = "2"  !CDS_PN = "2";
BODY = "Q_CAP_DIFFBUS","I137": #LOCATION = "C950" !CDS_LOCATION = "C950" &SEC = "1" #&CDS_SEC = "1";
"1":   PN = "1"  !CDS_PN = "1";
"2":   PN = "2"  !CDS_PN = "2";
BODY = "Q_CAP_DIFFBUS","I151": #LOCATION = "C949" !CDS_LOCATION = "C949" &SEC = "1" #&CDS_SEC = "1";
"1":   PN = "1"  !CDS_PN = "1";
"2":   PN = "2"  !CDS_PN = "2";
BODY = "Q_CAP_DIFFBUS","I152": #LOCATION = "C948" !CDS_LOCATION = "C948" &SEC = "1" #&CDS_SEC = "1";
"1":   PN = "1"  !CDS_PN = "1";
"2":   PN = "2"  !CDS_PN = "2";
BODY = "Q_CAP_DIFFBUS","I153": #LOCATION = "C947" !CDS_LOCATION = "C947" &SEC = "1" #&CDS_SEC = "1";
"1":   PN = "1"  !CDS_PN = "1";
"2":   PN = "2"  !CDS_PN = "2";
BODY = "Q_CAP_DIFFBUS","I154": #LOCATION = "C946" !CDS_LOCATION = "C946" &SEC = "1" #&CDS_SEC = "1";
"1":   PN = "1"  !CDS_PN = "1";
"2":   PN = "2"  !CDS_PN = "2";
BODY = "Q_CAP_DIFFBUS","I155": #LOCATION = "C945" !CDS_LOCATION = "C945" &SEC = "1" #&CDS_SEC = "1";
"1":   PN = "1"  !CDS_PN = "1";
"2":   PN = "2"  !CDS_PN = "2";
BODY = "Q_CAP_DIFFBUS","I156": #LOCATION = "C944" !CDS_LOCATION = "C944" &SEC = "1" #&CDS_SEC = "1";
"1":   PN = "1"  !CDS_PN = "1";
"2":   PN = "2"  !CDS_PN = "2";
BODY = "Q_CAP_DIFFBUS","I157": #LOCATION = "C943" !CDS_LOCATION = "C943" &SEC = "1" #&CDS_SEC = "1";
"1":   PN = "1"  !CDS_PN = "1";
"2":   PN = "2"  !CDS_PN = "2";
BODY = "Q_CAP_DIFFBUS","I158": #LOCATION = "C942" !CDS_LOCATION = "C942" &SEC = "1" #&CDS_SEC = "1";
"1":   PN = "1"  !CDS_PN = "1";
"2":   PN = "2"  !CDS_PN = "2";
BODY = "Q_CAP_DIFFBUS","I159": #LOCATION = "C941" !CDS_LOCATION = "C941" &SEC = "1" #&CDS_SEC = "1";
"1":   PN = "1"  !CDS_PN = "1";
"2":   PN = "2"  !CDS_PN = "2";
BODY = "Q_CAP_DIFFBUS","I160": #LOCATION = "C940" !CDS_LOCATION = "C940" &SEC = "1" #&CDS_SEC = "1";
"1":   PN = "1"  !CDS_PN = "1";
"2":   PN = "2"  !CDS_PN = "2";
BODY = "Q_CAP_DIFFBUS","I164": #LOCATION = "C939" !CDS_LOCATION = "C939" &SEC = "1" #&CDS_SEC = "1";
"1":   PN = "1"  !CDS_PN = "1";
"2":   PN = "2"  !CDS_PN = "2";
BODY = "Q_CAP_DIFFBUS","I165": #LOCATION = "C938" !CDS_LOCATION = "C938" &SEC = "1" #&CDS_SEC = "1";
"1":   PN = "1"  !CDS_PN = "1";
"2":   PN = "2"  !CDS_PN = "2";
BODY = "Q_CAP_DIFFBUS","I166": #LOCATION = "C937" !CDS_LOCATION = "C937" &SEC = "1" #&CDS_SEC = "1";
"1":   PN = "1"  !CDS_PN = "1";
"2":   PN = "2"  !CDS_PN = "2";
BODY = "Q_CAP_DIFFBUS","I167": #LOCATION = "C936" !CDS_LOCATION = "C936" &SEC = "1" #&CDS_SEC = "1";
"1":   PN = "1"  !CDS_PN = "1";
"2":   PN = "2"  !CDS_PN = "2";
BODY = "Q_CAP_DIFFBUS","I168": #LOCATION = "C935" !CDS_LOCATION = "C935" &SEC = "1" #&CDS_SEC = "1";
"1":   PN = "1"  !CDS_PN = "1";
"2":   PN = "2"  !CDS_PN = "2";
BODY = "Q_CAP_DIFFBUS","I169": #LOCATION = "C934" !CDS_LOCATION = "C934" &SEC = "1" #&CDS_SEC = "1";
"1":   PN = "1"  !CDS_PN = "1";
"2":   PN = "2"  !CDS_PN = "2";
BODY = "Q_CAP_DIFFBUS","I206": #LOCATION = "C957" !CDS_LOCATION = "C957" &SEC = "1" #&CDS_SEC = "1";
"1":   PN = "1"  !CDS_PN = "1";
"2":   PN = "2"  !CDS_PN = "2";
BODY = "Q_CAP_DIFFBUS","I207": #LOCATION = "C956" !CDS_LOCATION = "C956" &SEC = "1" #&CDS_SEC = "1";
"1":   PN = "1"  !CDS_PN = "1";
"2":   PN = "2"  !CDS_PN = "2";
BODY = "Q_CAP_DIFFBUS","I208": #LOCATION = "C955" !CDS_LOCATION = "C955" &SEC = "1" #&CDS_SEC = "1";
"1":   PN = "1"  !CDS_PN = "1";
"2":   PN = "2"  !CDS_PN = "2";
DRAWING = "@t6g_mb_lib.t6g(sch_1):page352";
BODY = "Q_CAP_DIFFBUS","I21": #LOCATION = "C869" !CDS_LOCATION = "C869" &SEC = "1" #&CDS_SEC = "1";
"1":   PN = "1"  !CDS_PN = "1";
"2":   PN = "2"  !CDS_PN = "2";
BODY = "Q_CAP_DIFFBUS","I22": #LOCATION = "C868" !CDS_LOCATION = "C868" &SEC = "1" #&CDS_SEC = "1";
"1":   PN = "1"  !CDS_PN = "1";
"2":   PN = "2"  !CDS_PN = "2";
BODY = "Q_CAP_DIFFBUS","I23": #LOCATION = "C867" !CDS_LOCATION = "C867" &SEC = "1" #&CDS_SEC = "1";
"1":   PN = "1"  !CDS_PN = "1";
"2":   PN = "2"  !CDS_PN = "2";
BODY = "Q_CAP_DIFFBUS","I24": #LOCATION = "C866" !CDS_LOCATION = "C866" &SEC = "1" #&CDS_SEC = "1";
"1":   PN = "1"  !CDS_PN = "1";
"2":   PN = "2"  !CDS_PN = "2";
BODY = "Q_CAP_DIFFBUS","I25": #LOCATION = "C864" !CDS_LOCATION = "C864" &SEC = "1" #&CDS_SEC = "1";
"1":   PN = "1"  !CDS_PN = "1";
"2":   PN = "2"  !CDS_PN = "2";
BODY = "Q_CAP_DIFFBUS","I26": #LOCATION = "C865" !CDS_LOCATION = "C865" &SEC = "1" #&CDS_SEC = "1";
"1":   PN = "1"  !CDS_PN = "1";
"2":   PN = "2"  !CDS_PN = "2";
BODY = "Q_CAP_DIFFBUS","I27": #LOCATION = "C863" !CDS_LOCATION = "C863" &SEC = "1" #&CDS_SEC = "1";
"1":   PN = "1"  !CDS_PN = "1";
"2":   PN = "2"  !CDS_PN = "2";
BODY = "Q_CAP_DIFFBUS","I28": #LOCATION = "C862" !CDS_LOCATION = "C862" &SEC = "1" #&CDS_SEC = "1";
"1":   PN = "1"  !CDS_PN = "1";
"2":   PN = "2"  !CDS_PN = "2";
BODY = "Q_CAP_DIFFBUS","I29": #LOCATION = "C861" !CDS_LOCATION = "C861" &SEC = "1" #&CDS_SEC = "1";
"1":   PN = "1"  !CDS_PN = "1";
"2":   PN = "2"  !CDS_PN = "2";
BODY = "Q_CAP_DIFFBUS","I30": #LOCATION = "C860" !CDS_LOCATION = "C860" &SEC = "1" #&CDS_SEC = "1";
"1":   PN = "1"  !CDS_PN = "1";
"2":   PN = "2"  !CDS_PN = "2";
BODY = "Q_CAP_DIFFBUS","I36": #LOCATION = "C859" !CDS_LOCATION = "C859" &SEC = "1" #&CDS_SEC = "1";
"1":   PN = "1"  !CDS_PN = "1";
"2":   PN = "2"  !CDS_PN = "2";
BODY = "Q_CAP_DIFFBUS","I37": #LOCATION = "C858" !CDS_LOCATION = "C858" &SEC = "1" #&CDS_SEC = "1";
"1":   PN = "1"  !CDS_PN = "1";
"2":   PN = "2"  !CDS_PN = "2";
BODY = "Q_CAP_DIFFBUS","I38": #LOCATION = "C857" !CDS_LOCATION = "C857" &SEC = "1" #&CDS_SEC = "1";
"1":   PN = "1"  !CDS_PN = "1";
"2":   PN = "2"  !CDS_PN = "2";
BODY = "Q_CAP_DIFFBUS","I39": #LOCATION = "C856" !CDS_LOCATION = "C856" &SEC = "1" #&CDS_SEC = "1";
"1":   PN = "1"  !CDS_PN = "1";
"2":   PN = "2"  !CDS_PN = "2";
BODY = "Q_CAP_DIFFBUS","I40": #LOCATION = "C855" !CDS_LOCATION = "C855" &SEC = "1" #&CDS_SEC = "1";
"1":   PN = "1"  !CDS_PN = "1";
"2":   PN = "2"  !CDS_PN = "2";
BODY = "Q_CAP_DIFFBUS","I41": #LOCATION = "C854" !CDS_LOCATION = "C854" &SEC = "1" #&CDS_SEC = "1";
"1":   PN = "1"  !CDS_PN = "1";
"2":   PN = "2"  !CDS_PN = "2";
BODY = "Q_CAP_DIFFBUS","I61": #LOCATION = "C852" !CDS_LOCATION = "C852" &SEC = "1" #&CDS_SEC = "1";
"1":   PN = "1"  !CDS_PN = "1";
"2":   PN = "2"  !CDS_PN = "2";
BODY = "Q_CAP_DIFFBUS","I62": #LOCATION = "C853" !CDS_LOCATION = "C853" &SEC = "1" #&CDS_SEC = "1";
"1":   PN = "1"  !CDS_PN = "1";
"2":   PN = "2"  !CDS_PN = "2";
BODY = "Q_CAP_DIFFBUS","I63": #LOCATION = "C851" !CDS_LOCATION = "C851" &SEC = "1" #&CDS_SEC = "1";
"1":   PN = "1"  !CDS_PN = "1";
"2":   PN = "2"  !CDS_PN = "2";
BODY = "Q_CAP_DIFFBUS","I64": #LOCATION = "C850" !CDS_LOCATION = "C850" &SEC = "1" #&CDS_SEC = "1";
"1":   PN = "1"  !CDS_PN = "1";
"2":   PN = "2"  !CDS_PN = "2";
BODY = "Q_CAP_DIFFBUS","I65": #LOCATION = "C849" !CDS_LOCATION = "C849" &SEC = "1" #&CDS_SEC = "1";
"1":   PN = "1"  !CDS_PN = "1";
"2":   PN = "2"  !CDS_PN = "2";
BODY = "Q_CAP_DIFFBUS","I66": #LOCATION = "C848" !CDS_LOCATION = "C848" &SEC = "1" #&CDS_SEC = "1";
"1":   PN = "1"  !CDS_PN = "1";
"2":   PN = "2"  !CDS_PN = "2";
BODY = "Q_CAP_DIFFBUS","I67": #LOCATION = "C847" !CDS_LOCATION = "C847" &SEC = "1" #&CDS_SEC = "1";
"1":   PN = "1"  !CDS_PN = "1";
"2":   PN = "2"  !CDS_PN = "2";
BODY = "Q_CAP_DIFFBUS","I68": #LOCATION = "C846" !CDS_LOCATION = "C846" &SEC = "1" #&CDS_SEC = "1";
"1":   PN = "1"  !CDS_PN = "1";
"2":   PN = "2"  !CDS_PN = "2";
BODY = "Q_CAP_DIFFBUS","I69": #LOCATION = "C845" !CDS_LOCATION = "C845" &SEC = "1" #&CDS_SEC = "1";
"1":   PN = "1"  !CDS_PN = "1";
"2":   PN = "2"  !CDS_PN = "2";
BODY = "Q_CAP_DIFFBUS","I70": #LOCATION = "C844" !CDS_LOCATION = "C844" &SEC = "1" #&CDS_SEC = "1";
"1":   PN = "1"  !CDS_PN = "1";
"2":   PN = "2"  !CDS_PN = "2";
BODY = "Q_CAP_DIFFBUS","I76": #LOCATION = "C842" !CDS_LOCATION = "C842" &SEC = "1" #&CDS_SEC = "1";
"1":   PN = "1"  !CDS_PN = "1";
"2":   PN = "2"  !CDS_PN = "2";
BODY = "Q_CAP_DIFFBUS","I77": #LOCATION = "C843" !CDS_LOCATION = "C843" &SEC = "1" #&CDS_SEC = "1";
"1":   PN = "1"  !CDS_PN = "1";
"2":   PN = "2"  !CDS_PN = "2";
BODY = "Q_CAP_DIFFBUS","I78": #LOCATION = "C841" !CDS_LOCATION = "C841" &SEC = "1" #&CDS_SEC = "1";
"1":   PN = "1"  !CDS_PN = "1";
"2":   PN = "2"  !CDS_PN = "2";
BODY = "Q_CAP_DIFFBUS","I79": #LOCATION = "C840" !CDS_LOCATION = "C840" &SEC = "1" #&CDS_SEC = "1";
"1":   PN = "1"  !CDS_PN = "1";
"2":   PN = "2"  !CDS_PN = "2";
BODY = "Q_CAP_DIFFBUS","I80": #LOCATION = "C838" !CDS_LOCATION = "C838" &SEC = "1" #&CDS_SEC = "1";
"1":   PN = "1"  !CDS_PN = "1";
"2":   PN = "2"  !CDS_PN = "2";
BODY = "Q_CAP_DIFFBUS","I81": #LOCATION = "C839" !CDS_LOCATION = "C839" &SEC = "1" #&CDS_SEC = "1";
"1":   PN = "1"  !CDS_PN = "1";
"2":   PN = "2"  !CDS_PN = "2";
BODY = "Q_CAP_DIFFBUS","I120": #LOCATION = "C901" !CDS_LOCATION = "C901" &SEC = "1" #&CDS_SEC = "1";
"1":   PN = "1"  !CDS_PN = "1";
"2":   PN = "2"  !CDS_PN = "2";
BODY = "Q_CAP_DIFFBUS","I121": #LOCATION = "C900" !CDS_LOCATION = "C900" &SEC = "1" #&CDS_SEC = "1";
"1":   PN = "1"  !CDS_PN = "1";
"2":   PN = "2"  !CDS_PN = "2";
BODY = "Q_CAP_DIFFBUS","I122": #LOCATION = "C899" !CDS_LOCATION = "C899" &SEC = "1" #&CDS_SEC = "1";
"1":   PN = "1"  !CDS_PN = "1";
"2":   PN = "2"  !CDS_PN = "2";
BODY = "Q_CAP_DIFFBUS","I123": #LOCATION = "C897" !CDS_LOCATION = "C897" &SEC = "1" #&CDS_SEC = "1";
"1":   PN = "1"  !CDS_PN = "1";
"2":   PN = "2"  !CDS_PN = "2";
BODY = "Q_CAP_DIFFBUS","I124": #LOCATION = "C896" !CDS_LOCATION = "C896" &SEC = "1" #&CDS_SEC = "1";
"1":   PN = "1"  !CDS_PN = "1";
"2":   PN = "2"  !CDS_PN = "2";
BODY = "Q_CAP_DIFFBUS","I125": #LOCATION = "C895" !CDS_LOCATION = "C895" &SEC = "1" #&CDS_SEC = "1";
"1":   PN = "1"  !CDS_PN = "1";
"2":   PN = "2"  !CDS_PN = "2";
BODY = "Q_CAP_DIFFBUS","I126": #LOCATION = "C894" !CDS_LOCATION = "C894" &SEC = "1" #&CDS_SEC = "1";
"1":   PN = "1"  !CDS_PN = "1";
"2":   PN = "2"  !CDS_PN = "2";
BODY = "Q_CAP_DIFFBUS","I127": #LOCATION = "C892" !CDS_LOCATION = "C892" &SEC = "1" #&CDS_SEC = "1";
"1":   PN = "1"  !CDS_PN = "1";
"2":   PN = "2"  !CDS_PN = "2";
BODY = "Q_CAP_DIFFBUS","I128": #LOCATION = "C893" !CDS_LOCATION = "C893" &SEC = "1" #&CDS_SEC = "1";
"1":   PN = "1"  !CDS_PN = "1";
"2":   PN = "2"  !CDS_PN = "2";
BODY = "Q_CAP_DIFFBUS","I132": #LOCATION = "C891" !CDS_LOCATION = "C891" &SEC = "1" #&CDS_SEC = "1";
"1":   PN = "1"  !CDS_PN = "1";
"2":   PN = "2"  !CDS_PN = "2";
BODY = "Q_CAP_DIFFBUS","I133": #LOCATION = "C890" !CDS_LOCATION = "C890" &SEC = "1" #&CDS_SEC = "1";
"1":   PN = "1"  !CDS_PN = "1";
"2":   PN = "2"  !CDS_PN = "2";
BODY = "Q_CAP_DIFFBUS","I134": #LOCATION = "C889" !CDS_LOCATION = "C889" &SEC = "1" #&CDS_SEC = "1";
"1":   PN = "1"  !CDS_PN = "1";
"2":   PN = "2"  !CDS_PN = "2";
BODY = "Q_CAP_DIFFBUS","I135": #LOCATION = "C888" !CDS_LOCATION = "C888" &SEC = "1" #&CDS_SEC = "1";
"1":   PN = "1"  !CDS_PN = "1";
"2":   PN = "2"  !CDS_PN = "2";
BODY = "Q_CAP_DIFFBUS","I136": #LOCATION = "C887" !CDS_LOCATION = "C887" &SEC = "1" #&CDS_SEC = "1";
"1":   PN = "1"  !CDS_PN = "1";
"2":   PN = "2"  !CDS_PN = "2";
BODY = "Q_CAP_DIFFBUS","I137": #LOCATION = "C886" !CDS_LOCATION = "C886" &SEC = "1" #&CDS_SEC = "1";
"1":   PN = "1"  !CDS_PN = "1";
"2":   PN = "2"  !CDS_PN = "2";
BODY = "Q_CAP_DIFFBUS","I151": #LOCATION = "C884" !CDS_LOCATION = "C884" &SEC = "1" #&CDS_SEC = "1";
"1":   PN = "1"  !CDS_PN = "1";
"2":   PN = "2"  !CDS_PN = "2";
BODY = "Q_CAP_DIFFBUS","I152": #LOCATION = "C885" !CDS_LOCATION = "C885" &SEC = "1" #&CDS_SEC = "1";
"1":   PN = "1"  !CDS_PN = "1";
"2":   PN = "2"  !CDS_PN = "2";
BODY = "Q_CAP_DIFFBUS","I153": #LOCATION = "C883" !CDS_LOCATION = "C883" &SEC = "1" #&CDS_SEC = "1";
"1":   PN = "1"  !CDS_PN = "1";
"2":   PN = "2"  !CDS_PN = "2";
BODY = "Q_CAP_DIFFBUS","I154": #LOCATION = "C882" !CDS_LOCATION = "C882" &SEC = "1" #&CDS_SEC = "1";
"1":   PN = "1"  !CDS_PN = "1";
"2":   PN = "2"  !CDS_PN = "2";
BODY = "Q_CAP_DIFFBUS","I155": #LOCATION = "C881" !CDS_LOCATION = "C881" &SEC = "1" #&CDS_SEC = "1";
"1":   PN = "1"  !CDS_PN = "1";
"2":   PN = "2"  !CDS_PN = "2";
BODY = "Q_CAP_DIFFBUS","I156": #LOCATION = "C880" !CDS_LOCATION = "C880" &SEC = "1" #&CDS_SEC = "1";
"1":   PN = "1"  !CDS_PN = "1";
"2":   PN = "2"  !CDS_PN = "2";
BODY = "Q_CAP_DIFFBUS","I157": #LOCATION = "C878" !CDS_LOCATION = "C878" &SEC = "1" #&CDS_SEC = "1";
"1":   PN = "1"  !CDS_PN = "1";
"2":   PN = "2"  !CDS_PN = "2";
BODY = "Q_CAP_DIFFBUS","I158": #LOCATION = "C879" !CDS_LOCATION = "C879" &SEC = "1" #&CDS_SEC = "1";
"1":   PN = "1"  !CDS_PN = "1";
"2":   PN = "2"  !CDS_PN = "2";
BODY = "Q_CAP_DIFFBUS","I159": #LOCATION = "C877" !CDS_LOCATION = "C877" &SEC = "1" #&CDS_SEC = "1";
"1":   PN = "1"  !CDS_PN = "1";
"2":   PN = "2"  !CDS_PN = "2";
BODY = "Q_CAP_DIFFBUS","I160": #LOCATION = "C876" !CDS_LOCATION = "C876" &SEC = "1" #&CDS_SEC = "1";
"1":   PN = "1"  !CDS_PN = "1";
"2":   PN = "2"  !CDS_PN = "2";
BODY = "Q_CAP_DIFFBUS","I164": #LOCATION = "C875" !CDS_LOCATION = "C875" &SEC = "1" #&CDS_SEC = "1";
"1":   PN = "1"  !CDS_PN = "1";
"2":   PN = "2"  !CDS_PN = "2";
BODY = "Q_CAP_DIFFBUS","I165": #LOCATION = "C874" !CDS_LOCATION = "C874" &SEC = "1" #&CDS_SEC = "1";
"1":   PN = "1"  !CDS_PN = "1";
"2":   PN = "2"  !CDS_PN = "2";
BODY = "Q_CAP_DIFFBUS","I166": #LOCATION = "C873" !CDS_LOCATION = "C873" &SEC = "1" #&CDS_SEC = "1";
"1":   PN = "1"  !CDS_PN = "1";
"2":   PN = "2"  !CDS_PN = "2";
BODY = "Q_CAP_DIFFBUS","I167": #LOCATION = "C872" !CDS_LOCATION = "C872" &SEC = "1" #&CDS_SEC = "1";
"1":   PN = "1"  !CDS_PN = "1";
"2":   PN = "2"  !CDS_PN = "2";
BODY = "Q_CAP_DIFFBUS","I168": #LOCATION = "C871" !CDS_LOCATION = "C871" &SEC = "1" #&CDS_SEC = "1";
"1":   PN = "1"  !CDS_PN = "1";
"2":   PN = "2"  !CDS_PN = "2";
BODY = "Q_CAP_DIFFBUS","I169": #LOCATION = "C870" !CDS_LOCATION = "C870" &SEC = "1" #&CDS_SEC = "1";
"1":   PN = "1"  !CDS_PN = "1";
"2":   PN = "2"  !CDS_PN = "2";
BODY = "Q_CAP_DIFFBUS","I206": #LOCATION = "C898" !CDS_LOCATION = "C898" &SEC = "1" #&CDS_SEC = "1";
"1":   PN = "1"  !CDS_PN = "1";
"2":   PN = "2"  !CDS_PN = "2";
DRAWING = "@t6g_mb_lib.t6g(sch_1):page353";
BODY = "Q_CAP_DIFFBUS","I229": #LOCATION = "C1579" !CDS_LOCATION = "C1579" &SEC = "1" #&CDS_SEC = "1";
"1":   PN = "1"  !CDS_PN = "1";
"2":   PN = "2"  !CDS_PN = "2";
BODY = "Q_CAP_DIFFBUS","I230": #LOCATION = "C1578" !CDS_LOCATION = "C1578" &SEC = "1" #&CDS_SEC = "1";
"1":   PN = "1"  !CDS_PN = "1";
"2":   PN = "2"  !CDS_PN = "2";
BODY = "Q_CAP_DIFFBUS","I231": #LOCATION = "C1575" !CDS_LOCATION = "C1575" &SEC = "1" #&CDS_SEC = "1";
"1":   PN = "1"  !CDS_PN = "1";
"2":   PN = "2"  !CDS_PN = "2";
BODY = "Q_CAP_DIFFBUS","I232": #LOCATION = "C1574" !CDS_LOCATION = "C1574" &SEC = "1" #&CDS_SEC = "1";
"1":   PN = "1"  !CDS_PN = "1";
"2":   PN = "2"  !CDS_PN = "2";
BODY = "Q_CAP_DIFFBUS","I233": #LOCATION = "C1573" !CDS_LOCATION = "C1573" &SEC = "1" #&CDS_SEC = "1";
"1":   PN = "1"  !CDS_PN = "1";
"2":   PN = "2"  !CDS_PN = "2";
BODY = "Q_CAP_DIFFBUS","I234": #LOCATION = "C1572" !CDS_LOCATION = "C1572" &SEC = "1" #&CDS_SEC = "1";
"1":   PN = "1"  !CDS_PN = "1";
"2":   PN = "2"  !CDS_PN = "2";
BODY = "Q_CAP_DIFFBUS","I235": #LOCATION = "C1570" !CDS_LOCATION = "C1570" &SEC = "1" #&CDS_SEC = "1";
"1":   PN = "1"  !CDS_PN = "1";
"2":   PN = "2"  !CDS_PN = "2";
BODY = "Q_CAP_DIFFBUS","I236": #LOCATION = "C1571" !CDS_LOCATION = "C1571" &SEC = "1" #&CDS_SEC = "1";
"1":   PN = "1"  !CDS_PN = "1";
"2":   PN = "2"  !CDS_PN = "2";
BODY = "Q_CAP_DIFFBUS","I237": #LOCATION = "C1569" !CDS_LOCATION = "C1569" &SEC = "1" #&CDS_SEC = "1";
"1":   PN = "1"  !CDS_PN = "1";
"2":   PN = "2"  !CDS_PN = "2";
BODY = "Q_CAP_DIFFBUS","I238": #LOCATION = "C1568" !CDS_LOCATION = "C1568" &SEC = "1" #&CDS_SEC = "1";
"1":   PN = "1"  !CDS_PN = "1";
"2":   PN = "2"  !CDS_PN = "2";
BODY = "Q_CAP_DIFFBUS","I239": #LOCATION = "C47" !CDS_LOCATION = "C47" &SEC = "1" #&CDS_SEC = "1";
"1":   PN = "1"  !CDS_PN = "1";
"2":   PN = "2"  !CDS_PN = "2";
BODY = "Q_CAP_DIFFBUS","I240": #LOCATION = "C1566" !CDS_LOCATION = "C1566" &SEC = "1" #&CDS_SEC = "1";
"1":   PN = "1"  !CDS_PN = "1";
"2":   PN = "2"  !CDS_PN = "2";
BODY = "Q_CAP_DIFFBUS","I241": #LOCATION = "C1565" !CDS_LOCATION = "C1565" &SEC = "1" #&CDS_SEC = "1";
"1":   PN = "1"  !CDS_PN = "1";
"2":   PN = "2"  !CDS_PN = "2";
BODY = "Q_CAP_DIFFBUS","I242": #LOCATION = "C46" !CDS_LOCATION = "C46" &SEC = "1" #&CDS_SEC = "1";
"1":   PN = "1"  !CDS_PN = "1";
"2":   PN = "2"  !CDS_PN = "2";
BODY = "Q_CAP_DIFFBUS","I259": #LOCATION = "C44" !CDS_LOCATION = "C44" &SEC = "1" #&CDS_SEC = "1";
"1":   PN = "1"  !CDS_PN = "1";
"2":   PN = "2"  !CDS_PN = "2";
BODY = "Q_CAP_DIFFBUS","I260": #LOCATION = "C1794" !CDS_LOCATION = "C1794" &SEC = "1" #&CDS_SEC = "1";
"1":   PN = "1"  !CDS_PN = "1";
"2":   PN = "2"  !CDS_PN = "2";
BODY = "Q_CAP_DIFFBUS","I261": #LOCATION = "C1793" !CDS_LOCATION = "C1793" &SEC = "1" #&CDS_SEC = "1";
"1":   PN = "1"  !CDS_PN = "1";
"2":   PN = "2"  !CDS_PN = "2";
BODY = "Q_CAP_DIFFBUS","I262": #LOCATION = "C1560" !CDS_LOCATION = "C1560" &SEC = "1" #&CDS_SEC = "1";
"1":   PN = "1"  !CDS_PN = "1";
"2":   PN = "2"  !CDS_PN = "2";
BODY = "Q_CAP_DIFFBUS","I263": #LOCATION = "C1559" !CDS_LOCATION = "C1559" &SEC = "1" #&CDS_SEC = "1";
"1":   PN = "1"  !CDS_PN = "1";
"2":   PN = "2"  !CDS_PN = "2";
BODY = "Q_CAP_DIFFBUS","I264": #LOCATION = "C1558" !CDS_LOCATION = "C1558" &SEC = "1" #&CDS_SEC = "1";
"1":   PN = "1"  !CDS_PN = "1";
"2":   PN = "2"  !CDS_PN = "2";
BODY = "Q_CAP_DIFFBUS","I265": #LOCATION = "C1556" !CDS_LOCATION = "C1556" &SEC = "1" #&CDS_SEC = "1";
"1":   PN = "1"  !CDS_PN = "1";
"2":   PN = "2"  !CDS_PN = "2";
BODY = "Q_CAP_DIFFBUS","I266": #LOCATION = "C1557" !CDS_LOCATION = "C1557" &SEC = "1" #&CDS_SEC = "1";
"1":   PN = "1"  !CDS_PN = "1";
"2":   PN = "2"  !CDS_PN = "2";
BODY = "Q_CAP_DIFFBUS","I267": #LOCATION = "C1555" !CDS_LOCATION = "C1555" &SEC = "1" #&CDS_SEC = "1";
"1":   PN = "1"  !CDS_PN = "1";
"2":   PN = "2"  !CDS_PN = "2";
BODY = "Q_CAP_DIFFBUS","I268": #LOCATION = "C41" !CDS_LOCATION = "C41" &SEC = "1" #&CDS_SEC = "1";
"1":   PN = "1"  !CDS_PN = "1";
"2":   PN = "2"  !CDS_PN = "2";
BODY = "Q_CAP_DIFFBUS","I269": #LOCATION = "C1553" !CDS_LOCATION = "C1553" &SEC = "1" #&CDS_SEC = "1";
"1":   PN = "1"  !CDS_PN = "1";
"2":   PN = "2"  !CDS_PN = "2";
BODY = "Q_CAP_DIFFBUS","I270": #LOCATION = "C1552" !CDS_LOCATION = "C1552" &SEC = "1" #&CDS_SEC = "1";
"1":   PN = "1"  !CDS_PN = "1";
"2":   PN = "2"  !CDS_PN = "2";
BODY = "Q_CAP_DIFFBUS","I271": #LOCATION = "C1792" !CDS_LOCATION = "C1792" &SEC = "1" #&CDS_SEC = "1";
"1":   PN = "1"  !CDS_PN = "1";
"2":   PN = "2"  !CDS_PN = "2";
BODY = "Q_CAP_DIFFBUS","I272": #LOCATION = "C1550" !CDS_LOCATION = "C1550" &SEC = "1" #&CDS_SEC = "1";
"1":   PN = "1"  !CDS_PN = "1";
"2":   PN = "2"  !CDS_PN = "2";
BODY = "Q_CAP_DIFFBUS","I273": #LOCATION = "C1548" !CDS_LOCATION = "C1548" &SEC = "1" #&CDS_SEC = "1";
"1":   PN = "1"  !CDS_PN = "1";
"2":   PN = "2"  !CDS_PN = "2";
BODY = "Q_CAP_DIFFBUS","I274": #LOCATION = "C1549" !CDS_LOCATION = "C1549" &SEC = "1" #&CDS_SEC = "1";
"1":   PN = "1"  !CDS_PN = "1";
"2":   PN = "2"  !CDS_PN = "2";
BODY = "Q_CAP_DIFFBUS","I311": #LOCATION = "C1577" !CDS_LOCATION = "C1577" &SEC = "1" #&CDS_SEC = "1";
"1":   PN = "1"  !CDS_PN = "1";
"2":   PN = "2"  !CDS_PN = "2";
BODY = "Q_CAP_DIFFBUS","I312": #LOCATION = "C1576" !CDS_LOCATION = "C1576" &SEC = "1" #&CDS_SEC = "1";
"1":   PN = "1"  !CDS_PN = "1";
"2":   PN = "2"  !CDS_PN = "2";
BODY = "Q_CAP_DIFFBUS","I333": #LOCATION = "C836" !CDS_LOCATION = "C836" &SEC = "1" #&CDS_SEC = "1";
"1":   PN = "1"  !CDS_PN = "1";
"2":   PN = "2"  !CDS_PN = "2";
BODY = "Q_CAP_DIFFBUS","I334": #LOCATION = "C837" !CDS_LOCATION = "C837" &SEC = "1" #&CDS_SEC = "1";
"1":   PN = "1"  !CDS_PN = "1";
"2":   PN = "2"  !CDS_PN = "2";
BODY = "Q_CAP_DIFFBUS","I335": #LOCATION = "C834" !CDS_LOCATION = "C834" &SEC = "1" #&CDS_SEC = "1";
"1":   PN = "1"  !CDS_PN = "1";
"2":   PN = "2"  !CDS_PN = "2";
BODY = "Q_CAP_DIFFBUS","I336": #LOCATION = "C835" !CDS_LOCATION = "C835" &SEC = "1" #&CDS_SEC = "1";
"1":   PN = "1"  !CDS_PN = "1";
"2":   PN = "2"  !CDS_PN = "2";
BODY = "Q_CAP_DIFFBUS","I337": #LOCATION = "C831" !CDS_LOCATION = "C831" &SEC = "1" #&CDS_SEC = "1";
"1":   PN = "1"  !CDS_PN = "1";
"2":   PN = "2"  !CDS_PN = "2";
BODY = "Q_CAP_DIFFBUS","I338": #LOCATION = "C832" !CDS_LOCATION = "C832" &SEC = "1" #&CDS_SEC = "1";
"1":   PN = "1"  !CDS_PN = "1";
"2":   PN = "2"  !CDS_PN = "2";
BODY = "Q_CAP_DIFFBUS","I339": #LOCATION = "C833" !CDS_LOCATION = "C833" &SEC = "1" #&CDS_SEC = "1";
"1":   PN = "1"  !CDS_PN = "1";
"2":   PN = "2"  !CDS_PN = "2";
BODY = "Q_CAP_DIFFBUS","I340": #LOCATION = "C828" !CDS_LOCATION = "C828" &SEC = "1" #&CDS_SEC = "1";
"1":   PN = "1"  !CDS_PN = "1";
"2":   PN = "2"  !CDS_PN = "2";
BODY = "Q_CAP_DIFFBUS","I341": #LOCATION = "C830" !CDS_LOCATION = "C830" &SEC = "1" #&CDS_SEC = "1";
"1":   PN = "1"  !CDS_PN = "1";
"2":   PN = "2"  !CDS_PN = "2";
BODY = "Q_CAP_DIFFBUS","I342": #LOCATION = "C829" !CDS_LOCATION = "C829" &SEC = "1" #&CDS_SEC = "1";
"1":   PN = "1"  !CDS_PN = "1";
"2":   PN = "2"  !CDS_PN = "2";
BODY = "Q_CAP_DIFFBUS","I343": #LOCATION = "C827" !CDS_LOCATION = "C827" &SEC = "1" #&CDS_SEC = "1";
"1":   PN = "1"  !CDS_PN = "1";
"2":   PN = "2"  !CDS_PN = "2";
BODY = "Q_CAP_DIFFBUS","I344": #LOCATION = "C826" !CDS_LOCATION = "C826" &SEC = "1" #&CDS_SEC = "1";
"1":   PN = "1"  !CDS_PN = "1";
"2":   PN = "2"  !CDS_PN = "2";
BODY = "Q_CAP_DIFFBUS","I345": #LOCATION = "C822" !CDS_LOCATION = "C822" &SEC = "1" #&CDS_SEC = "1";
"1":   PN = "1"  !CDS_PN = "1";
"2":   PN = "2"  !CDS_PN = "2";
BODY = "Q_CAP_DIFFBUS","I346": #LOCATION = "C823" !CDS_LOCATION = "C823" &SEC = "1" #&CDS_SEC = "1";
"1":   PN = "1"  !CDS_PN = "1";
"2":   PN = "2"  !CDS_PN = "2";
BODY = "Q_CAP_DIFFBUS","I363": #LOCATION = "C820" !CDS_LOCATION = "C820" &SEC = "1" #&CDS_SEC = "1";
"1":   PN = "1"  !CDS_PN = "1";
"2":   PN = "2"  !CDS_PN = "2";
BODY = "Q_CAP_DIFFBUS","I364": #LOCATION = "C821" !CDS_LOCATION = "C821" &SEC = "1" #&CDS_SEC = "1";
"1":   PN = "1"  !CDS_PN = "1";
"2":   PN = "2"  !CDS_PN = "2";
BODY = "Q_CAP_DIFFBUS","I365": #LOCATION = "C818" !CDS_LOCATION = "C818" &SEC = "1" #&CDS_SEC = "1";
"1":   PN = "1"  !CDS_PN = "1";
"2":   PN = "2"  !CDS_PN = "2";
BODY = "Q_CAP_DIFFBUS","I366": #LOCATION = "C819" !CDS_LOCATION = "C819" &SEC = "1" #&CDS_SEC = "1";
"1":   PN = "1"  !CDS_PN = "1";
"2":   PN = "2"  !CDS_PN = "2";
BODY = "Q_CAP_DIFFBUS","I367": #LOCATION = "C817" !CDS_LOCATION = "C817" &SEC = "1" #&CDS_SEC = "1";
"1":   PN = "1"  !CDS_PN = "1";
"2":   PN = "2"  !CDS_PN = "2";
BODY = "Q_CAP_DIFFBUS","I368": #LOCATION = "C816" !CDS_LOCATION = "C816" &SEC = "1" #&CDS_SEC = "1";
"1":   PN = "1"  !CDS_PN = "1";
"2":   PN = "2"  !CDS_PN = "2";
BODY = "Q_CAP_DIFFBUS","I369": #LOCATION = "C815" !CDS_LOCATION = "C815" &SEC = "1" #&CDS_SEC = "1";
"1":   PN = "1"  !CDS_PN = "1";
"2":   PN = "2"  !CDS_PN = "2";
BODY = "Q_CAP_DIFFBUS","I370": #LOCATION = "C814" !CDS_LOCATION = "C814" &SEC = "1" #&CDS_SEC = "1";
"1":   PN = "1"  !CDS_PN = "1";
"2":   PN = "2"  !CDS_PN = "2";
BODY = "Q_CAP_DIFFBUS","I371": #LOCATION = "C812" !CDS_LOCATION = "C812" &SEC = "1" #&CDS_SEC = "1";
"1":   PN = "1"  !CDS_PN = "1";
"2":   PN = "2"  !CDS_PN = "2";
BODY = "Q_CAP_DIFFBUS","I372": #LOCATION = "C813" !CDS_LOCATION = "C813" &SEC = "1" #&CDS_SEC = "1";
"1":   PN = "1"  !CDS_PN = "1";
"2":   PN = "2"  !CDS_PN = "2";
BODY = "Q_CAP_DIFFBUS","I373": #LOCATION = "C811" !CDS_LOCATION = "C811" &SEC = "1" #&CDS_SEC = "1";
"1":   PN = "1"  !CDS_PN = "1";
"2":   PN = "2"  !CDS_PN = "2";
BODY = "Q_CAP_DIFFBUS","I374": #LOCATION = "C810" !CDS_LOCATION = "C810" &SEC = "1" #&CDS_SEC = "1";
"1":   PN = "1"  !CDS_PN = "1";
"2":   PN = "2"  !CDS_PN = "2";
BODY = "Q_CAP_DIFFBUS","I375": #LOCATION = "C809" !CDS_LOCATION = "C809" &SEC = "1" #&CDS_SEC = "1";
"1":   PN = "1"  !CDS_PN = "1";
"2":   PN = "2"  !CDS_PN = "2";
BODY = "Q_CAP_DIFFBUS","I376": #LOCATION = "C808" !CDS_LOCATION = "C808" &SEC = "1" #&CDS_SEC = "1";
"1":   PN = "1"  !CDS_PN = "1";
"2":   PN = "2"  !CDS_PN = "2";
BODY = "Q_CAP_DIFFBUS","I377": #LOCATION = "C806" !CDS_LOCATION = "C806" &SEC = "1" #&CDS_SEC = "1";
"1":   PN = "1"  !CDS_PN = "1";
"2":   PN = "2"  !CDS_PN = "2";
BODY = "Q_CAP_DIFFBUS","I378": #LOCATION = "C807" !CDS_LOCATION = "C807" &SEC = "1" #&CDS_SEC = "1";
"1":   PN = "1"  !CDS_PN = "1";
"2":   PN = "2"  !CDS_PN = "2";
BODY = "Q_CAP_DIFFBUS","I415": #LOCATION = "C825" !CDS_LOCATION = "C825" &SEC = "1" #&CDS_SEC = "1";
"1":   PN = "1"  !CDS_PN = "1";
"2":   PN = "2"  !CDS_PN = "2";
BODY = "Q_CAP_DIFFBUS","I416": #LOCATION = "C824" !CDS_LOCATION = "C824" &SEC = "1" #&CDS_SEC = "1";
"1":   PN = "1"  !CDS_PN = "1";
"2":   PN = "2"  !CDS_PN = "2";
DRAWING = "@t6g_mb_lib.t6g(sch_1):page354";
BODY = "Q_CAP_DIFFBUS","I122": #LOCATION = "C773" !CDS_LOCATION = "C773" &SEC = "1" #&CDS_SEC = "1";
"1":   PN = "1"  !CDS_PN = "1";
"2":   PN = "2"  !CDS_PN = "2";
BODY = "Q_CAP_DIFFBUS","I123": #LOCATION = "C772" !CDS_LOCATION = "C772" &SEC = "1" #&CDS_SEC = "1";
"1":   PN = "1"  !CDS_PN = "1";
"2":   PN = "2"  !CDS_PN = "2";
BODY = "Q_CAP_DIFFBUS","I124": #LOCATION = "C771" !CDS_LOCATION = "C771" &SEC = "1" #&CDS_SEC = "1";
"1":   PN = "1"  !CDS_PN = "1";
"2":   PN = "2"  !CDS_PN = "2";
BODY = "Q_CAP_DIFFBUS","I125": #LOCATION = "C770" !CDS_LOCATION = "C770" &SEC = "1" #&CDS_SEC = "1";
"1":   PN = "1"  !CDS_PN = "1";
"2":   PN = "2"  !CDS_PN = "2";
BODY = "Q_CAP_DIFFBUS","I126": #LOCATION = "C769" !CDS_LOCATION = "C769" &SEC = "1" #&CDS_SEC = "1";
"1":   PN = "1"  !CDS_PN = "1";
"2":   PN = "2"  !CDS_PN = "2";
BODY = "Q_CAP_DIFFBUS","I127": #LOCATION = "C768" !CDS_LOCATION = "C768" &SEC = "1" #&CDS_SEC = "1";
"1":   PN = "1"  !CDS_PN = "1";
"2":   PN = "2"  !CDS_PN = "2";
BODY = "Q_CAP_DIFFBUS","I128": #LOCATION = "C767" !CDS_LOCATION = "C767" &SEC = "1" #&CDS_SEC = "1";
"1":   PN = "1"  !CDS_PN = "1";
"2":   PN = "2"  !CDS_PN = "2";
BODY = "Q_CAP_DIFFBUS","I129": #LOCATION = "C766" !CDS_LOCATION = "C766" &SEC = "1" #&CDS_SEC = "1";
"1":   PN = "1"  !CDS_PN = "1";
"2":   PN = "2"  !CDS_PN = "2";
BODY = "Q_CAP_DIFFBUS","I130": #LOCATION = "C764" !CDS_LOCATION = "C764" &SEC = "1" #&CDS_SEC = "1";
"1":   PN = "1"  !CDS_PN = "1";
"2":   PN = "2"  !CDS_PN = "2";
BODY = "Q_CAP_DIFFBUS","I131": #LOCATION = "C765" !CDS_LOCATION = "C765" &SEC = "1" #&CDS_SEC = "1";
"1":   PN = "1"  !CDS_PN = "1";
"2":   PN = "2"  !CDS_PN = "2";
BODY = "Q_CAP_DIFFBUS","I135": #LOCATION = "C763" !CDS_LOCATION = "C763" &SEC = "1" #&CDS_SEC = "1";
"1":   PN = "1"  !CDS_PN = "1";
"2":   PN = "2"  !CDS_PN = "2";
BODY = "Q_CAP_DIFFBUS","I136": #LOCATION = "C762" !CDS_LOCATION = "C762" &SEC = "1" #&CDS_SEC = "1";
"1":   PN = "1"  !CDS_PN = "1";
"2":   PN = "2"  !CDS_PN = "2";
BODY = "Q_CAP_DIFFBUS","I137": #LOCATION = "C761" !CDS_LOCATION = "C761" &SEC = "1" #&CDS_SEC = "1";
"1":   PN = "1"  !CDS_PN = "1";
"2":   PN = "2"  !CDS_PN = "2";
BODY = "Q_CAP_DIFFBUS","I138": #LOCATION = "C760" !CDS_LOCATION = "C760" &SEC = "1" #&CDS_SEC = "1";
"1":   PN = "1"  !CDS_PN = "1";
"2":   PN = "2"  !CDS_PN = "2";
BODY = "Q_CAP_DIFFBUS","I139": #LOCATION = "C759" !CDS_LOCATION = "C759" &SEC = "1" #&CDS_SEC = "1";
"1":   PN = "1"  !CDS_PN = "1";
"2":   PN = "2"  !CDS_PN = "2";
BODY = "Q_CAP_DIFFBUS","I140": #LOCATION = "C758" !CDS_LOCATION = "C758" &SEC = "1" #&CDS_SEC = "1";
"1":   PN = "1"  !CDS_PN = "1";
"2":   PN = "2"  !CDS_PN = "2";
BODY = "Q_CAP_DIFFBUS","I154": #LOCATION = "C756" !CDS_LOCATION = "C756" &SEC = "1" #&CDS_SEC = "1";
"1":   PN = "1"  !CDS_PN = "1";
"2":   PN = "2"  !CDS_PN = "2";
BODY = "Q_CAP_DIFFBUS","I155": #LOCATION = "C757" !CDS_LOCATION = "C757" &SEC = "1" #&CDS_SEC = "1";
"1":   PN = "1"  !CDS_PN = "1";
"2":   PN = "2"  !CDS_PN = "2";
BODY = "Q_CAP_DIFFBUS","I156": #LOCATION = "C755" !CDS_LOCATION = "C755" &SEC = "1" #&CDS_SEC = "1";
"1":   PN = "1"  !CDS_PN = "1";
"2":   PN = "2"  !CDS_PN = "2";
BODY = "Q_CAP_DIFFBUS","I157": #LOCATION = "C754" !CDS_LOCATION = "C754" &SEC = "1" #&CDS_SEC = "1";
"1":   PN = "1"  !CDS_PN = "1";
"2":   PN = "2"  !CDS_PN = "2";
BODY = "Q_CAP_DIFFBUS","I158": #LOCATION = "C753" !CDS_LOCATION = "C753" &SEC = "1" #&CDS_SEC = "1";
"1":   PN = "1"  !CDS_PN = "1";
"2":   PN = "2"  !CDS_PN = "2";
BODY = "Q_CAP_DIFFBUS","I159": #LOCATION = "C752" !CDS_LOCATION = "C752" &SEC = "1" #&CDS_SEC = "1";
"1":   PN = "1"  !CDS_PN = "1";
"2":   PN = "2"  !CDS_PN = "2";
BODY = "Q_CAP_DIFFBUS","I160": #LOCATION = "C750" !CDS_LOCATION = "C750" &SEC = "1" #&CDS_SEC = "1";
"1":   PN = "1"  !CDS_PN = "1";
"2":   PN = "2"  !CDS_PN = "2";
BODY = "Q_CAP_DIFFBUS","I161": #LOCATION = "C751" !CDS_LOCATION = "C751" &SEC = "1" #&CDS_SEC = "1";
"1":   PN = "1"  !CDS_PN = "1";
"2":   PN = "2"  !CDS_PN = "2";
BODY = "Q_CAP_DIFFBUS","I162": #LOCATION = "C749" !CDS_LOCATION = "C749" &SEC = "1" #&CDS_SEC = "1";
"1":   PN = "1"  !CDS_PN = "1";
"2":   PN = "2"  !CDS_PN = "2";
BODY = "Q_CAP_DIFFBUS","I163": #LOCATION = "C748" !CDS_LOCATION = "C748" &SEC = "1" #&CDS_SEC = "1";
"1":   PN = "1"  !CDS_PN = "1";
"2":   PN = "2"  !CDS_PN = "2";
BODY = "Q_CAP_DIFFBUS","I167": #LOCATION = "C747" !CDS_LOCATION = "C747" &SEC = "1" #&CDS_SEC = "1";
"1":   PN = "1"  !CDS_PN = "1";
"2":   PN = "2"  !CDS_PN = "2";
BODY = "Q_CAP_DIFFBUS","I168": #LOCATION = "C746" !CDS_LOCATION = "C746" &SEC = "1" #&CDS_SEC = "1";
"1":   PN = "1"  !CDS_PN = "1";
"2":   PN = "2"  !CDS_PN = "2";
BODY = "Q_CAP_DIFFBUS","I169": #LOCATION = "C745" !CDS_LOCATION = "C745" &SEC = "1" #&CDS_SEC = "1";
"1":   PN = "1"  !CDS_PN = "1";
"2":   PN = "2"  !CDS_PN = "2";
BODY = "Q_CAP_DIFFBUS","I170": #LOCATION = "C744" !CDS_LOCATION = "C744" &SEC = "1" #&CDS_SEC = "1";
"1":   PN = "1"  !CDS_PN = "1";
"2":   PN = "2"  !CDS_PN = "2";
BODY = "Q_CAP_DIFFBUS","I171": #LOCATION = "C743" !CDS_LOCATION = "C743" &SEC = "1" #&CDS_SEC = "1";
"1":   PN = "1"  !CDS_PN = "1";
"2":   PN = "2"  !CDS_PN = "2";
BODY = "Q_CAP_DIFFBUS","I172": #LOCATION = "C742" !CDS_LOCATION = "C742" &SEC = "1" #&CDS_SEC = "1";
"1":   PN = "1"  !CDS_PN = "1";
"2":   PN = "2"  !CDS_PN = "2";
BODY = "Q_CAP_DIFFBUS","I229": #LOCATION = "C740" !CDS_LOCATION = "C740" &SEC = "1" #&CDS_SEC = "1";
"1":   PN = "1"  !CDS_PN = "1";
"2":   PN = "2"  !CDS_PN = "2";
BODY = "Q_CAP_DIFFBUS","I230": #LOCATION = "C741" !CDS_LOCATION = "C741" &SEC = "1" #&CDS_SEC = "1";
"1":   PN = "1"  !CDS_PN = "1";
"2":   PN = "2"  !CDS_PN = "2";
BODY = "Q_CAP_DIFFBUS","I231": #LOCATION = "C739" !CDS_LOCATION = "C739" &SEC = "1" #&CDS_SEC = "1";
"1":   PN = "1"  !CDS_PN = "1";
"2":   PN = "2"  !CDS_PN = "2";
BODY = "Q_CAP_DIFFBUS","I232": #LOCATION = "C738" !CDS_LOCATION = "C738" &SEC = "1" #&CDS_SEC = "1";
"1":   PN = "1"  !CDS_PN = "1";
"2":   PN = "2"  !CDS_PN = "2";
BODY = "Q_CAP_DIFFBUS","I233": #LOCATION = "C737" !CDS_LOCATION = "C737" &SEC = "1" #&CDS_SEC = "1";
"1":   PN = "1"  !CDS_PN = "1";
"2":   PN = "2"  !CDS_PN = "2";
BODY = "Q_CAP_DIFFBUS","I234": #LOCATION = "C736" !CDS_LOCATION = "C736" &SEC = "1" #&CDS_SEC = "1";
"1":   PN = "1"  !CDS_PN = "1";
"2":   PN = "2"  !CDS_PN = "2";
BODY = "Q_CAP_DIFFBUS","I235": #LOCATION = "C734" !CDS_LOCATION = "C734" &SEC = "1" #&CDS_SEC = "1";
"1":   PN = "1"  !CDS_PN = "1";
"2":   PN = "2"  !CDS_PN = "2";
BODY = "Q_CAP_DIFFBUS","I236": #LOCATION = "C735" !CDS_LOCATION = "C735" &SEC = "1" #&CDS_SEC = "1";
"1":   PN = "1"  !CDS_PN = "1";
"2":   PN = "2"  !CDS_PN = "2";
BODY = "Q_CAP_DIFFBUS","I237": #LOCATION = "C733" !CDS_LOCATION = "C733" &SEC = "1" #&CDS_SEC = "1";
"1":   PN = "1"  !CDS_PN = "1";
"2":   PN = "2"  !CDS_PN = "2";
BODY = "Q_CAP_DIFFBUS","I246": #LOCATION = "C732" !CDS_LOCATION = "C732" &SEC = "1" #&CDS_SEC = "1";
"1":   PN = "1"  !CDS_PN = "1";
"2":   PN = "2"  !CDS_PN = "2";
BODY = "Q_CAP_DIFFBUS","I247": #LOCATION = "C731" !CDS_LOCATION = "C731" &SEC = "1" #&CDS_SEC = "1";
"1":   PN = "1"  !CDS_PN = "1";
"2":   PN = "2"  !CDS_PN = "2";
BODY = "Q_CAP_DIFFBUS","I248": #LOCATION = "C730" !CDS_LOCATION = "C730" &SEC = "1" #&CDS_SEC = "1";
"1":   PN = "1"  !CDS_PN = "1";
"2":   PN = "2"  !CDS_PN = "2";
BODY = "Q_CAP_DIFFBUS","I249": #LOCATION = "C729" !CDS_LOCATION = "C729" &SEC = "1" #&CDS_SEC = "1";
"1":   PN = "1"  !CDS_PN = "1";
"2":   PN = "2"  !CDS_PN = "2";
BODY = "Q_CAP_DIFFBUS","I250": #LOCATION = "C728" !CDS_LOCATION = "C728" &SEC = "1" #&CDS_SEC = "1";
"1":   PN = "1"  !CDS_PN = "1";
"2":   PN = "2"  !CDS_PN = "2";
BODY = "Q_CAP_DIFFBUS","I251": #LOCATION = "C727" !CDS_LOCATION = "C727" &SEC = "1" #&CDS_SEC = "1";
"1":   PN = "1"  !CDS_PN = "1";
"2":   PN = "2"  !CDS_PN = "2";
BODY = "Q_CAP_DIFFBUS","I274": #LOCATION = "C725" !CDS_LOCATION = "C725" &SEC = "1" #&CDS_SEC = "1";
"1":   PN = "1"  !CDS_PN = "1";
"2":   PN = "2"  !CDS_PN = "2";
BODY = "Q_CAP_DIFFBUS","I275": #LOCATION = "C724" !CDS_LOCATION = "C724" &SEC = "1" #&CDS_SEC = "1";
"1":   PN = "1"  !CDS_PN = "1";
"2":   PN = "2"  !CDS_PN = "2";
BODY = "Q_CAP_DIFFBUS","I276": #LOCATION = "C722" !CDS_LOCATION = "C722" &SEC = "1" #&CDS_SEC = "1";
"1":   PN = "1"  !CDS_PN = "1";
"2":   PN = "2"  !CDS_PN = "2";
BODY = "Q_CAP_DIFFBUS","I277": #LOCATION = "C723" !CDS_LOCATION = "C723" &SEC = "1" #&CDS_SEC = "1";
"1":   PN = "1"  !CDS_PN = "1";
"2":   PN = "2"  !CDS_PN = "2";
BODY = "Q_CAP_DIFFBUS","I278": #LOCATION = "C721" !CDS_LOCATION = "C721" &SEC = "1" #&CDS_SEC = "1";
"1":   PN = "1"  !CDS_PN = "1";
"2":   PN = "2"  !CDS_PN = "2";
BODY = "Q_CAP_DIFFBUS","I279": #LOCATION = "C720" !CDS_LOCATION = "C720" &SEC = "1" #&CDS_SEC = "1";
"1":   PN = "1"  !CDS_PN = "1";
"2":   PN = "2"  !CDS_PN = "2";
BODY = "Q_CAP_DIFFBUS","I280": #LOCATION = "C719" !CDS_LOCATION = "C719" &SEC = "1" #&CDS_SEC = "1";
"1":   PN = "1"  !CDS_PN = "1";
"2":   PN = "2"  !CDS_PN = "2";
BODY = "Q_CAP_DIFFBUS","I281": #LOCATION = "C718" !CDS_LOCATION = "C718" &SEC = "1" #&CDS_SEC = "1";
"1":   PN = "1"  !CDS_PN = "1";
"2":   PN = "2"  !CDS_PN = "2";
BODY = "Q_CAP_DIFFBUS","I282": #LOCATION = "C717" !CDS_LOCATION = "C717" &SEC = "1" #&CDS_SEC = "1";
"1":   PN = "1"  !CDS_PN = "1";
"2":   PN = "2"  !CDS_PN = "2";
BODY = "Q_CAP_DIFFBUS","I283": #LOCATION = "C716" !CDS_LOCATION = "C716" &SEC = "1" #&CDS_SEC = "1";
"1":   PN = "1"  !CDS_PN = "1";
"2":   PN = "2"  !CDS_PN = "2";
BODY = "Q_CAP_DIFFBUS","I294": #LOCATION = "C715" !CDS_LOCATION = "C715" &SEC = "1" #&CDS_SEC = "1";
"1":   PN = "1"  !CDS_PN = "1";
"2":   PN = "2"  !CDS_PN = "2";
BODY = "Q_CAP_DIFFBUS","I295": #LOCATION = "C714" !CDS_LOCATION = "C714" &SEC = "1" #&CDS_SEC = "1";
"1":   PN = "1"  !CDS_PN = "1";
"2":   PN = "2"  !CDS_PN = "2";
BODY = "Q_CAP_DIFFBUS","I296": #LOCATION = "C712" !CDS_LOCATION = "C712" &SEC = "1" #&CDS_SEC = "1";
"1":   PN = "1"  !CDS_PN = "1";
"2":   PN = "2"  !CDS_PN = "2";
BODY = "Q_CAP_DIFFBUS","I297": #LOCATION = "C713" !CDS_LOCATION = "C713" &SEC = "1" #&CDS_SEC = "1";
"1":   PN = "1"  !CDS_PN = "1";
"2":   PN = "2"  !CDS_PN = "2";
BODY = "Q_CAP_DIFFBUS","I298": #LOCATION = "C711" !CDS_LOCATION = "C711" &SEC = "1" #&CDS_SEC = "1";
"1":   PN = "1"  !CDS_PN = "1";
"2":   PN = "2"  !CDS_PN = "2";
BODY = "Q_CAP_DIFFBUS","I299": #LOCATION = "C710" !CDS_LOCATION = "C710" &SEC = "1" #&CDS_SEC = "1";
"1":   PN = "1"  !CDS_PN = "1";
"2":   PN = "2"  !CDS_PN = "2";
BODY = "Q_CAP_DIFFBUS","I312": #LOCATION = "C726" !CDS_LOCATION = "C726" &SEC = "1" #&CDS_SEC = "1";
"1":   PN = "1"  !CDS_PN = "1";
"2":   PN = "2"  !CDS_PN = "2";
DRAWING = "@t6g_mb_lib.t6g(sch_1):page273";
BODY = "Q_RES","I4": #LOCATION = "R333" !CDS_LOCATION = "R333" &SEC = "1" #&CDS_SEC = "1";
"A":   PN = "1"  !CDS_PN = "1";
"B":   PN = "2"  !CDS_PN = "2";
BODY = "MOSFET_NCH_DUAL","I9": #LOCATION = "Q37" !CDS_LOCATION = "Q37" &SEC = "1" #&CDS_SEC = "1";
"D1":   PN = "6"  !CDS_PN = "6";
"G1":   PN = "2"  !CDS_PN = "2";
"S1":   PN = "1"  !CDS_PN = "1";
BODY = "Q_RES","I10": #LOCATION = "R336" !CDS_LOCATION = "R336" &SEC = "1" #&CDS_SEC = "1";
"A":   PN = "1"  !CDS_PN = "1";
"B":   PN = "2"  !CDS_PN = "2";
BODY = "MOSFET_NCH_DUAL","I14": #LOCATION = "Q37" !CDS_LOCATION = "Q37" &SEC = "2" #&CDS_SEC = "2";
"D2":   PN = "3"  !CDS_PN = "3";
"G2":   PN = "5"  !CDS_PN = "5";
"S2":   PN = "4"  !CDS_PN = "4";
BODY = "Q_RES","I22": #LOCATION = "R1654" !CDS_LOCATION = "R1654" &SEC = "1" #&CDS_SEC = "1";
"A":   PN = "1"  !CDS_PN = "1";
"B":   PN = "2"  !CDS_PN = "2";
BODY = "BAT547F","I27": #LOCATION = "D1" !CDS_LOCATION = "D1" &SEC = "1" #&CDS_SEC = "1";
"1":   PN = "1"  !CDS_PN = "1";
"3":   PN = "3"  !CDS_PN = "3";
BODY = "Q_CAP","I41": #LOCATION = "C1227" !CDS_LOCATION = "C1227" &SEC = "1" #&CDS_SEC = "1";
"A":   PN = "1"  !CDS_PN = "1";
"B":   PN = "2"  !CDS_PN = "2";
BODY = "Q_RES","I45": #LOCATION = "R4638" !CDS_LOCATION = "R4638" &SEC = "1" #&CDS_SEC = "1";
"A":   PN = "1"  !CDS_PN = "1";
"B":   PN = "2"  !CDS_PN = "2";
BODY = "Q_CAP","I48": #LOCATION = "C1332" !CDS_LOCATION = "C1332" &SEC = "1" #&CDS_SEC = "1";
"A":   PN = "1"  !CDS_PN = "1";
"B":   PN = "2"  !CDS_PN = "2";
BODY = "Q_CAP","I49": #LOCATION = "C1333" !CDS_LOCATION = "C1333" &SEC = "1" #&CDS_SEC = "1";
"A":   PN = "1"  !CDS_PN = "1";
"B":   PN = "2"  !CDS_PN = "2";
BODY = "MOSFET_NCH_1D3S","I50": #LOCATION = "Q56" !CDS_LOCATION = "Q56" &SEC = "1" #&CDS_SEC = "1";
"1":   PN = "1"  !CDS_PN = "1";
"2":   PN = "2"  !CDS_PN = "2";
"3":   PN = "3"  !CDS_PN = "3";
"4":   PN = "4"  !CDS_PN = "4";
"5":   PN = "5"  !CDS_PN = "5";
BODY = "Q_CAP","I51": #LOCATION = "C60" !CDS_LOCATION = "C60" &SEC = "1" #&CDS_SEC = "1";
"A":   PN = "1"  !CDS_PN = "1";
"B":   PN = "2"  !CDS_PN = "2";
BODY = "Q_CAP","I61": #LOCATION = "C1340" !CDS_LOCATION = "C1340" &SEC = "1" #&CDS_SEC = "1";
"A":   PN = "1"  !CDS_PN = "1";
"B":   PN = "2"  !CDS_PN = "2";
BODY = "Q_RES","I7": #LOCATION = "R334" !CDS_LOCATION = "R334" &SEC = "1" #&CDS_SEC = "1";
"A":   PN = "1"  !CDS_PN = "1";
"B":   PN = "2"  !CDS_PN = "2";
BODY = "Q_RES","I15": #LOCATION = "R335" !CDS_LOCATION = "R335" &SEC = "1" #&CDS_SEC = "1";
"A":   PN = "1"  !CDS_PN = "1";
"B":   PN = "2"  !CDS_PN = "2";
BODY = "Q_CAP","I18": #LOCATION = "C1042" !CDS_LOCATION = "C1042" &SEC = "1" #&CDS_SEC = "1";
"A":   PN = "1"  !CDS_PN = "1";
"B":   PN = "2"  !CDS_PN = "2";
BODY = "Q_CAP","I19": #LOCATION = "C1170" !CDS_LOCATION = "C1170" &SEC = "1" #&CDS_SEC = "1";
"A":   PN = "1"  !CDS_PN = "1";
"B":   PN = "2"  !CDS_PN = "2";
BODY = "Q_CAP","I20": #LOCATION = "C57" !CDS_LOCATION = "C57" &SEC = "1" #&CDS_SEC = "1";
"A":   PN = "1"  !CDS_PN = "1";
"B":   PN = "2"  !CDS_PN = "2";
BODY = "MOSFET_NCH_1D3S","I23": #LOCATION = "Q57" !CDS_LOCATION = "Q57" &SEC = "1" #&CDS_SEC = "1";
"1":   PN = "1"  !CDS_PN = "1";
"2":   PN = "2"  !CDS_PN = "2";
"3":   PN = "3"  !CDS_PN = "3";
"4":   PN = "4"  !CDS_PN = "4";
"5":   PN = "5"  !CDS_PN = "5";
BODY = "Q_CAP","I38": #LOCATION = "C9226" !CDS_LOCATION = "C9226" &SEC = "1" #&CDS_SEC = "1";
"A":   PN = "1"  !CDS_PN = "1";
"B":   PN = "2"  !CDS_PN = "2";
BODY = "Q_CAP","I43": #LOCATION = "C1331" !CDS_LOCATION = "C1331" &SEC = "1" #&CDS_SEC = "1";
"A":   PN = "1"  !CDS_PN = "1";
"B":   PN = "2"  !CDS_PN = "2";
BODY = "Q_CAP","I59": #LOCATION = "C61" !CDS_LOCATION = "C61" &SEC = "1" #&CDS_SEC = "1";
"A":   PN = "1"  !CDS_PN = "1";
"B":   PN = "2"  !CDS_PN = "2";
BODY = "MOSFET_NCH_GDS_ESD_PROTECTED","I62": #LOCATION = "U324" !CDS_LOCATION = "U324" &SEC = "1" #&CDS_SEC = "1";
"D":   PN = "D"  !CDS_PN = "D";
"G":   PN = "G"  !CDS_PN = "G";
"S":   PN = "S"  !CDS_PN = "S";
BODY = "Q_RES","I74": #LOCATION = "R4639" !CDS_LOCATION = "R4639" &SEC = "1" #&CDS_SEC = "1";
"A":   PN = "1"  !CDS_PN = "1";
"B":   PN = "2"  !CDS_PN = "2";
BODY = "Q_RES","I75": #LOCATION = "R4640" !CDS_LOCATION = "R4640" &SEC = "1" #&CDS_SEC = "1";
"A":   PN = "1"  !CDS_PN = "1";
"B":   PN = "2"  !CDS_PN = "2";
BODY = "Q_RES","I76": #LOCATION = "R4641" !CDS_LOCATION = "R4641" &SEC = "1" #&CDS_SEC = "1";
"A":   PN = "1"  !CDS_PN = "1";
"B":   PN = "2"  !CDS_PN = "2";
BODY = "RT9818C44GV","I77": #LOCATION = "U100" !CDS_LOCATION = "U100" #SEC = "1" !CDS_SEC = "1";
"GND":   PN = "2"  !CDS_PN = "2";
"RESET#":   PN = "1"  !CDS_PN = "1";
"VDD":   PN = "3"  !CDS_PN = "3";
BODY = "Q_CAP","I79": #LOCATION = "C6122" !CDS_LOCATION = "C6122" &SEC = "1" #&CDS_SEC = "1";
"A":   PN = "1"  !CDS_PN = "1";
"B":   PN = "2"  !CDS_PN = "2";
BODY = "Q_RES","I83": #LOCATION = "R479" !CDS_LOCATION = "R479" #SEC = "1" !CDS_SEC = "1";
"A":   PN = "1"  !CDS_PN = "1";
"B":   PN = "2"  !CDS_PN = "2";
BODY = "Q_RES","I84": #LOCATION = "R480" !CDS_LOCATION = "R480" #SEC = "1" !CDS_SEC = "1";
"A":   PN = "1"  !CDS_PN = "1";
"B":   PN = "2"  !CDS_PN = "2";
BODY = "Q_RES","I88": #LOCATION = "R490" !CDS_LOCATION = "R490" #SEC = "1" !CDS_SEC = "1";
"A":   PN = "1"  !CDS_PN = "1";
"B":   PN = "2"  !CDS_PN = "2";
BODY = "Q_RES","I91": #LOCATION = "R6050" !CDS_LOCATION = "R6050" #SEC = "1" !CDS_SEC = "1";
"A":   PN = "1"  !CDS_PN = "1";
"B":   PN = "2"  !CDS_PN = "2";
BODY = "Q_RES","I93": #LOCATION = "R496" !CDS_LOCATION = "R496" &SEC = "1" #&CDS_SEC = "1";
"A":   PN = "1"  !CDS_PN = "1";
"B":   PN = "2"  !CDS_PN = "2";
BODY = "Q_RES","I95": #LOCATION = "R487" !CDS_LOCATION = "R487" #SEC = "1" !CDS_SEC = "1";
"A":   PN = "1"  !CDS_PN = "1";
"B":   PN = "2"  !CDS_PN = "2";
BODY = "Q_RES","I96": #LOCATION = "R482" !CDS_LOCATION = "R482" #SEC = "1" !CDS_SEC = "1";
"A":   PN = "1"  !CDS_PN = "1";
"B":   PN = "2"  !CDS_PN = "2";
BODY = "MOSFET_NCH_DUAL","I97": #LOCATION = "Q1" !CDS_LOCATION = "Q1" #SEC = "1" !CDS_SEC = "1";
"D1":   PN = "6"  !CDS_PN = "6";
"G1":   PN = "2"  !CDS_PN = "2";
"S1":   PN = "1"  !CDS_PN = "1";
BODY = "MOSFET_NCH_DUAL","I98": #LOCATION = "Q1" !CDS_LOCATION = "Q1" #SEC = "2" !CDS_SEC = "2";
"D2":   PN = "3"  !CDS_PN = "3";
"G2":   PN = "5"  !CDS_PN = "5";
"S2":   PN = "4"  !CDS_PN = "4";
BODY = "Q_RES","I99": #LOCATION = "R492" !CDS_LOCATION = "R492" #SEC = "1" !CDS_SEC = "1";
"A":   PN = "1"  !CDS_PN = "1";
"B":   PN = "2"  !CDS_PN = "2";
BODY = "Q_RES","I102": #LOCATION = "R494" !CDS_LOCATION = "R494" #SEC = "1" !CDS_SEC = "1";
"A":   PN = "1"  !CDS_PN = "1";
"B":   PN = "2"  !CDS_PN = "2";
BODY = "Q_RES","I104": #LOCATION = "R552" !CDS_LOCATION = "R552" &SEC = "1" #&CDS_SEC = "1";
"A":   PN = "1"  !CDS_PN = "1";
"B":   PN = "2"  !CDS_PN = "2";
BODY = "MOSFET_NCH_DUAL","I107": #LOCATION = "Q3" !CDS_LOCATION = "Q3" #SEC = "1" !CDS_SEC = "1";
"D1":   PN = "6"  !CDS_PN = "6";
"G1":   PN = "2"  !CDS_PN = "2";
"S1":   PN = "1"  !CDS_PN = "1";
BODY = "MOSFET_NCH_DUAL","I108": #LOCATION = "Q3" !CDS_LOCATION = "Q3" #SEC = "2" !CDS_SEC = "2";
"D2":   PN = "3"  !CDS_PN = "3";
"G2":   PN = "5"  !CDS_PN = "5";
"S2":   PN = "4"  !CDS_PN = "4";
BODY = "Q_RES","I111": #LOCATION = "R554" !CDS_LOCATION = "R554" #SEC = "1" !CDS_SEC = "1";
"A":   PN = "1"  !CDS_PN = "1";
"B":   PN = "2"  !CDS_PN = "2";
BODY = "Q_RES","I113": #LOCATION = "R569" !CDS_LOCATION = "R569" &SEC = "1" #&CDS_SEC = "1";
"A":   PN = "1"  !CDS_PN = "1";
"B":   PN = "2"  !CDS_PN = "2";
BODY = "Q_RES","I114": #LOCATION = "R568" !CDS_LOCATION = "R568" &SEC = "1" #&CDS_SEC = "1";
"A":   PN = "1"  !CDS_PN = "1";
"B":   PN = "2"  !CDS_PN = "2";
BODY = "Q_CAP","I116": #LOCATION = "C29" !CDS_LOCATION = "C29" &SEC = "1" #&CDS_SEC = "1";
"A":   PN = "1"  !CDS_PN = "1";
"B":   PN = "2"  !CDS_PN = "2";
BODY = "Q_RES","I120": #LOCATION = "R1492" !CDS_LOCATION = "R1492" &SEC = "1" #&CDS_SEC = "1";
"A":   PN = "1"  !CDS_PN = "1";
"B":   PN = "2"  !CDS_PN = "2";
BODY = "BSS138DW7F","I123": #LOCATION = "Q27" !CDS_LOCATION = "Q27" &SEC = "1" #&CDS_SEC = "1";
"D1":   PN = "6"  !CDS_PN = "6";
"D2":   PN = "3"  !CDS_PN = "3";
"G1":   PN = "2"  !CDS_PN = "2";
"G2":   PN = "5"  !CDS_PN = "5";
"S1":   PN = "1"  !CDS_PN = "1";
"S2":   PN = "4"  !CDS_PN = "4";
BODY = "Q_RES","I125": #LOCATION = "R1493" !CDS_LOCATION = "R1493" &SEC = "1" #&CDS_SEC = "1";
"A":   PN = "1"  !CDS_PN = "1";
"B":   PN = "2"  !CDS_PN = "2";
BODY = "Q_RES","I130": #LOCATION = "R1362" !CDS_LOCATION = "R1362" &SEC = "1" #&CDS_SEC = "1";
"A":   PN = "1"  !CDS_PN = "1";
"B":   PN = "2"  !CDS_PN = "2";
BODY = "APX80929SAG7","I131": #LOCATION = "U6006" !CDS_LOCATION = "U6006" #SEC = "1" !CDS_SEC = "1";
"GND":   PN = "1"  !CDS_PN = "1";
"RESET_L":   PN = "2"  !CDS_PN = "2";
"VCC":   PN = "3"  !CDS_PN = "3";
BODY = "Q_CAP","I133": #LOCATION = "C6500" !CDS_LOCATION = "C6500" &SEC = "1" #&CDS_SEC = "1";
"A":   PN = "1"  !CDS_PN = "1";
"B":   PN = "2"  !CDS_PN = "2";
BODY = "Q_RES","I136": #LOCATION = "R6500" !CDS_LOCATION = "R6500" #SEC = "1" !CDS_SEC = "1";
"A":   PN = "1"  !CDS_PN = "1";
"B":   PN = "2"  !CDS_PN = "2";
BODY = "Q_RES","I139": #LOCATION = "R6501" !CDS_LOCATION = "R6501" #SEC = "1" !CDS_SEC = "1";
"A":   PN = "1"  !CDS_PN = "1";
"B":   PN = "2"  !CDS_PN = "2";
BODY = "Q_RES","I141": #LOCATION = "R1491" !CDS_LOCATION = "R1491" #SEC = "1" !CDS_SEC = "1";
"A":   PN = "1"  !CDS_PN = "1";
"B":   PN = "2"  !CDS_PN = "2";
DRAWING = "@t6g_mb_lib.t6g(sch_1):page295";
BODY = "ISL28022FRZT","I30": #LOCATION = "U266" !CDS_LOCATION = "U266" #SEC = "1" !CDS_SEC = "1";
"A0":   PN = "2"  !CDS_PN = "2";
"A1":   PN = "1"  !CDS_PN = "1";
"EXT_CLK||INT":   PN = "3"  !CDS_PN = "3";
"GND":   PN = "10"  !CDS_PN = "10";
"NC0":   PN = "6"  !CDS_PN = "6";
"NC1":   PN = "7"  !CDS_PN = "7";
"NC2":   PN = "8"  !CDS_PN = "8";
"NC3":   PN = "14"  !CDS_PN = "14";
"NC4":   PN = "15"  !CDS_PN = "15";
"NC5":   PN = "16"  !CDS_PN = "16";
"SCL|||SMBCLK":   PN = "5"  !CDS_PN = "5";
"SDA||SMBDAT":   PN = "4"  !CDS_PN = "4";
"TH_GND":   PN = "TH"  !CDS_PN = "TH";
"VBUS":   PN = "11"  !CDS_PN = "11";
"VCC":   PN = "9"  !CDS_PN = "9";
"VINM":   PN = "12"  !CDS_PN = "12";
"VINP":   PN = "13"  !CDS_PN = "13";
BODY = "Q_RES","I31": #LOCATION = "R3616" !CDS_LOCATION = "R3616" &SEC = "1" #&CDS_SEC = "1";
"A":   PN = "1"  !CDS_PN = "1";
"B":   PN = "2"  !CDS_PN = "2";
BODY = "Q_CAP","I34": #LOCATION = "C2015" !CDS_LOCATION = "C2015" &SEC = "1" #&CDS_SEC = "1";
"A":   PN = "1"  !CDS_PN = "1";
"B":   PN = "2"  !CDS_PN = "2";
BODY = "Q_RES","I35": #LOCATION = "R3563" !CDS_LOCATION = "R3563" &SEC = "1" #&CDS_SEC = "1";
"A":   PN = "1"  !CDS_PN = "1";
"B":   PN = "2"  !CDS_PN = "2";
BODY = "Q_RES","I40": #LOCATION = "R3617" !CDS_LOCATION = "R3617" &SEC = "1" #&CDS_SEC = "1";
"A":   PN = "1"  !CDS_PN = "1";
"B":   PN = "2"  !CDS_PN = "2";
BODY = "Q_RES","I41": #LOCATION = "R3602" !CDS_LOCATION = "R3602" &SEC = "1" #&CDS_SEC = "1";
"A":   PN = "1"  !CDS_PN = "1";
"B":   PN = "2"  !CDS_PN = "2";
BODY = "Q_RES","I43": #LOCATION = "R3603" !CDS_LOCATION = "R3603" &SEC = "1" #&CDS_SEC = "1";
"A":   PN = "1"  !CDS_PN = "1";
"B":   PN = "2"  !CDS_PN = "2";
BODY = "Q_CAP","I50": #LOCATION = "C2024" !CDS_LOCATION = "C2024" &SEC = "1" #&CDS_SEC = "1";
"A":   PN = "1"  !CDS_PN = "1";
"B":   PN = "2"  !CDS_PN = "2";
BODY = "Q_CAP","I77": #LOCATION = "C2027" !CDS_LOCATION = "C2027" &SEC = "1" #&CDS_SEC = "1";
"A":   PN = "1"  !CDS_PN = "1";
"B":   PN = "2"  !CDS_PN = "2";
BODY = "Q_RES","I88": #LOCATION = "R3628" !CDS_LOCATION = "R3628" &SEC = "1" #&CDS_SEC = "1";
"A":   PN = "1"  !CDS_PN = "1";
"B":   PN = "2"  !CDS_PN = "2";
BODY = "Q_RES","I89": #LOCATION = "R3627" !CDS_LOCATION = "R3627" &SEC = "1" #&CDS_SEC = "1";
"A":   PN = "1"  !CDS_PN = "1";
"B":   PN = "2"  !CDS_PN = "2";
BODY = "Q_RES","I93": #LOCATION = "R3645" !CDS_LOCATION = "R3645" &SEC = "1" #&CDS_SEC = "1";
"A":   PN = "1"  !CDS_PN = "1";
"B":   PN = "2"  !CDS_PN = "2";
BODY = "Q_RES","I122": #LOCATION = "R3752" !CDS_LOCATION = "R3752" &SEC = "1" #&CDS_SEC = "1";
"A":   PN = "1"  !CDS_PN = "1";
"B":   PN = "2"  !CDS_PN = "2";
BODY = "Q_CAP","I125": #LOCATION = "C2067" !CDS_LOCATION = "C2067" &SEC = "1" #&CDS_SEC = "1";
"A":   PN = "1"  !CDS_PN = "1";
"B":   PN = "2"  !CDS_PN = "2";
BODY = "ISL28022FRZT","I129": #LOCATION = "U276" !CDS_LOCATION = "U276" #SEC = "1" !CDS_SEC = "1";
"A0":   PN = "2"  !CDS_PN = "2";
"A1":   PN = "1"  !CDS_PN = "1";
"EXT_CLK||INT":   PN = "3"  !CDS_PN = "3";
"GND":   PN = "10"  !CDS_PN = "10";
"NC0":   PN = "6"  !CDS_PN = "6";
"NC1":   PN = "7"  !CDS_PN = "7";
"NC2":   PN = "8"  !CDS_PN = "8";
"NC3":   PN = "14"  !CDS_PN = "14";
"NC4":   PN = "15"  !CDS_PN = "15";
"NC5":   PN = "16"  !CDS_PN = "16";
"SCL|||SMBCLK":   PN = "5"  !CDS_PN = "5";
"SDA||SMBDAT":   PN = "4"  !CDS_PN = "4";
"TH_GND":   PN = "TH"  !CDS_PN = "TH";
"VBUS":   PN = "11"  !CDS_PN = "11";
"VCC":   PN = "9"  !CDS_PN = "9";
"VINM":   PN = "12"  !CDS_PN = "12";
"VINP":   PN = "13"  !CDS_PN = "13";
BODY = "Q_RES","I132": #LOCATION = "R3758" !CDS_LOCATION = "R3758" &SEC = "1" #&CDS_SEC = "1";
"A":   PN = "1"  !CDS_PN = "1";
"B":   PN = "2"  !CDS_PN = "2";
BODY = "Q_CAP","I133": #LOCATION = "C2071" !CDS_LOCATION = "C2071" &SEC = "1" #&CDS_SEC = "1";
"A":   PN = "1"  !CDS_PN = "1";
"B":   PN = "2"  !CDS_PN = "2";
BODY = "Q_RES","I134": #LOCATION = "R3760" !CDS_LOCATION = "R3760" &SEC = "1" #&CDS_SEC = "1";
"A":   PN = "1"  !CDS_PN = "1";
"B":   PN = "2"  !CDS_PN = "2";
BODY = "Q_RES","I135": #LOCATION = "R3764" !CDS_LOCATION = "R3764" &SEC = "1" #&CDS_SEC = "1";
"A":   PN = "1"  !CDS_PN = "1";
"B":   PN = "2"  !CDS_PN = "2";
BODY = "Q_RES","I136": #LOCATION = "R3763" !CDS_LOCATION = "R3763" &SEC = "1" #&CDS_SEC = "1";
"A":   PN = "1"  !CDS_PN = "1";
"B":   PN = "2"  !CDS_PN = "2";
BODY = "Q_CAP","I142": #LOCATION = "C2069" !CDS_LOCATION = "C2069" &SEC = "1" #&CDS_SEC = "1";
"A":   PN = "1"  !CDS_PN = "1";
"B":   PN = "2"  !CDS_PN = "2";
BODY = "Q_RES","I144": #LOCATION = "R3767" !CDS_LOCATION = "R3767" &SEC = "1" #&CDS_SEC = "1";
"A":   PN = "1"  !CDS_PN = "1";
"B":   PN = "2"  !CDS_PN = "2";
BODY = "Q_RES","I146": #LOCATION = "R3751" !CDS_LOCATION = "R3751" &SEC = "1" #&CDS_SEC = "1";
"A":   PN = "1"  !CDS_PN = "1";
"B":   PN = "2"  !CDS_PN = "2";
BODY = "Q_RES","I149": #LOCATION = "R4093" !CDS_LOCATION = "R4093" &SEC = "1" #&CDS_SEC = "1";
"A":   PN = "1"  !CDS_PN = "1";
"B":   PN = "2"  !CDS_PN = "2";
BODY = "Q_RES","I151": #LOCATION = "R4094" !CDS_LOCATION = "R4094" &SEC = "1" #&CDS_SEC = "1";
"A":   PN = "1"  !CDS_PN = "1";
"B":   PN = "2"  !CDS_PN = "2";
BODY = "Q_RES","I152": #LOCATION = "R3600" !CDS_LOCATION = "R3600" &SEC = "1" #&CDS_SEC = "1";
"A":   PN = "1"  !CDS_PN = "1";
"B":   PN = "2"  !CDS_PN = "2";
BODY = "Q_RES","I153": #LOCATION = "R3601" !CDS_LOCATION = "R3601" &SEC = "1" #&CDS_SEC = "1";
"A":   PN = "1"  !CDS_PN = "1";
"B":   PN = "2"  !CDS_PN = "2";
BODY = "Q_RES","I154": #LOCATION = "R3756" !CDS_LOCATION = "R3756" &SEC = "1" #&CDS_SEC = "1";
"A":   PN = "1"  !CDS_PN = "1";
"B":   PN = "2"  !CDS_PN = "2";
BODY = "Q_RES","I155": #LOCATION = "R3754" !CDS_LOCATION = "R3754" &SEC = "1" #&CDS_SEC = "1";
"A":   PN = "1"  !CDS_PN = "1";
"B":   PN = "2"  !CDS_PN = "2";
DRAWING = "@t6g_mb_lib.t6g(sch_1):page358";
BODY = "Q_RES","I78": #LOCATION = "R2787" !CDS_LOCATION = "R2787" &SEC = "1" #&CDS_SEC = "1";
"A":   PN = "1"  !CDS_PN = "1";
"B":   PN = "2"  !CDS_PN = "2";
BODY = "Q_RES","I79": #LOCATION = "R2786" !CDS_LOCATION = "R2786" &SEC = "1" #&CDS_SEC = "1";
"A":   PN = "1"  !CDS_PN = "1";
"B":   PN = "2"  !CDS_PN = "2";
BODY = "Q_CAP","I81": #LOCATION = "C5232" !CDS_LOCATION = "C5232" &SEC = "1" #&CDS_SEC = "1";
"A":   PN = "1"  !CDS_PN = "1";
"B":   PN = "2"  !CDS_PN = "2";
BODY = "Q_RES","I83": #LOCATION = "R5238" !CDS_LOCATION = "R5238" &SEC = "1" #&CDS_SEC = "1";
"A":   PN = "1"  !CDS_PN = "1";
"B":   PN = "2"  !CDS_PN = "2";
BODY = "TUSB211IRWBR","I84": #LOCATION = "U5201" !CDS_LOCATION = "U5201" &SEC = "1" #&CDS_SEC = "1";
"CD":   PN = "4"  !CDS_PN = "4";
"D1M":   PN = "1"  !CDS_PN = "1";
"D1P":   PN = "2"  !CDS_PN = "2";
"D2M":   PN = "8"  !CDS_PN = "8";
"D2P":   PN = "7"  !CDS_PN = "7";
"ENA_HS":   PN = "9"  !CDS_PN = "9";
"EQ":   PN = "6"  !CDS_PN = "6";
"GND":   PN = "10"  !CDS_PN = "10";
"RSTN":   PN = "5"  !CDS_PN = "5";
"TEST":   PN = "3"  !CDS_PN = "3";
"VCC":   PN = "12"  !CDS_PN = "12";
"VREG":   PN = "11"  !CDS_PN = "11";
BODY = "Q_CAP","I87": #LOCATION = "C5236" !CDS_LOCATION = "C5236" &SEC = "1" #&CDS_SEC = "1";
"A":   PN = "1"  !CDS_PN = "1";
"B":   PN = "2"  !CDS_PN = "2";
BODY = "Q_CAP","I88": #LOCATION = "C5229" !CDS_LOCATION = "C5229" &SEC = "1" #&CDS_SEC = "1";
"A":   PN = "1"  !CDS_PN = "1";
"B":   PN = "2"  !CDS_PN = "2";
BODY = "Q_RES","I90": #LOCATION = "R5236" !CDS_LOCATION = "R5236" &SEC = "1" #&CDS_SEC = "1";
"A":   PN = "1"  !CDS_PN = "1";
"B":   PN = "2"  !CDS_PN = "2";
BODY = "Q_RES","I91": #LOCATION = "R5234" !CDS_LOCATION = "R5234" &SEC = "1" #&CDS_SEC = "1";
"A":   PN = "1"  !CDS_PN = "1";
"B":   PN = "2"  !CDS_PN = "2";
BODY = "Q_CAP","I92": #LOCATION = "C5234" !CDS_LOCATION = "C5234" &SEC = "1" #&CDS_SEC = "1";
"A":   PN = "1"  !CDS_PN = "1";
"B":   PN = "2"  !CDS_PN = "2";
BODY = "Q_RES","I96": #LOCATION = "R2790" !CDS_LOCATION = "R2790" &SEC = "1" #&CDS_SEC = "1";
"A":   PN = "1"  !CDS_PN = "1";
"B":   PN = "2"  !CDS_PN = "2";
BODY = "Q_RES","I97": #LOCATION = "R2791" !CDS_LOCATION = "R2791" &SEC = "1" #&CDS_SEC = "1";
"A":   PN = "1"  !CDS_PN = "1";
"B":   PN = "2"  !CDS_PN = "2";
BODY = "Q_RES","I98": #LOCATION = "R2789" !CDS_LOCATION = "R2789" &SEC = "1" #&CDS_SEC = "1";
"A":   PN = "1"  !CDS_PN = "1";
"B":   PN = "2"  !CDS_PN = "2";
BODY = "Q_RES","I99": #LOCATION = "R2788" !CDS_LOCATION = "R2788" &SEC = "1" #&CDS_SEC = "1";
"A":   PN = "1"  !CDS_PN = "1";
"B":   PN = "2"  !CDS_PN = "2";
BODY = "GL852GOHY60","I100": #LOCATION = "U268" !CDS_LOCATION = "U268" &SEC = "1" #&CDS_SEC = "1";
"AVDD<0>":   PN = "5"  !CDS_PN = "5";
"AVDD<1>":   PN = "9"  !CDS_PN = "9";
"AVDD<2>":   PN = "14"  !CDS_PN = "14";
"DM0":   PN = "1"  !CDS_PN = "1";
"DM1":   PN = "3"  !CDS_PN = "3";
"DM2":   PN = "6"  !CDS_PN = "6";
"DM3":   PN = "12"  !CDS_PN = "12";
"DM4":   PN = "15"  !CDS_PN = "15";
"DP0":   PN = "2"  !CDS_PN = "2";
"DP1":   PN = "4"  !CDS_PN = "4";
"DP2":   PN = "7"  !CDS_PN = "7";
"DP3":   PN = "13"  !CDS_PN = "13";
"DP4":   PN = "16"  !CDS_PN = "16";
"DVDD":   PN = "21"  !CDS_PN = "21";
"OVCUR1#||SMC":   PN = "25"  !CDS_PN = "25";
"OVCUR2#||SMD":   PN = "24"  !CDS_PN = "24";
"OVCUR3#":   PN = "20"  !CDS_PN = "20";
"OVCUR4#":   PN = "19"  !CDS_PN = "19";
"PGANG":   PN = "23"  !CDS_PN = "23";
"PSELF":   PN = "22"  !CDS_PN = "22";
"RESET#":   PN = "17"  !CDS_PN = "17";
"RREF":   PN = "8"  !CDS_PN = "8";
"SDA":   PN = "26"  !CDS_PN = "26";
"TEST||SCL":   PN = "18"  !CDS_PN = "18";
"TH":   PN = "TH"  !CDS_PN = "TH";
"V5":   PN = "27"  !CDS_PN = "27";
"V33":   PN = "28"  !CDS_PN = "28";
"X1":   PN = "10"  !CDS_PN = "10";
"X2":   PN = "11"  !CDS_PN = "11";
BODY = "Q_RES","I137": #LOCATION = "R3652" !CDS_LOCATION = "R3652" &SEC = "1" #&CDS_SEC = "1";
"A":   PN = "1"  !CDS_PN = "1";
"B":   PN = "2"  !CDS_PN = "2";
BODY = "Q_RES","I138": #LOCATION = "R3651" !CDS_LOCATION = "R3651" &SEC = "1" #&CDS_SEC = "1";
"A":   PN = "1"  !CDS_PN = "1";
"B":   PN = "2"  !CDS_PN = "2";
BODY = "Q_RES","I139": #LOCATION = "R3653" !CDS_LOCATION = "R3653" &SEC = "1" #&CDS_SEC = "1";
"A":   PN = "1"  !CDS_PN = "1";
"B":   PN = "2"  !CDS_PN = "2";
BODY = "Q_CAP","I142": #LOCATION = "C2034" !CDS_LOCATION = "C2034" &SEC = "1" #&CDS_SEC = "1";
"A":   PN = "1"  !CDS_PN = "1";
"B":   PN = "2"  !CDS_PN = "2";
BODY = "Q_CAP","I143": #LOCATION = "C2033" !CDS_LOCATION = "C2033" &SEC = "1" #&CDS_SEC = "1";
"A":   PN = "1"  !CDS_PN = "1";
"B":   PN = "2"  !CDS_PN = "2";
BODY = "Q_CAP","I145": #LOCATION = "C2032" !CDS_LOCATION = "C2032" &SEC = "1" #&CDS_SEC = "1";
"A":   PN = "1"  !CDS_PN = "1";
"B":   PN = "2"  !CDS_PN = "2";
BODY = "Q_CAP","I147": #LOCATION = "C2035" !CDS_LOCATION = "C2035" &SEC = "1" #&CDS_SEC = "1";
"A":   PN = "1"  !CDS_PN = "1";
"B":   PN = "2"  !CDS_PN = "2";
BODY = "Q_CAP","I148": #LOCATION = "C2031" !CDS_LOCATION = "C2031" &SEC = "1" #&CDS_SEC = "1";
"A":   PN = "1"  !CDS_PN = "1";
"B":   PN = "2"  !CDS_PN = "2";
BODY = "Q_RES","I155": #LOCATION = "R3654" !CDS_LOCATION = "R3654" &SEC = "1" #&CDS_SEC = "1";
"A":   PN = "1"  !CDS_PN = "1";
"B":   PN = "2"  !CDS_PN = "2";
BODY = "Q_CAP","I158": #LOCATION = "C2041" !CDS_LOCATION = "C2041" &SEC = "1" #&CDS_SEC = "1";
"A":   PN = "1"  !CDS_PN = "1";
"B":   PN = "2"  !CDS_PN = "2";
BODY = "Q_RES","I159": #LOCATION = "R3660" !CDS_LOCATION = "R3660" &SEC = "1" #&CDS_SEC = "1";
"A":   PN = "1"  !CDS_PN = "1";
"B":   PN = "2"  !CDS_PN = "2";
BODY = "Q_RES","I161": #LOCATION = "R3655" !CDS_LOCATION = "R3655" &SEC = "1" #&CDS_SEC = "1";
"A":   PN = "1"  !CDS_PN = "1";
"B":   PN = "2"  !CDS_PN = "2";
BODY = "Q_CAP","I162": #LOCATION = "C2040" !CDS_LOCATION = "C2040" &SEC = "1" #&CDS_SEC = "1";
"A":   PN = "1"  !CDS_PN = "1";
"B":   PN = "2"  !CDS_PN = "2";
BODY = "Q_CAP","I163": #LOCATION = "C2039" !CDS_LOCATION = "C2039" &SEC = "1" #&CDS_SEC = "1";
"A":   PN = "1"  !CDS_PN = "1";
"B":   PN = "2"  !CDS_PN = "2";
BODY = "Q_CAP","I164": #LOCATION = "C2038" !CDS_LOCATION = "C2038" &SEC = "1" #&CDS_SEC = "1";
"A":   PN = "1"  !CDS_PN = "1";
"B":   PN = "2"  !CDS_PN = "2";
BODY = "Q_RES","I167": #LOCATION = "R3662" !CDS_LOCATION = "R3662" &SEC = "1" #&CDS_SEC = "1";
"A":   PN = "1"  !CDS_PN = "1";
"B":   PN = "2"  !CDS_PN = "2";
BODY = "Q_RES","I182": #LOCATION = "R3665" !CDS_LOCATION = "R3665" &SEC = "1" #&CDS_SEC = "1";
"A":   PN = "1"  !CDS_PN = "1";
"B":   PN = "2"  !CDS_PN = "2";
BODY = "Q_RES","I186": #LOCATION = "R3663" !CDS_LOCATION = "R3663" &SEC = "1" #&CDS_SEC = "1";
"A":   PN = "1"  !CDS_PN = "1";
"B":   PN = "2"  !CDS_PN = "2";
BODY = "Q_RES","I187": #LOCATION = "R3664" !CDS_LOCATION = "R3664" &SEC = "1" #&CDS_SEC = "1";
"A":   PN = "1"  !CDS_PN = "1";
"B":   PN = "2"  !CDS_PN = "2";
BODY = "Q_RES","I194": #LOCATION = "R3656" !CDS_LOCATION = "R3656" &SEC = "1" #&CDS_SEC = "1";
"A":   PN = "1"  !CDS_PN = "1";
"B":   PN = "2"  !CDS_PN = "2";
BODY = "Q_RES","I195": #LOCATION = "R3657" !CDS_LOCATION = "R3657" &SEC = "1" #&CDS_SEC = "1";
"A":   PN = "1"  !CDS_PN = "1";
"B":   PN = "2"  !CDS_PN = "2";
BODY = "Q_RES","I196": #LOCATION = "R3658" !CDS_LOCATION = "R3658" &SEC = "1" #&CDS_SEC = "1";
"A":   PN = "1"  !CDS_PN = "1";
"B":   PN = "2"  !CDS_PN = "2";
BODY = "Q_RES","I198": #LOCATION = "R3659" !CDS_LOCATION = "R3659" &SEC = "1" #&CDS_SEC = "1";
"A":   PN = "1"  !CDS_PN = "1";
"B":   PN = "2"  !CDS_PN = "2";
BODY = "Q_RES","I199": #LOCATION = "R3666" !CDS_LOCATION = "R3666" &SEC = "1" #&CDS_SEC = "1";
"A":   PN = "1"  !CDS_PN = "1";
"B":   PN = "2"  !CDS_PN = "2";
BODY = "Q_RES","I201": #LOCATION = "R3661" !CDS_LOCATION = "R3661" &SEC = "1" #&CDS_SEC = "1";
"A":   PN = "1"  !CDS_PN = "1";
"B":   PN = "2"  !CDS_PN = "2";
BODY = "Q_RES","I202": #LOCATION = "R4420" !CDS_LOCATION = "R4420" &SEC = "1" #&CDS_SEC = "1";
"A":   PN = "1"  !CDS_PN = "1";
"B":   PN = "2"  !CDS_PN = "2";
BODY = "Q_RES","I203": #LOCATION = "R4419" !CDS_LOCATION = "R4419" &SEC = "1" #&CDS_SEC = "1";
"A":   PN = "1"  !CDS_PN = "1";
"B":   PN = "2"  !CDS_PN = "2";
BODY = "Q_RES","I206": #LOCATION = "R4483" !CDS_LOCATION = "R4483" &SEC = "1" #&CDS_SEC = "1";
"A":   PN = "1"  !CDS_PN = "1";
"B":   PN = "2"  !CDS_PN = "2";
BODY = "Q_RES","I208": #LOCATION = "R4482" !CDS_LOCATION = "R4482" &SEC = "1" #&CDS_SEC = "1";
"A":   PN = "1"  !CDS_PN = "1";
"B":   PN = "2"  !CDS_PN = "2";
BODY = "Q_XTAL_4P_13BI_24GND","I210": #LOCATION = "Y8004" !CDS_LOCATION = "Y8004" #SEC = "1" !CDS_SEC = "1";
"G1":   PN = "2"  !CDS_PN = "2";
"G2":   PN = "4"  !CDS_PN = "4";
"X1":   PN = "1"  !CDS_PN = "1";
"X2":   PN = "3"  !CDS_PN = "3";
BODY = "Q_CAP","I211": #LOCATION = "C2030" !CDS_LOCATION = "C2030" &SEC = "1" #&CDS_SEC = "1";
"A":   PN = "1"  !CDS_PN = "1";
"B":   PN = "2"  !CDS_PN = "2";
BODY = "Q_CAP","I212": #LOCATION = "C2029" !CDS_LOCATION = "C2029" &SEC = "1" #&CDS_SEC = "1";
"A":   PN = "1"  !CDS_PN = "1";
"B":   PN = "2"  !CDS_PN = "2";
DRAWING = "@t6g_mb_lib.t6g(sch_1):page359";
BODY = "Q_CAP","I16": #LOCATION = "C2010" !CDS_LOCATION = "C2010" &SEC = "1" #&CDS_SEC = "1";
"A":   PN = "1"  !CDS_PN = "1";
"B":   PN = "2"  !CDS_PN = "2";
BODY = "Q_RES","I77": #LOCATION = "R4180" !CDS_LOCATION = "R4180" &SEC = "1" #&CDS_SEC = "1";
"A":   PN = "1"  !CDS_PN = "1";
"B":   PN = "2"  !CDS_PN = "2";
BODY = "Q_RES","I78": #LOCATION = "R4183" !CDS_LOCATION = "R4183" &SEC = "1" #&CDS_SEC = "1";
"A":   PN = "1"  !CDS_PN = "1";
"B":   PN = "2"  !CDS_PN = "2";
BODY = "Q_RES","I79": #LOCATION = "R4215" !CDS_LOCATION = "R4215" &SEC = "1" #&CDS_SEC = "1";
"A":   PN = "1"  !CDS_PN = "1";
"B":   PN = "2"  !CDS_PN = "2";
BODY = "Q_RES","I81": #LOCATION = "R4199" !CDS_LOCATION = "R4199" &SEC = "1" #&CDS_SEC = "1";
"A":   PN = "1"  !CDS_PN = "1";
"B":   PN = "2"  !CDS_PN = "2";
BODY = "Q_RES","I82": #LOCATION = "R4198" !CDS_LOCATION = "R4198" &SEC = "1" #&CDS_SEC = "1";
"A":   PN = "1"  !CDS_PN = "1";
"B":   PN = "2"  !CDS_PN = "2";
BODY = "Q_RES","I85": #LOCATION = "R4207" !CDS_LOCATION = "R4207" &SEC = "1" #&CDS_SEC = "1";
"A":   PN = "1"  !CDS_PN = "1";
"B":   PN = "2"  !CDS_PN = "2";
BODY = "Q_RES","I86": #LOCATION = "R4206" !CDS_LOCATION = "R4206" &SEC = "1" #&CDS_SEC = "1";
"A":   PN = "1"  !CDS_PN = "1";
"B":   PN = "2"  !CDS_PN = "2";
BODY = "Q_RES","I89": #LOCATION = "R4191" !CDS_LOCATION = "R4191" &SEC = "1" #&CDS_SEC = "1";
"A":   PN = "1"  !CDS_PN = "1";
"B":   PN = "2"  !CDS_PN = "2";
BODY = "Q_RES","I91": #LOCATION = "R4190" !CDS_LOCATION = "R4190" &SEC = "1" #&CDS_SEC = "1";
"A":   PN = "1"  !CDS_PN = "1";
"B":   PN = "2"  !CDS_PN = "2";
BODY = "Q_RES","I94": #LOCATION = "R4204" !CDS_LOCATION = "R4204" &SEC = "1" #&CDS_SEC = "1";
"A":   PN = "1"  !CDS_PN = "1";
"B":   PN = "2"  !CDS_PN = "2";
BODY = "Q_RES","I95": #LOCATION = "R4196" !CDS_LOCATION = "R4196" &SEC = "1" #&CDS_SEC = "1";
"A":   PN = "1"  !CDS_PN = "1";
"B":   PN = "2"  !CDS_PN = "2";
BODY = "Q_RES","I96": #LOCATION = "R4205" !CDS_LOCATION = "R4205" &SEC = "1" #&CDS_SEC = "1";
"A":   PN = "1"  !CDS_PN = "1";
"B":   PN = "2"  !CDS_PN = "2";
BODY = "Q_RES","I98": #LOCATION = "R4197" !CDS_LOCATION = "R4197" &SEC = "1" #&CDS_SEC = "1";
"A":   PN = "1"  !CDS_PN = "1";
"B":   PN = "2"  !CDS_PN = "2";
BODY = "Q_RES","I101": #LOCATION = "R4188" !CDS_LOCATION = "R4188" &SEC = "1" #&CDS_SEC = "1";
"A":   PN = "1"  !CDS_PN = "1";
"B":   PN = "2"  !CDS_PN = "2";
BODY = "Q_RES","I102": #LOCATION = "R4189" !CDS_LOCATION = "R4189" &SEC = "1" #&CDS_SEC = "1";
"A":   PN = "1"  !CDS_PN = "1";
"B":   PN = "2"  !CDS_PN = "2";
BODY = "Q_CAP","I104": #LOCATION = "C73" !CDS_LOCATION = "C73" &SEC = "1" #&CDS_SEC = "1";
"A":   PN = "1"  !CDS_PN = "1";
"B":   PN = "2"  !CDS_PN = "2";
BODY = "Q_RES","I107": #LOCATION = "R4182" !CDS_LOCATION = "R4182" &SEC = "1" #&CDS_SEC = "1";
"A":   PN = "1"  !CDS_PN = "1";
"B":   PN = "2"  !CDS_PN = "2";
BODY = "Q_RES","I108": #LOCATION = "R4214" !CDS_LOCATION = "R4214" &SEC = "1" #&CDS_SEC = "1";
"A":   PN = "1"  !CDS_PN = "1";
"B":   PN = "2"  !CDS_PN = "2";
BODY = "Q_RES","I109": #LOCATION = "R4179" !CDS_LOCATION = "R4179" &SEC = "1" #&CDS_SEC = "1";
"A":   PN = "1"  !CDS_PN = "1";
"B":   PN = "2"  !CDS_PN = "2";
BODY = "Q_RES","I114": #LOCATION = "R4178" !CDS_LOCATION = "R4178" &SEC = "1" #&CDS_SEC = "1";
"A":   PN = "1"  !CDS_PN = "1";
"B":   PN = "2"  !CDS_PN = "2";
BODY = "Q_RES","I115": #LOCATION = "R4213" !CDS_LOCATION = "R4213" &SEC = "1" #&CDS_SEC = "1";
"A":   PN = "1"  !CDS_PN = "1";
"B":   PN = "2"  !CDS_PN = "2";
BODY = "Q_RES","I116": #LOCATION = "R4181" !CDS_LOCATION = "R4181" &SEC = "1" #&CDS_SEC = "1";
"A":   PN = "1"  !CDS_PN = "1";
"B":   PN = "2"  !CDS_PN = "2";
BODY = "Q_CAP","I119": #LOCATION = "C32" !CDS_LOCATION = "C32" &SEC = "1" #&CDS_SEC = "1";
"A":   PN = "1"  !CDS_PN = "1";
"B":   PN = "2"  !CDS_PN = "2";
BODY = "Q_RES","I121": #LOCATION = "R4187" !CDS_LOCATION = "R4187" &SEC = "1" #&CDS_SEC = "1";
"A":   PN = "1"  !CDS_PN = "1";
"B":   PN = "2"  !CDS_PN = "2";
BODY = "Q_RES","I122": #LOCATION = "R4186" !CDS_LOCATION = "R4186" &SEC = "1" #&CDS_SEC = "1";
"A":   PN = "1"  !CDS_PN = "1";
"B":   PN = "2"  !CDS_PN = "2";
BODY = "Q_RES","I125": #LOCATION = "R4195" !CDS_LOCATION = "R4195" &SEC = "1" #&CDS_SEC = "1";
"A":   PN = "1"  !CDS_PN = "1";
"B":   PN = "2"  !CDS_PN = "2";
BODY = "Q_RES","I127": #LOCATION = "R4203" !CDS_LOCATION = "R4203" &SEC = "1" #&CDS_SEC = "1";
"A":   PN = "1"  !CDS_PN = "1";
"B":   PN = "2"  !CDS_PN = "2";
BODY = "Q_RES","I128": #LOCATION = "R4194" !CDS_LOCATION = "R4194" &SEC = "1" #&CDS_SEC = "1";
"A":   PN = "1"  !CDS_PN = "1";
"B":   PN = "2"  !CDS_PN = "2";
BODY = "Q_RES","I129": #LOCATION = "R4202" !CDS_LOCATION = "R4202" &SEC = "1" #&CDS_SEC = "1";
"A":   PN = "1"  !CDS_PN = "1";
"B":   PN = "2"  !CDS_PN = "2";
BODY = "Q_RES","I134": #LOCATION = "R3553" !CDS_LOCATION = "R3553" &SEC = "1" #&CDS_SEC = "1";
"A":   PN = "1"  !CDS_PN = "1";
"B":   PN = "2"  !CDS_PN = "2";
BODY = "Q_RES","I135": #LOCATION = "R4212" !CDS_LOCATION = "R4212" &SEC = "1" #&CDS_SEC = "1";
"A":   PN = "1"  !CDS_PN = "1";
"B":   PN = "2"  !CDS_PN = "2";
BODY = "Q_RES","I136": #LOCATION = "R3554" !CDS_LOCATION = "R3554" &SEC = "1" #&CDS_SEC = "1";
"A":   PN = "1"  !CDS_PN = "1";
"B":   PN = "2"  !CDS_PN = "2";
BODY = "Q_CAP","I139": #LOCATION = "C31" !CDS_LOCATION = "C31" &SEC = "1" #&CDS_SEC = "1";
"A":   PN = "1"  !CDS_PN = "1";
"B":   PN = "2"  !CDS_PN = "2";
BODY = "Q_RES","I141": #LOCATION = "R4185" !CDS_LOCATION = "R4185" &SEC = "1" #&CDS_SEC = "1";
"A":   PN = "1"  !CDS_PN = "1";
"B":   PN = "2"  !CDS_PN = "2";
BODY = "Q_RES","I142": #LOCATION = "R4184" !CDS_LOCATION = "R4184" &SEC = "1" #&CDS_SEC = "1";
"A":   PN = "1"  !CDS_PN = "1";
"B":   PN = "2"  !CDS_PN = "2";
BODY = "Q_RES","I145": #LOCATION = "R4193" !CDS_LOCATION = "R4193" &SEC = "1" #&CDS_SEC = "1";
"A":   PN = "1"  !CDS_PN = "1";
"B":   PN = "2"  !CDS_PN = "2";
BODY = "Q_RES","I147": #LOCATION = "R4201" !CDS_LOCATION = "R4201" &SEC = "1" #&CDS_SEC = "1";
"A":   PN = "1"  !CDS_PN = "1";
"B":   PN = "2"  !CDS_PN = "2";
BODY = "Q_RES","I148": #LOCATION = "R4192" !CDS_LOCATION = "R4192" &SEC = "1" #&CDS_SEC = "1";
"A":   PN = "1"  !CDS_PN = "1";
"B":   PN = "2"  !CDS_PN = "2";
BODY = "Q_RES","I149": #LOCATION = "R4200" !CDS_LOCATION = "R4200" &SEC = "1" #&CDS_SEC = "1";
"A":   PN = "1"  !CDS_PN = "1";
"B":   PN = "2"  !CDS_PN = "2";
BODY = "LM75BD","I164": #LOCATION = "U270" !CDS_LOCATION = "U270" &SEC = "1" #&CDS_SEC = "1";
"A0":   PN = "7"  !CDS_PN = "7";
"A1":   PN = "6"  !CDS_PN = "6";
"A2":   PN = "5"  !CDS_PN = "5";
"GND":   PN = "4"  !CDS_PN = "4";
"OS":   PN = "3"  !CDS_PN = "3";
"SCL":   PN = "2"  !CDS_PN = "2";
"SDA":   PN = "1"  !CDS_PN = "1";
"VCC":   PN = "8"  !CDS_PN = "8";
BODY = "LM75BD","I165": #LOCATION = "U271" !CDS_LOCATION = "U271" &SEC = "1" #&CDS_SEC = "1";
"A0":   PN = "7"  !CDS_PN = "7";
"A1":   PN = "6"  !CDS_PN = "6";
"A2":   PN = "5"  !CDS_PN = "5";
"GND":   PN = "4"  !CDS_PN = "4";
"OS":   PN = "3"  !CDS_PN = "3";
"SCL":   PN = "2"  !CDS_PN = "2";
"SDA":   PN = "1"  !CDS_PN = "1";
"VCC":   PN = "8"  !CDS_PN = "8";
BODY = "LM75BD","I166": #LOCATION = "U272" !CDS_LOCATION = "U272" &SEC = "1" #&CDS_SEC = "1";
"A0":   PN = "7"  !CDS_PN = "7";
"A1":   PN = "6"  !CDS_PN = "6";
"A2":   PN = "5"  !CDS_PN = "5";
"GND":   PN = "4"  !CDS_PN = "4";
"OS":   PN = "3"  !CDS_PN = "3";
"SCL":   PN = "2"  !CDS_PN = "2";
"SDA":   PN = "1"  !CDS_PN = "1";
"VCC":   PN = "8"  !CDS_PN = "8";
BODY = "LM75BD","I167": #LOCATION = "U273" !CDS_LOCATION = "U273" &SEC = "1" #&CDS_SEC = "1";
"A0":   PN = "7"  !CDS_PN = "7";
"A1":   PN = "6"  !CDS_PN = "6";
"A2":   PN = "5"  !CDS_PN = "5";
"GND":   PN = "4"  !CDS_PN = "4";
"OS":   PN = "3"  !CDS_PN = "3";
"SCL":   PN = "2"  !CDS_PN = "2";
"SDA":   PN = "1"  !CDS_PN = "1";
"VCC":   PN = "8"  !CDS_PN = "8";
BODY = "Q_RES","I168": #LOCATION = "R4211" !CDS_LOCATION = "R4211" &SEC = "1" #&CDS_SEC = "1";
"A":   PN = "1"  !CDS_PN = "1";
"B":   PN = "2"  !CDS_PN = "2";
BODY = "Q_RES","I169": #LOCATION = "R4209" !CDS_LOCATION = "R4209" &SEC = "1" #&CDS_SEC = "1";
"A":   PN = "1"  !CDS_PN = "1";
"B":   PN = "2"  !CDS_PN = "2";
BODY = "Q_RES","I170": #LOCATION = "R4210" !CDS_LOCATION = "R4210" &SEC = "1" #&CDS_SEC = "1";
"A":   PN = "1"  !CDS_PN = "1";
"B":   PN = "2"  !CDS_PN = "2";
BODY = "Q_RES","I171": #LOCATION = "R4208" !CDS_LOCATION = "R4208" &SEC = "1" #&CDS_SEC = "1";
"A":   PN = "1"  !CDS_PN = "1";
"B":   PN = "2"  !CDS_PN = "2";
DRAWING = "@t6g_mb_lib.t6g(sch_1):page360";
BODY = "Q_CAP","I26": #LOCATION = "C2018" !CDS_LOCATION = "C2018" &SEC = "1" #&CDS_SEC = "1";
"A":   PN = "1"  !CDS_PN = "1";
"B":   PN = "2"  !CDS_PN = "2";
BODY = "Q_RES","I33": #LOCATION = "R3575" !CDS_LOCATION = "R3575" &SEC = "1" #&CDS_SEC = "1";
"A":   PN = "1"  !CDS_PN = "1";
"B":   PN = "2"  !CDS_PN = "2";
BODY = "Q_RES","I35": #LOCATION = "R3574" !CDS_LOCATION = "R3574" &SEC = "1" #&CDS_SEC = "1";
"A":   PN = "1"  !CDS_PN = "1";
"B":   PN = "2"  !CDS_PN = "2";
BODY = "Q_RES","I36": #LOCATION = "R3611" !CDS_LOCATION = "R3611" &SEC = "1" #&CDS_SEC = "1";
"A":   PN = "1"  !CDS_PN = "1";
"B":   PN = "2"  !CDS_PN = "2";
BODY = "Q_RES","I41": #LOCATION = "R3560" !CDS_LOCATION = "R3560" &SEC = "1" #&CDS_SEC = "1";
"A":   PN = "1"  !CDS_PN = "1";
"B":   PN = "2"  !CDS_PN = "2";
BODY = "Q_CAP","I42": #LOCATION = "C2013" !CDS_LOCATION = "C2013" &SEC = "1" #&CDS_SEC = "1";
"A":   PN = "1"  !CDS_PN = "1";
"B":   PN = "2"  !CDS_PN = "2";
BODY = "Q_RES","I45": #LOCATION = "R3610" !CDS_LOCATION = "R3610" &SEC = "1" #&CDS_SEC = "1";
"A":   PN = "1"  !CDS_PN = "1";
"B":   PN = "2"  !CDS_PN = "2";
BODY = "ISL28022FRZT","I46": #LOCATION = "U264" !CDS_LOCATION = "U264" #SEC = "1" !CDS_SEC = "1";
"A0":   PN = "2"  !CDS_PN = "2";
"A1":   PN = "1"  !CDS_PN = "1";
"EXT_CLK||INT":   PN = "3"  !CDS_PN = "3";
"GND":   PN = "10"  !CDS_PN = "10";
"NC0":   PN = "6"  !CDS_PN = "6";
"NC1":   PN = "7"  !CDS_PN = "7";
"NC2":   PN = "8"  !CDS_PN = "8";
"NC3":   PN = "14"  !CDS_PN = "14";
"NC4":   PN = "15"  !CDS_PN = "15";
"NC5":   PN = "16"  !CDS_PN = "16";
"SCL|||SMBCLK":   PN = "5"  !CDS_PN = "5";
"SDA||SMBDAT":   PN = "4"  !CDS_PN = "4";
"TH_GND":   PN = "TH"  !CDS_PN = "TH";
"VBUS":   PN = "11"  !CDS_PN = "11";
"VCC":   PN = "9"  !CDS_PN = "9";
"VINM":   PN = "12"  !CDS_PN = "12";
"VINP":   PN = "13"  !CDS_PN = "13";
BODY = "Q_CAP","I49": #LOCATION = "C2019" !CDS_LOCATION = "C2019" &SEC = "1" #&CDS_SEC = "1";
"A":   PN = "1"  !CDS_PN = "1";
"B":   PN = "2"  !CDS_PN = "2";
BODY = "Q_RES","I56": #LOCATION = "R3579" !CDS_LOCATION = "R3579" &SEC = "1" #&CDS_SEC = "1";
"A":   PN = "1"  !CDS_PN = "1";
"B":   PN = "2"  !CDS_PN = "2";
BODY = "Q_RES","I58": #LOCATION = "R3578" !CDS_LOCATION = "R3578" &SEC = "1" #&CDS_SEC = "1";
"A":   PN = "1"  !CDS_PN = "1";
"B":   PN = "2"  !CDS_PN = "2";
BODY = "Q_RES","I59": #LOCATION = "R3613" !CDS_LOCATION = "R3613" &SEC = "1" #&CDS_SEC = "1";
"A":   PN = "1"  !CDS_PN = "1";
"B":   PN = "2"  !CDS_PN = "2";
BODY = "Q_RES","I64": #LOCATION = "R3561" !CDS_LOCATION = "R3561" &SEC = "1" #&CDS_SEC = "1";
"A":   PN = "1"  !CDS_PN = "1";
"B":   PN = "2"  !CDS_PN = "2";
BODY = "Q_CAP","I65": #LOCATION = "C2014" !CDS_LOCATION = "C2014" &SEC = "1" #&CDS_SEC = "1";
"A":   PN = "1"  !CDS_PN = "1";
"B":   PN = "2"  !CDS_PN = "2";
BODY = "Q_RES","I68": #LOCATION = "R3612" !CDS_LOCATION = "R3612" &SEC = "1" #&CDS_SEC = "1";
"A":   PN = "1"  !CDS_PN = "1";
"B":   PN = "2"  !CDS_PN = "2";
BODY = "ISL28022FRZT","I69": #LOCATION = "U265" !CDS_LOCATION = "U265" #SEC = "1" !CDS_SEC = "1";
"A0":   PN = "2"  !CDS_PN = "2";
"A1":   PN = "1"  !CDS_PN = "1";
"EXT_CLK||INT":   PN = "3"  !CDS_PN = "3";
"GND":   PN = "10"  !CDS_PN = "10";
"NC0":   PN = "6"  !CDS_PN = "6";
"NC1":   PN = "7"  !CDS_PN = "7";
"NC2":   PN = "8"  !CDS_PN = "8";
"NC3":   PN = "14"  !CDS_PN = "14";
"NC4":   PN = "15"  !CDS_PN = "15";
"NC5":   PN = "16"  !CDS_PN = "16";
"SCL|||SMBCLK":   PN = "5"  !CDS_PN = "5";
"SDA||SMBDAT":   PN = "4"  !CDS_PN = "4";
"TH_GND":   PN = "TH"  !CDS_PN = "TH";
"VBUS":   PN = "11"  !CDS_PN = "11";
"VCC":   PN = "9"  !CDS_PN = "9";
"VINM":   PN = "12"  !CDS_PN = "12";
"VINP":   PN = "13"  !CDS_PN = "13";
BODY = "Q_CAP","I71": #LOCATION = "C2021" !CDS_LOCATION = "C2021" &SEC = "1" #&CDS_SEC = "1";
"A":   PN = "1"  !CDS_PN = "1";
"B":   PN = "2"  !CDS_PN = "2";
BODY = "Q_CAP","I72": #LOCATION = "C2022" !CDS_LOCATION = "C2022" &SEC = "1" #&CDS_SEC = "1";
"A":   PN = "1"  !CDS_PN = "1";
"B":   PN = "2"  !CDS_PN = "2";
BODY = "Q_RES","I86": #LOCATION = "R3623" !CDS_LOCATION = "R3623" &SEC = "1" #&CDS_SEC = "1";
"A":   PN = "1"  !CDS_PN = "1";
"B":   PN = "2"  !CDS_PN = "2";
BODY = "Q_RES","I87": #LOCATION = "R3621" !CDS_LOCATION = "R3621" &SEC = "1" #&CDS_SEC = "1";
"A":   PN = "1"  !CDS_PN = "1";
"B":   PN = "2"  !CDS_PN = "2";
BODY = "Q_RES","I89": #LOCATION = "R3624" !CDS_LOCATION = "R3624" &SEC = "1" #&CDS_SEC = "1";
"A":   PN = "1"  !CDS_PN = "1";
"B":   PN = "2"  !CDS_PN = "2";
BODY = "Q_RES","I90": #LOCATION = "R3622" !CDS_LOCATION = "R3622" &SEC = "1" #&CDS_SEC = "1";
"A":   PN = "1"  !CDS_PN = "1";
"B":   PN = "2"  !CDS_PN = "2";
BODY = "Q_RES","I92": #LOCATION = "R3634" !CDS_LOCATION = "R3634" &SEC = "1" #&CDS_SEC = "1";
"A":   PN = "1"  !CDS_PN = "1";
"B":   PN = "2"  !CDS_PN = "2";
BODY = "Q_RES","I93": #LOCATION = "R3635" !CDS_LOCATION = "R3635" &SEC = "1" #&CDS_SEC = "1";
"A":   PN = "1"  !CDS_PN = "1";
"B":   PN = "2"  !CDS_PN = "2";
BODY = "ISL28022FRZT","I94": #LOCATION = "U263" !CDS_LOCATION = "U263" #SEC = "1" !CDS_SEC = "1";
"A0":   PN = "2"  !CDS_PN = "2";
"A1":   PN = "1"  !CDS_PN = "1";
"EXT_CLK||INT":   PN = "3"  !CDS_PN = "3";
"GND":   PN = "10"  !CDS_PN = "10";
"NC0":   PN = "6"  !CDS_PN = "6";
"NC1":   PN = "7"  !CDS_PN = "7";
"NC2":   PN = "8"  !CDS_PN = "8";
"NC3":   PN = "14"  !CDS_PN = "14";
"NC4":   PN = "15"  !CDS_PN = "15";
"NC5":   PN = "16"  !CDS_PN = "16";
"SCL|||SMBCLK":   PN = "5"  !CDS_PN = "5";
"SDA||SMBDAT":   PN = "4"  !CDS_PN = "4";
"TH_GND":   PN = "TH"  !CDS_PN = "TH";
"VBUS":   PN = "11"  !CDS_PN = "11";
"VCC":   PN = "9"  !CDS_PN = "9";
"VINM":   PN = "12"  !CDS_PN = "12";
"VINP":   PN = "13"  !CDS_PN = "13";
BODY = "Q_RES","I96": #LOCATION = "R3559" !CDS_LOCATION = "R3559" &SEC = "1" #&CDS_SEC = "1";
"A":   PN = "1"  !CDS_PN = "1";
"B":   PN = "2"  !CDS_PN = "2";
BODY = "Q_CAP","I98": #LOCATION = "C2012" !CDS_LOCATION = "C2012" &SEC = "1" #&CDS_SEC = "1";
"A":   PN = "1"  !CDS_PN = "1";
"B":   PN = "2"  !CDS_PN = "2";
BODY = "Q_RES","I100": #LOCATION = "R3620" !CDS_LOCATION = "R3620" &SEC = "1" #&CDS_SEC = "1";
"A":   PN = "1"  !CDS_PN = "1";
"B":   PN = "2"  !CDS_PN = "2";
BODY = "Q_RES","I103": #LOCATION = "R3608" !CDS_LOCATION = "R3608" &SEC = "1" #&CDS_SEC = "1";
"A":   PN = "1"  !CDS_PN = "1";
"B":   PN = "2"  !CDS_PN = "2";
BODY = "Q_RES","I104": #LOCATION = "R3609" !CDS_LOCATION = "R3609" &SEC = "1" #&CDS_SEC = "1";
"A":   PN = "1"  !CDS_PN = "1";
"B":   PN = "2"  !CDS_PN = "2";
BODY = "Q_CAP","I108": #LOCATION = "C2020" !CDS_LOCATION = "C2020" &SEC = "1" #&CDS_SEC = "1";
"A":   PN = "1"  !CDS_PN = "1";
"B":   PN = "2"  !CDS_PN = "2";
BODY = "Q_RES","I109": #LOCATION = "R3570" !CDS_LOCATION = "R3570" &SEC = "1" #&CDS_SEC = "1";
"A":   PN = "1"  !CDS_PN = "1";
"B":   PN = "2"  !CDS_PN = "2";
BODY = "Q_RES","I110": #LOCATION = "R3571" !CDS_LOCATION = "R3571" &SEC = "1" #&CDS_SEC = "1";
"A":   PN = "1"  !CDS_PN = "1";
"B":   PN = "2"  !CDS_PN = "2";
BODY = "Q_CAP","I114": #LOCATION = "C2017" !CDS_LOCATION = "C2017" &SEC = "1" #&CDS_SEC = "1";
"A":   PN = "1"  !CDS_PN = "1";
"B":   PN = "2"  !CDS_PN = "2";
BODY = "Q_RES","I116": #LOCATION = "R3633" !CDS_LOCATION = "R3633" &SEC = "1" #&CDS_SEC = "1";
"A":   PN = "1"  !CDS_PN = "1";
"B":   PN = "2"  !CDS_PN = "2";
BODY = "Q_RES","I122": #LOCATION = "R4091" !CDS_LOCATION = "R4091" &SEC = "1" #&CDS_SEC = "1";
"A":   PN = "1"  !CDS_PN = "1";
"B":   PN = "2"  !CDS_PN = "2";
BODY = "Q_RES","I124": #LOCATION = "R4090" !CDS_LOCATION = "R4090" &SEC = "1" #&CDS_SEC = "1";
"A":   PN = "1"  !CDS_PN = "1";
"B":   PN = "2"  !CDS_PN = "2";
BODY = "Q_RES","I126": #LOCATION = "R4092" !CDS_LOCATION = "R4092" &SEC = "1" #&CDS_SEC = "1";
"A":   PN = "1"  !CDS_PN = "1";
"B":   PN = "2"  !CDS_PN = "2";
BODY = "Q_RES","I127": #LOCATION = "R3569" !CDS_LOCATION = "R3569" &SEC = "1" #&CDS_SEC = "1";
"A":   PN = "1"  !CDS_PN = "1";
"B":   PN = "2"  !CDS_PN = "2";
BODY = "Q_RES","I128": #LOCATION = "R3568" !CDS_LOCATION = "R3568" &SEC = "1" #&CDS_SEC = "1";
"A":   PN = "1"  !CDS_PN = "1";
"B":   PN = "2"  !CDS_PN = "2";
BODY = "Q_RES","I129": #LOCATION = "R3573" !CDS_LOCATION = "R3573" &SEC = "1" #&CDS_SEC = "1";
"A":   PN = "1"  !CDS_PN = "1";
"B":   PN = "2"  !CDS_PN = "2";
BODY = "Q_RES","I130": #LOCATION = "R3572" !CDS_LOCATION = "R3572" &SEC = "1" #&CDS_SEC = "1";
"A":   PN = "1"  !CDS_PN = "1";
"B":   PN = "2"  !CDS_PN = "2";
BODY = "Q_RES","I131": #LOCATION = "R3576" !CDS_LOCATION = "R3576" &SEC = "1" #&CDS_SEC = "1";
"A":   PN = "1"  !CDS_PN = "1";
"B":   PN = "2"  !CDS_PN = "2";
BODY = "Q_RES","I132": #LOCATION = "R3577" !CDS_LOCATION = "R3577" &SEC = "1" #&CDS_SEC = "1";
"A":   PN = "1"  !CDS_PN = "1";
"B":   PN = "2"  !CDS_PN = "2";
DRAWING = "@t6g_mb_lib.t6g(sch_1):page361";
BODY = "M24128BWMN6TP","I35": #LOCATION = "U64" !CDS_LOCATION = "U64" &SEC = "1" #&CDS_SEC = "1";
"E0":   PN = "1"  !CDS_PN = "1";
"E1":   PN = "2"  !CDS_PN = "2";
"E2":   PN = "3"  !CDS_PN = "3";
"SCL":   PN = "6"  !CDS_PN = "6";
"SDA":   PN = "5"  !CDS_PN = "5";
"VCC":   PN = "8"  !CDS_PN = "8";
"VSS":   PN = "4"  !CDS_PN = "4";
"WC#":   PN = "7"  !CDS_PN = "7";
BODY = "Q_RES","I45": #LOCATION = "R717" !CDS_LOCATION = "R717" &SEC = "1" #&CDS_SEC = "1";
"A":   PN = "1"  !CDS_PN = "1";
"B":   PN = "2"  !CDS_PN = "2";
BODY = "Q_RES","I47": #LOCATION = "R713" !CDS_LOCATION = "R713" &SEC = "1" #&CDS_SEC = "1";
"A":   PN = "1"  !CDS_PN = "1";
"B":   PN = "2"  !CDS_PN = "2";
BODY = "Q_RES","I50": #LOCATION = "R718" !CDS_LOCATION = "R718" &SEC = "1" #&CDS_SEC = "1";
"A":   PN = "1"  !CDS_PN = "1";
"B":   PN = "2"  !CDS_PN = "2";
BODY = "Q_RES","I52": #LOCATION = "R714" !CDS_LOCATION = "R714" &SEC = "1" #&CDS_SEC = "1";
"A":   PN = "1"  !CDS_PN = "1";
"B":   PN = "2"  !CDS_PN = "2";
BODY = "Q_CAP","I55": #LOCATION = "C629" !CDS_LOCATION = "C629" &SEC = "1" #&CDS_SEC = "1";
"A":   PN = "1"  !CDS_PN = "1";
"B":   PN = "2"  !CDS_PN = "2";
BODY = "Q_RES","I57": #LOCATION = "R710" !CDS_LOCATION = "R710" &SEC = "1" #&CDS_SEC = "1";
"A":   PN = "1"  !CDS_PN = "1";
"B":   PN = "2"  !CDS_PN = "2";
BODY = "Q_RES","I61": #LOCATION = "R722" !CDS_LOCATION = "R722" &SEC = "1" #&CDS_SEC = "1";
"A":   PN = "1"  !CDS_PN = "1";
"B":   PN = "2"  !CDS_PN = "2";
BODY = "Q_RES","I62": #LOCATION = "R721" !CDS_LOCATION = "R721" &SEC = "1" #&CDS_SEC = "1";
"A":   PN = "1"  !CDS_PN = "1";
"B":   PN = "2"  !CDS_PN = "2";
BODY = "Q_RES","I93": #LOCATION = "R43" !CDS_LOCATION = "R43" &SEC = "1" #&CDS_SEC = "1";
"A":   PN = "1"  !CDS_PN = "1";
"B":   PN = "2"  !CDS_PN = "2";
BODY = "Q_RES","I95": #LOCATION = "R26" !CDS_LOCATION = "R26" &SEC = "1" #&CDS_SEC = "1";
"A":   PN = "1"  !CDS_PN = "1";
"B":   PN = "2"  !CDS_PN = "2";
BODY = "Q_RES","I103": #LOCATION = "R52" !CDS_LOCATION = "R52" &SEC = "1" #&CDS_SEC = "1";
"A":   PN = "1"  !CDS_PN = "1";
"B":   PN = "2"  !CDS_PN = "2";
BODY = "Q_CAP","I110": #LOCATION = "C1" !CDS_LOCATION = "C1" &SEC = "1" #&CDS_SEC = "1";
"A":   PN = "1"  !CDS_PN = "1";
"B":   PN = "2"  !CDS_PN = "2";
BODY = "Q_RES","I113": #LOCATION = "R24" !CDS_LOCATION = "R24" &SEC = "1" #&CDS_SEC = "1";
"A":   PN = "1"  !CDS_PN = "1";
"B":   PN = "2"  !CDS_PN = "2";
BODY = "Q_RES","I114": #LOCATION = "R4" !CDS_LOCATION = "R4" &SEC = "1" #&CDS_SEC = "1";
"A":   PN = "1"  !CDS_PN = "1";
"B":   PN = "2"  !CDS_PN = "2";
BODY = "Q_RES","I115": #LOCATION = "R44" !CDS_LOCATION = "R44" &SEC = "1" #&CDS_SEC = "1";
"A":   PN = "1"  !CDS_PN = "1";
"B":   PN = "2"  !CDS_PN = "2";
BODY = "M24128BWMN6TP","I97": #LOCATION = "U1" !CDS_LOCATION = "U1" &SEC = "1" #&CDS_SEC = "1";
"E0":   PN = "1"  !CDS_PN = "1";
"E1":   PN = "2"  !CDS_PN = "2";
"E2":   PN = "3"  !CDS_PN = "3";
"SCL":   PN = "6"  !CDS_PN = "6";
"SDA":   PN = "5"  !CDS_PN = "5";
"VCC":   PN = "8"  !CDS_PN = "8";
"VSS":   PN = "4"  !CDS_PN = "4";
"WC#":   PN = "7"  !CDS_PN = "7";
BODY = "Q_RES","I101": #LOCATION = "R60" !CDS_LOCATION = "R60" &SEC = "1" #&CDS_SEC = "1";
"A":   PN = "1"  !CDS_PN = "1";
"B":   PN = "2"  !CDS_PN = "2";
BODY = "Q_RES","I104": #LOCATION = "R62" !CDS_LOCATION = "R62" &SEC = "1" #&CDS_SEC = "1";
"A":   PN = "1"  !CDS_PN = "1";
"B":   PN = "2"  !CDS_PN = "2";
BODY = "Q_RES","I107": #LOCATION = "R54" !CDS_LOCATION = "R54" &SEC = "1" #&CDS_SEC = "1";
"A":   PN = "1"  !CDS_PN = "1";
"B":   PN = "2"  !CDS_PN = "2";
BODY = "Q_RES","I120": #LOCATION = "R68" !CDS_LOCATION = "R68" &SEC = "1" #&CDS_SEC = "1";
"A":   PN = "1"  !CDS_PN = "1";
"B":   PN = "2"  !CDS_PN = "2";
BODY = "Q_RES","I121": #LOCATION = "R69" !CDS_LOCATION = "R69" &SEC = "1" #&CDS_SEC = "1";
"A":   PN = "1"  !CDS_PN = "1";
"B":   PN = "2"  !CDS_PN = "2";
BODY = "Q_RES","I122": #LOCATION = "R121" !CDS_LOCATION = "R121" &SEC = "1" #&CDS_SEC = "1";
"A":   PN = "1"  !CDS_PN = "1";
"B":   PN = "2"  !CDS_PN = "2";
BODY = "Q_RES","I123": #LOCATION = "R125" !CDS_LOCATION = "R125" &SEC = "1" #&CDS_SEC = "1";
"A":   PN = "1"  !CDS_PN = "1";
"B":   PN = "2"  !CDS_PN = "2";
BODY = "Q_RES","I124": #LOCATION = "R85" !CDS_LOCATION = "R85" &SEC = "1" #&CDS_SEC = "1";
"A":   PN = "1"  !CDS_PN = "1";
"B":   PN = "2"  !CDS_PN = "2";
BODY = "Q_RES","I125": #LOCATION = "R86" !CDS_LOCATION = "R86" &SEC = "1" #&CDS_SEC = "1";
"A":   PN = "1"  !CDS_PN = "1";
"B":   PN = "2"  !CDS_PN = "2";
DRAWING = "@t6g_mb_lib.t6g(sch_1):page363";
BODY = "Q_RES","I387": #LOCATION = "R2802" !CDS_LOCATION = "R2802" &SEC = "1" #&CDS_SEC = "1";
"A":   PN = "1"  !CDS_PN = "1";
"B":   PN = "2"  !CDS_PN = "2";
BODY = "Q_RES","I388": #LOCATION = "R2803" !CDS_LOCATION = "R2803" &SEC = "1" #&CDS_SEC = "1";
"A":   PN = "1"  !CDS_PN = "1";
"B":   PN = "2"  !CDS_PN = "2";
BODY = "MOSFET_NCH_GDS_ESD_PROTECTED","I392": #LOCATION = "U190" !CDS_LOCATION = "U190" &SEC = "1" #&CDS_SEC = "1";
"D":   PN = "D"  !CDS_PN = "D";
"G":   PN = "G"  !CDS_PN = "G";
"S":   PN = "S"  !CDS_PN = "S";
BODY = "Q_RES","I394": #LOCATION = "R2793" !CDS_LOCATION = "R2793" &SEC = "1" #&CDS_SEC = "1";
"A":   PN = "1"  !CDS_PN = "1";
"B":   PN = "2"  !CDS_PN = "2";
BODY = "Q_RES","I396": #LOCATION = "R2794" !CDS_LOCATION = "R2794" &SEC = "1" #&CDS_SEC = "1";
"A":   PN = "1"  !CDS_PN = "1";
"B":   PN = "2"  !CDS_PN = "2";
BODY = "LTC4307CMS8","I398": #LOCATION = "U192" !CDS_LOCATION = "U192" &SEC = "1" #&CDS_SEC = "1";
"ENABLE":   PN = "1"  !CDS_PN = "1";
"GND":   PN = "4"  !CDS_PN = "4";
"READY":   PN = "5"  !CDS_PN = "5";
"SCL_IN":   PN = "3"  !CDS_PN = "3";
"SCL_OUT":   PN = "2"  !CDS_PN = "2";
"SDA_IN":   PN = "6"  !CDS_PN = "6";
"SDA_OUT":   PN = "7"  !CDS_PN = "7";
"VCC":   PN = "8"  !CDS_PN = "8";
BODY = "Q_CAP","I412": #LOCATION = "C1751" !CDS_LOCATION = "C1751" &SEC = "1" #&CDS_SEC = "1";
"A":   PN = "1"  !CDS_PN = "1";
"B":   PN = "2"  !CDS_PN = "2";
BODY = "Q_RES","I420": #LOCATION = "R2796" !CDS_LOCATION = "R2796" &SEC = "1" #&CDS_SEC = "1";
"A":   PN = "1"  !CDS_PN = "1";
"B":   PN = "2"  !CDS_PN = "2";
BODY = "Q_RES","I425": #LOCATION = "R2811" !CDS_LOCATION = "R2811" &SEC = "1" #&CDS_SEC = "1";
"A":   PN = "1"  !CDS_PN = "1";
"B":   PN = "2"  !CDS_PN = "2";
BODY = "Q_RES","I426": #LOCATION = "R2812" !CDS_LOCATION = "R2812" &SEC = "1" #&CDS_SEC = "1";
"A":   PN = "1"  !CDS_PN = "1";
"B":   PN = "2"  !CDS_PN = "2";
BODY = "Q_RES","I429": #LOCATION = "R2800" !CDS_LOCATION = "R2800" &SEC = "1" #&CDS_SEC = "1";
"A":   PN = "1"  !CDS_PN = "1";
"B":   PN = "2"  !CDS_PN = "2";
BODY = "Q_RES","I430": #LOCATION = "R2801" !CDS_LOCATION = "R2801" &SEC = "1" #&CDS_SEC = "1";
"A":   PN = "1"  !CDS_PN = "1";
"B":   PN = "2"  !CDS_PN = "2";
BODY = "Q_RES","I436": #LOCATION = "R2805" !CDS_LOCATION = "R2805" &SEC = "1" #&CDS_SEC = "1";
"A":   PN = "1"  !CDS_PN = "1";
"B":   PN = "2"  !CDS_PN = "2";
BODY = "Q_RES","I438": #LOCATION = "R2807" !CDS_LOCATION = "R2807" &SEC = "1" #&CDS_SEC = "1";
"A":   PN = "1"  !CDS_PN = "1";
"B":   PN = "2"  !CDS_PN = "2";
BODY = "Q_RES","I440": #LOCATION = "R2906" !CDS_LOCATION = "R2906" &SEC = "1" #&CDS_SEC = "1";
"A":   PN = "1"  !CDS_PN = "1";
"B":   PN = "2"  !CDS_PN = "2";
BODY = "Q_RES","I441": #LOCATION = "R2905" !CDS_LOCATION = "R2905" &SEC = "1" #&CDS_SEC = "1";
"A":   PN = "1"  !CDS_PN = "1";
"B":   PN = "2"  !CDS_PN = "2";
BODY = "Q_CAP","I452": #LOCATION = "C74" !CDS_LOCATION = "C74" &SEC = "1" #&CDS_SEC = "1";
"A":   PN = "1"  !CDS_PN = "1";
"B":   PN = "2"  !CDS_PN = "2";
BODY = "Q_CAP","I453": #LOCATION = "C64" !CDS_LOCATION = "C64" &SEC = "1" #&CDS_SEC = "1";
"A":   PN = "1"  !CDS_PN = "1";
"B":   PN = "2"  !CDS_PN = "2";
BODY = "Q_CAP","I454": #LOCATION = "C65" !CDS_LOCATION = "C65" &SEC = "1" #&CDS_SEC = "1";
"A":   PN = "1"  !CDS_PN = "1";
"B":   PN = "2"  !CDS_PN = "2";
BODY = "Q_CAP","I455": #LOCATION = "C66" !CDS_LOCATION = "C66" &SEC = "1" #&CDS_SEC = "1";
"A":   PN = "1"  !CDS_PN = "1";
"B":   PN = "2"  !CDS_PN = "2";
BODY = "Q_CAP","I456": #LOCATION = "C67" !CDS_LOCATION = "C67" &SEC = "1" #&CDS_SEC = "1";
"A":   PN = "1"  !CDS_PN = "1";
"B":   PN = "2"  !CDS_PN = "2";
BODY = "Q_RES","I463": #LOCATION = "R3113" !CDS_LOCATION = "R3113" &SEC = "1" #&CDS_SEC = "1";
"A":   PN = "1"  !CDS_PN = "1";
"B":   PN = "2"  !CDS_PN = "2";
BODY = "Q_RES","I464": #LOCATION = "R3114" !CDS_LOCATION = "R3114" &SEC = "1" #&CDS_SEC = "1";
"A":   PN = "1"  !CDS_PN = "1";
"B":   PN = "2"  !CDS_PN = "2";
BODY = "CONN60_101062636003K02LF","I466": #LOCATION = "J45" !CDS_LOCATION = "J45" #SEC = "1" !CDS_SEC = "1";
"A1":   PN = "A1"  !CDS_PN = "A1";
"A2":   PN = "A2"  !CDS_PN = "A2";
"A3":   PN = "A3"  !CDS_PN = "A3";
"B1":   PN = "B1"  !CDS_PN = "B1";
"B2":   PN = "B2"  !CDS_PN = "B2";
"B3":   PN = "B3"  !CDS_PN = "B3";
"C1":   PN = "C1"  !CDS_PN = "C1";
"C2":   PN = "C2"  !CDS_PN = "C2";
"C3":   PN = "C3"  !CDS_PN = "C3";
"D1":   PN = "D1"  !CDS_PN = "D1";
"D2":   PN = "D2"  !CDS_PN = "D2";
"D3":   PN = "D3"  !CDS_PN = "D3";
"P1_1":   PN = "P1_1"  !CDS_PN = "P1_1";
"P1_2":   PN = "P1_2"  !CDS_PN = "P1_2";
"P1_3":   PN = "P1_3"  !CDS_PN = "P1_3";
"P1_4":   PN = "P1_4"  !CDS_PN = "P1_4";
"P1_5":   PN = "P1_5"  !CDS_PN = "P1_5";
"P1_6":   PN = "P1_6"  !CDS_PN = "P1_6";
"P1_7":   PN = "P1_7"  !CDS_PN = "P1_7";
"P1_8":   PN = "P1_8"  !CDS_PN = "P1_8";
"P2_1":   PN = "P2_1"  !CDS_PN = "P2_1";
"P2_2":   PN = "P2_2"  !CDS_PN = "P2_2";
"P2_3":   PN = "P2_3"  !CDS_PN = "P2_3";
"P2_4":   PN = "P2_4"  !CDS_PN = "P2_4";
"P2_5":   PN = "P2_5"  !CDS_PN = "P2_5";
"P2_6":   PN = "P2_6"  !CDS_PN = "P2_6";
"P2_7":   PN = "P2_7"  !CDS_PN = "P2_7";
"P2_8":   PN = "P2_8"  !CDS_PN = "P2_8";
"P3_1":   PN = "P3_1"  !CDS_PN = "P3_1";
"P3_2":   PN = "P3_2"  !CDS_PN = "P3_2";
"P3_3":   PN = "P3_3"  !CDS_PN = "P3_3";
"P3_4":   PN = "P3_4"  !CDS_PN = "P3_4";
"P3_5":   PN = "P3_5"  !CDS_PN = "P3_5";
"P3_6":   PN = "P3_6"  !CDS_PN = "P3_6";
"P3_7":   PN = "P3_7"  !CDS_PN = "P3_7";
"P3_8":   PN = "P3_8"  !CDS_PN = "P3_8";
"P4_1":   PN = "P4_1"  !CDS_PN = "P4_1";
"P4_2":   PN = "P4_2"  !CDS_PN = "P4_2";
"P4_3":   PN = "P4_3"  !CDS_PN = "P4_3";
"P4_4":   PN = "P4_4"  !CDS_PN = "P4_4";
"P4_5":   PN = "P4_5"  !CDS_PN = "P4_5";
"P4_6":   PN = "P4_6"  !CDS_PN = "P4_6";
"P4_7":   PN = "P4_7"  !CDS_PN = "P4_7";
"P4_8":   PN = "P4_8"  !CDS_PN = "P4_8";
"P5_1":   PN = "P5_1"  !CDS_PN = "P5_1";
"P5_2":   PN = "P5_2"  !CDS_PN = "P5_2";
"P5_3":   PN = "P5_3"  !CDS_PN = "P5_3";
"P5_4":   PN = "P5_4"  !CDS_PN = "P5_4";
"P5_5":   PN = "P5_5"  !CDS_PN = "P5_5";
"P5_6":   PN = "P5_6"  !CDS_PN = "P5_6";
"P5_7":   PN = "P5_7"  !CDS_PN = "P5_7";
"P5_8":   PN = "P5_8"  !CDS_PN = "P5_8";
"P6_1":   PN = "P6_1"  !CDS_PN = "P6_1";
"P6_2":   PN = "P6_2"  !CDS_PN = "P6_2";
"P6_3":   PN = "P6_3"  !CDS_PN = "P6_3";
"P6_4":   PN = "P6_4"  !CDS_PN = "P6_4";
"P6_5":   PN = "P6_5"  !CDS_PN = "P6_5";
"P6_6":   PN = "P6_6"  !CDS_PN = "P6_6";
"P6_7":   PN = "P6_7"  !CDS_PN = "P6_7";
"P6_8":   PN = "P6_8"  !CDS_PN = "P6_8";
BODY = "Q_RES","I467": #LOCATION = "R8102" !CDS_LOCATION = "R8102" &SEC = "1" #&CDS_SEC = "1";
"A":   PN = "1"  !CDS_PN = "1";
"B":   PN = "2"  !CDS_PN = "2";
BODY = "Q_CAP","I469": #LOCATION = "C8011" !CDS_LOCATION = "C8011" &SEC = "1" #&CDS_SEC = "1";
"A":   PN = "1"  !CDS_PN = "1";
"B":   PN = "2"  !CDS_PN = "2";
BODY = "Q_RES","I472": #LOCATION = "R9000" !CDS_LOCATION = "R9000" &SEC = "1" #&CDS_SEC = "1";
"A":   PN = "1"  !CDS_PN = "1";
"B":   PN = "2"  !CDS_PN = "2";
BODY = "Q_RES","I475": #LOCATION = "R2950" !CDS_LOCATION = "R2950" &SEC = "1" #&CDS_SEC = "1";
"A":   PN = "1"  !CDS_PN = "1";
"B":   PN = "2"  !CDS_PN = "2";
BODY = "Q_RES","I476": #LOCATION = "R1526" !CDS_LOCATION = "R1526" &SEC = "1" #&CDS_SEC = "1";
"A":   PN = "1"  !CDS_PN = "1";
"B":   PN = "2"  !CDS_PN = "2";
BODY = "Q_CAP","I478": #LOCATION = "C1115" !CDS_LOCATION = "C1115" &SEC = "1" #&CDS_SEC = "1";
"A":   PN = "1"  !CDS_PN = "1";
"B":   PN = "2"  !CDS_PN = "2";
DRAWING = "@t6g_mb_lib.t6g(sch_1):page364";
BODY = "Q_CAP","I14": #LOCATION = "C1775" !CDS_LOCATION = "C1775" &SEC = "1" #&CDS_SEC = "1";
"A":   PN = "1"  !CDS_PN = "1";
"B":   PN = "2"  !CDS_PN = "2";
BODY = "Q_RES","I24": #LOCATION = "R2944" !CDS_LOCATION = "R2944" &SEC = "1" #&CDS_SEC = "1";
"A":   PN = "1"  !CDS_PN = "1";
"B":   PN = "2"  !CDS_PN = "2";
BODY = "Q_RES","I25": #LOCATION = "R2946" !CDS_LOCATION = "R2946" &SEC = "1" #&CDS_SEC = "1";
"A":   PN = "1"  !CDS_PN = "1";
"B":   PN = "2"  !CDS_PN = "2";
BODY = "Q_RES","I28": #LOCATION = "R2940" !CDS_LOCATION = "R2940" &SEC = "1" #&CDS_SEC = "1";
"A":   PN = "1"  !CDS_PN = "1";
"B":   PN = "2"  !CDS_PN = "2";
BODY = "Q_RES","I29": #LOCATION = "R2941" !CDS_LOCATION = "R2941" &SEC = "1" #&CDS_SEC = "1";
"A":   PN = "1"  !CDS_PN = "1";
"B":   PN = "2"  !CDS_PN = "2";
BODY = "Q_RES","I30": #LOCATION = "R2948" !CDS_LOCATION = "R2948" &SEC = "1" #&CDS_SEC = "1";
"A":   PN = "1"  !CDS_PN = "1";
"B":   PN = "2"  !CDS_PN = "2";
BODY = "74LVC1G08W57","I31": #LOCATION = "U278" !CDS_LOCATION = "U278" &SEC = "1" #&CDS_SEC = "1";
"A":   PN = "1"  !CDS_PN = "1";
"B":   PN = "2"  !CDS_PN = "2";
"GND":   PN = "3"  !CDS_PN = "3";
"VCC":   PN = "5"  !CDS_PN = "5";
"Y":   PN = "4"  !CDS_PN = "4";
BODY = "Q_RES","I34": #LOCATION = "R3770" !CDS_LOCATION = "R3770" &SEC = "1" #&CDS_SEC = "1";
"A":   PN = "1"  !CDS_PN = "1";
"B":   PN = "2"  !CDS_PN = "2";
BODY = "74LVC2G07DW7","I37": #LOCATION = "U308" !CDS_LOCATION = "U308" &SEC = "1" #&CDS_SEC = "1";
"1A":   PN = "1"  !CDS_PN = "1";
"1Y":   PN = "6"  !CDS_PN = "6";
"2A":   PN = "3"  !CDS_PN = "3";
"2Y":   PN = "4"  !CDS_PN = "4";
"GND":   PN = "2"  !CDS_PN = "2";
"VCC":   PN = "5"  !CDS_PN = "5";
BODY = "Q_CAP","I40": #LOCATION = "C69" !CDS_LOCATION = "C69" &SEC = "1" #&CDS_SEC = "1";
"A":   PN = "1"  !CDS_PN = "1";
"B":   PN = "2"  !CDS_PN = "2";
BODY = "Q_RES","I41": #LOCATION = "R4268" !CDS_LOCATION = "R4268" &SEC = "1" #&CDS_SEC = "1";
"A":   PN = "1"  !CDS_PN = "1";
"B":   PN = "2"  !CDS_PN = "2";
BODY = "Q_RES","I43": #LOCATION = "R4265" !CDS_LOCATION = "R4265" &SEC = "1" #&CDS_SEC = "1";
"A":   PN = "1"  !CDS_PN = "1";
"B":   PN = "2"  !CDS_PN = "2";
BODY = "Q_RES","I47": #LOCATION = "R4264" !CDS_LOCATION = "R4264" &SEC = "1" #&CDS_SEC = "1";
"A":   PN = "1"  !CDS_PN = "1";
"B":   PN = "2"  !CDS_PN = "2";
BODY = "Q_RES","I48": #LOCATION = "R4266" !CDS_LOCATION = "R4266" &SEC = "1" #&CDS_SEC = "1";
"A":   PN = "1"  !CDS_PN = "1";
"B":   PN = "2"  !CDS_PN = "2";
BODY = "Q_RES","I50": #LOCATION = "R4552" !CDS_LOCATION = "R4552" &SEC = "1" #&CDS_SEC = "1";
"A":   PN = "1"  !CDS_PN = "1";
"B":   PN = "2"  !CDS_PN = "2";
BODY = "Q_RES","I51": #LOCATION = "R4551" !CDS_LOCATION = "R4551" &SEC = "1" #&CDS_SEC = "1";
"A":   PN = "1"  !CDS_PN = "1";
"B":   PN = "2"  !CDS_PN = "2";
BODY = "MOSFET_NCH_DUAL","I53": #LOCATION = "Q145" !CDS_LOCATION = "Q145" &SEC = "1" #&CDS_SEC = "1";
"D1":   PN = "6"  !CDS_PN = "6";
"G1":   PN = "2"  !CDS_PN = "2";
"S1":   PN = "1"  !CDS_PN = "1";
BODY = "Q_RES","I55": #LOCATION = "R4553" !CDS_LOCATION = "R4553" &SEC = "1" #&CDS_SEC = "1";
"A":   PN = "1"  !CDS_PN = "1";
"B":   PN = "2"  !CDS_PN = "2";
BODY = "MOSFET_NCH_DUAL","I58": #LOCATION = "Q145" !CDS_LOCATION = "Q145" &SEC = "2" #&CDS_SEC = "2";
"D2":   PN = "3"  !CDS_PN = "3";
"G2":   PN = "5"  !CDS_PN = "5";
"S2":   PN = "4"  !CDS_PN = "4";
BODY = "Q_RES","I59": #LOCATION = "R4554" !CDS_LOCATION = "R4554" &SEC = "1" #&CDS_SEC = "1";
"A":   PN = "1"  !CDS_PN = "1";
"B":   PN = "2"  !CDS_PN = "2";
BODY = "Q_CAP","I62": #LOCATION = "C70" !CDS_LOCATION = "C70" &SEC = "1" #&CDS_SEC = "1";
"A":   PN = "1"  !CDS_PN = "1";
"B":   PN = "2"  !CDS_PN = "2";
DRAWING = "@t6g_mb_lib.t6g(sch_1):page365";
BODY = "Q_RES","I3": #LOCATION = "R2531" !CDS_LOCATION = "R2531" &SEC = "1" #&CDS_SEC = "1";
"A":   PN = "1"  !CDS_PN = "1";
"B":   PN = "2"  !CDS_PN = "2";
BODY = "MOSFET_NCH_GDS_ESD_PROTECTED","I6": #LOCATION = "U158" !CDS_LOCATION = "U158" &SEC = "1" #&CDS_SEC = "1";
"D":   PN = "D"  !CDS_PN = "D";
"G":   PN = "G"  !CDS_PN = "G";
"S":   PN = "S"  !CDS_PN = "S";
BODY = "Q_RES","I7": #LOCATION = "R2529" !CDS_LOCATION = "R2529" &SEC = "1" #&CDS_SEC = "1";
"A":   PN = "1"  !CDS_PN = "1";
"B":   PN = "2"  !CDS_PN = "2";
BODY = "Q_RES","I8": #LOCATION = "R2528" !CDS_LOCATION = "R2528" &SEC = "1" #&CDS_SEC = "1";
"A":   PN = "1"  !CDS_PN = "1";
"B":   PN = "2"  !CDS_PN = "2";
BODY = "Q_RES","I10": #LOCATION = "R2530" !CDS_LOCATION = "R2530" &SEC = "1" #&CDS_SEC = "1";
"A":   PN = "1"  !CDS_PN = "1";
"B":   PN = "2"  !CDS_PN = "2";
BODY = "MOSFET_NCH_GDS_ESD_PROTECTED","I14": #LOCATION = "Q54" !CDS_LOCATION = "Q54" &SEC = "1" #&CDS_SEC = "1";
"D":   PN = "D"  !CDS_PN = "D";
"G":   PN = "G"  !CDS_PN = "G";
"S":   PN = "S"  !CDS_PN = "S";
BODY = "74LVC2G07DW7","I16": #LOCATION = "U8004" !CDS_LOCATION = "U8004" #SEC = "1" !CDS_SEC = "1";
"1A":   PN = "1"  !CDS_PN = "1";
"1Y":   PN = "6"  !CDS_PN = "6";
"2A":   PN = "3"  !CDS_PN = "3";
"2Y":   PN = "4"  !CDS_PN = "4";
"GND":   PN = "2"  !CDS_PN = "2";
"VCC":   PN = "5"  !CDS_PN = "5";
BODY = "Q_RES","I18": #LOCATION = "R8104" !CDS_LOCATION = "R8104" &SEC = "1" #&CDS_SEC = "1";
"A":   PN = "1"  !CDS_PN = "1";
"B":   PN = "2"  !CDS_PN = "2";
BODY = "Q_RES","I20": #LOCATION = "R8105" !CDS_LOCATION = "R8105" &SEC = "1" #&CDS_SEC = "1";
"A":   PN = "1"  !CDS_PN = "1";
"B":   PN = "2"  !CDS_PN = "2";
BODY = "Q_CAP","I23": #LOCATION = "C8013" !CDS_LOCATION = "C8013" &SEC = "1" #&CDS_SEC = "1";
"A":   PN = "1"  !CDS_PN = "1";
"B":   PN = "2"  !CDS_PN = "2";
BODY = "Q_CAP","I25": #LOCATION = "C8012" !CDS_LOCATION = "C8012" &SEC = "1" #&CDS_SEC = "1";
"A":   PN = "1"  !CDS_PN = "1";
"B":   PN = "2"  !CDS_PN = "2";
BODY = "Q_RES","I27": #LOCATION = "R8103" !CDS_LOCATION = "R8103" &SEC = "1" #&CDS_SEC = "1";
"A":   PN = "1"  !CDS_PN = "1";
"B":   PN = "2"  !CDS_PN = "2";
BODY = "Q_RES","I31": #LOCATION = "R8106" !CDS_LOCATION = "R8106" &SEC = "1" #&CDS_SEC = "1";
"A":   PN = "1"  !CDS_PN = "1";
"B":   PN = "2"  !CDS_PN = "2";
DRAWING = "@t6g_mb_lib.t6g(sch_1):page348";
BODY = "Q_RES","I17": #LOCATION = "R6035" !CDS_LOCATION = "R6035" &SEC = "1" #&CDS_SEC = "1";
"A":   PN = "1"  !CDS_PN = "1";
"B":   PN = "2"  !CDS_PN = "2";
BODY = "Q_RES","I18": #LOCATION = "R6034" !CDS_LOCATION = "R6034" &SEC = "1" #&CDS_SEC = "1";
"A":   PN = "1"  !CDS_PN = "1";
"B":   PN = "2"  !CDS_PN = "2";
BODY = "Q_RES","I24": #LOCATION = "R321" !CDS_LOCATION = "R321" &SEC = "1" #&CDS_SEC = "1";
"A":   PN = "1"  !CDS_PN = "1";
"B":   PN = "2"  !CDS_PN = "2";
BODY = "Q_RES","I25": #LOCATION = "R3777" !CDS_LOCATION = "R3777" &SEC = "1" #&CDS_SEC = "1";
"A":   PN = "1"  !CDS_PN = "1";
"B":   PN = "2"  !CDS_PN = "2";
BODY = "Q_RES","I26": #LOCATION = "R1798" !CDS_LOCATION = "R1798" &SEC = "1" #&CDS_SEC = "1";
"A":   PN = "1"  !CDS_PN = "1";
"B":   PN = "2"  !CDS_PN = "2";
BODY = "Q_RES","I27": #LOCATION = "R3776" !CDS_LOCATION = "R3776" &SEC = "1" #&CDS_SEC = "1";
"A":   PN = "1"  !CDS_PN = "1";
"B":   PN = "2"  !CDS_PN = "2";
BODY = "Q_RES","I28": #LOCATION = "R6032" !CDS_LOCATION = "R6032" &SEC = "1" #&CDS_SEC = "1";
"A":   PN = "1"  !CDS_PN = "1";
"B":   PN = "2"  !CDS_PN = "2";
BODY = "Q_RES","I29": #LOCATION = "R1815" !CDS_LOCATION = "R1815" &SEC = "1" #&CDS_SEC = "1";
"A":   PN = "1"  !CDS_PN = "1";
"B":   PN = "2"  !CDS_PN = "2";
BODY = "Q_RES","I30": #LOCATION = "R6033" !CDS_LOCATION = "R6033" &SEC = "1" #&CDS_SEC = "1";
"A":   PN = "1"  !CDS_PN = "1";
"B":   PN = "2"  !CDS_PN = "2";
BODY = "Q_RES","I31": #LOCATION = "R4087" !CDS_LOCATION = "R4087" &SEC = "1" #&CDS_SEC = "1";
"A":   PN = "1"  !CDS_PN = "1";
"B":   PN = "2"  !CDS_PN = "2";
BODY = "Q_RES","I32": #LOCATION = "R1816" !CDS_LOCATION = "R1816" &SEC = "1" #&CDS_SEC = "1";
"A":   PN = "1"  !CDS_PN = "1";
"B":   PN = "2"  !CDS_PN = "2";
BODY = "Q_RES","I43": #LOCATION = "R6025" !CDS_LOCATION = "R6025" &SEC = "1" #&CDS_SEC = "1";
"A":   PN = "1"  !CDS_PN = "1";
"B":   PN = "2"  !CDS_PN = "2";
BODY = "Q_RES","I50": #LOCATION = "R3254" !CDS_LOCATION = "R3254" &SEC = "1" #&CDS_SEC = "1";
"A":   PN = "1"  !CDS_PN = "1";
"B":   PN = "2"  !CDS_PN = "2";
BODY = "Q_RES","I85": #LOCATION = "R2414" !CDS_LOCATION = "R2414" &SEC = "1" #&CDS_SEC = "1";
"A":   PN = "1"  !CDS_PN = "1";
"B":   PN = "2"  !CDS_PN = "2";
BODY = "Q_RES","I86": #LOCATION = "R2413" !CDS_LOCATION = "R2413" &SEC = "1" #&CDS_SEC = "1";
"A":   PN = "1"  !CDS_PN = "1";
"B":   PN = "2"  !CDS_PN = "2";
BODY = "Q_RES","I87": #LOCATION = "R4509" !CDS_LOCATION = "R4509" &SEC = "1" #&CDS_SEC = "1";
"A":   PN = "1"  !CDS_PN = "1";
"B":   PN = "2"  !CDS_PN = "2";
BODY = "Q_RES","I88": #LOCATION = "R4508" !CDS_LOCATION = "R4508" &SEC = "1" #&CDS_SEC = "1";
"A":   PN = "1"  !CDS_PN = "1";
"B":   PN = "2"  !CDS_PN = "2";
BODY = "Q_RES","I96": #LOCATION = "R3858" !CDS_LOCATION = "R3858" &SEC = "1" #&CDS_SEC = "1";
"A":   PN = "1"  !CDS_PN = "1";
"B":   PN = "2"  !CDS_PN = "2";
BODY = "Q_RES","I97": #LOCATION = "R2425" !CDS_LOCATION = "R2425" &SEC = "1" #&CDS_SEC = "1";
"A":   PN = "1"  !CDS_PN = "1";
"B":   PN = "2"  !CDS_PN = "2";
BODY = "Q_RES","I98": #LOCATION = "R2421" !CDS_LOCATION = "R2421" &SEC = "1" #&CDS_SEC = "1";
"A":   PN = "1"  !CDS_PN = "1";
"B":   PN = "2"  !CDS_PN = "2";
BODY = "Q_RES","I117": #LOCATION = "R6006" !CDS_LOCATION = "R6006" &SEC = "1" #&CDS_SEC = "1";
"A":   PN = "1"  !CDS_PN = "1";
"B":   PN = "2"  !CDS_PN = "2";
BODY = "Q_RES","I118": #LOCATION = "R6005" !CDS_LOCATION = "R6005" &SEC = "1" #&CDS_SEC = "1";
"A":   PN = "1"  !CDS_PN = "1";
"B":   PN = "2"  !CDS_PN = "2";
BODY = "Q_RES","I119": #LOCATION = "R6007" !CDS_LOCATION = "R6007" &SEC = "1" #&CDS_SEC = "1";
"A":   PN = "1"  !CDS_PN = "1";
"B":   PN = "2"  !CDS_PN = "2";
BODY = "Q_RES","I120": #LOCATION = "R6004" !CDS_LOCATION = "R6004" &SEC = "1" #&CDS_SEC = "1";
"A":   PN = "1"  !CDS_PN = "1";
"B":   PN = "2"  !CDS_PN = "2";
BODY = "Q_RES","I121": #LOCATION = "R6003" !CDS_LOCATION = "R6003" &SEC = "1" #&CDS_SEC = "1";
"A":   PN = "1"  !CDS_PN = "1";
"B":   PN = "2"  !CDS_PN = "2";
BODY = "Q_RES","I122": #LOCATION = "R6002" !CDS_LOCATION = "R6002" &SEC = "1" #&CDS_SEC = "1";
"A":   PN = "1"  !CDS_PN = "1";
"B":   PN = "2"  !CDS_PN = "2";
BODY = "Q_RES","I124": #LOCATION = "R6001" !CDS_LOCATION = "R6001" &SEC = "1" #&CDS_SEC = "1";
"A":   PN = "1"  !CDS_PN = "1";
"B":   PN = "2"  !CDS_PN = "2";
BODY = "Q_RES","I128": #LOCATION = "R6014" !CDS_LOCATION = "R6014" &SEC = "1" #&CDS_SEC = "1";
"A":   PN = "1"  !CDS_PN = "1";
"B":   PN = "2"  !CDS_PN = "2";
BODY = "Q_RES","I129": #LOCATION = "R6015" !CDS_LOCATION = "R6015" &SEC = "1" #&CDS_SEC = "1";
"A":   PN = "1"  !CDS_PN = "1";
"B":   PN = "2"  !CDS_PN = "2";
BODY = "Q_RES","I130": #LOCATION = "R6013" !CDS_LOCATION = "R6013" &SEC = "1" #&CDS_SEC = "1";
"A":   PN = "1"  !CDS_PN = "1";
"B":   PN = "2"  !CDS_PN = "2";
BODY = "Q_RES","I171": #LOCATION = "R1801" !CDS_LOCATION = "R1801" &SEC = "1" #&CDS_SEC = "1";
"A":   PN = "1"  !CDS_PN = "1";
"B":   PN = "2"  !CDS_PN = "2";
BODY = "SCONN168_ME1016810202011","I176": #LOCATION = "J41" !CDS_LOCATION = "J41" #SEC = "1" !CDS_SEC = "1";
"+3.3V_EDGE":   PN = "B11"  !CDS_PN = "B11";
"+12V_EDGE_B1":   PN = "B1"  !CDS_PN = "B1";
"+12V_EDGE_B2":   PN = "B2"  !CDS_PN = "B2";
"+12V_EDGE_B3":   PN = "B3"  !CDS_PN = "B3";
"+12V_EDGE_B4":   PN = "B4"  !CDS_PN = "B4";
"+12V_EDGE_B5":   PN = "B5"  !CDS_PN = "B5";
"+12V_EDGE_B6":   PN = "B6"  !CDS_PN = "B6";
"AUX_PWR_EN":   PN = "B12"  !CDS_PN = "B12";
"BIF0#":   PN = "B7"  !CDS_PN = "B7";
"BIF1#":   PN = "B8"  !CDS_PN = "B8";
"BIF2#":   PN = "B9"  !CDS_PN = "B9";
"CLK":   PN = "OB6"  !CDS_PN = "OB6";
"DATA_IN":   PN = "OB4"  !CDS_PN = "OB4";
"DATA_OUT":   PN = "OB5"  !CDS_PN = "OB5";
"G1":   PN = "G1"  !CDS_PN = "G1";
"G2":   PN = "G2"  !CDS_PN = "G2";
"G3":   PN = "G3"  !CDS_PN = "G3";
"G4":   PN = "G4"  !CDS_PN = "G4";
"G5":   PN = "G5"  !CDS_PN = "G5";
"GND_A1":   PN = "A1"  !CDS_PN = "A1";
"GND_A2":   PN = "A2"  !CDS_PN = "A2";
"GND_A3":   PN = "A3"  !CDS_PN = "A3";
"GND_A4":   PN = "A4"  !CDS_PN = "A4";
"GND_A5":   PN = "A5"  !CDS_PN = "A5";
"GND_A6":   PN = "A6"  !CDS_PN = "A6";
"GND_A13":   PN = "A13"  !CDS_PN = "A13";
"GND_A16":   PN = "A16"  !CDS_PN = "A16";
"GND_A19":   PN = "A19"  !CDS_PN = "A19";
"GND_A22":   PN = "A22"  !CDS_PN = "A22";
"GND_A25":   PN = "A25"  !CDS_PN = "A25";
"GND_A28":   PN = "A28"  !CDS_PN = "A28";
"GND_A29":   PN = "A29"  !CDS_PN = "A29";
"GND_A32":   PN = "A32"  !CDS_PN = "A32";
"GND_A35":   PN = "A35"  !CDS_PN = "A35";
"GND_A38":   PN = "A38"  !CDS_PN = "A38";
"GND_A41":   PN = "A41"  !CDS_PN = "A41";
"GND_A43":   PN = "A43"  !CDS_PN = "A43";
"GND_A46":   PN = "A46"  !CDS_PN = "A46";
"GND_A49":   PN = "A49"  !CDS_PN = "A49";
"GND_A52":   PN = "A52"  !CDS_PN = "A52";
"GND_A55":   PN = "A55"  !CDS_PN = "A55";
"GND_A58":   PN = "A58"  !CDS_PN = "A58";
"GND_A61":   PN = "A61"  !CDS_PN = "A61";
"GND_A64":   PN = "A64"  !CDS_PN = "A64";
"GND_A67":   PN = "A67"  !CDS_PN = "A67";
"GND_B13":   PN = "B13"  !CDS_PN = "B13";
"GND_B16":   PN = "B16"  !CDS_PN = "B16";
"GND_B19":   PN = "B19"  !CDS_PN = "B19";
"GND_B22":   PN = "B22"  !CDS_PN = "B22";
"GND_B25":   PN = "B25"  !CDS_PN = "B25";
"GND_B28":   PN = "B28"  !CDS_PN = "B28";
"GND_B29":   PN = "B29"  !CDS_PN = "B29";
"GND_B32":   PN = "B32"  !CDS_PN = "B32";
"GND_B35":   PN = "B35"  !CDS_PN = "B35";
"GND_B38":   PN = "B38"  !CDS_PN = "B38";
"GND_B41":   PN = "B41"  !CDS_PN = "B41";
"GND_B43":   PN = "B43"  !CDS_PN = "B43";
"GND_B46":   PN = "B46"  !CDS_PN = "B46";
"GND_B49":   PN = "B49"  !CDS_PN = "B49";
"GND_B52":   PN = "B52"  !CDS_PN = "B52";
"GND_B55":   PN = "B55"  !CDS_PN = "B55";
"GND_B58":   PN = "B58"  !CDS_PN = "B58";
"GND_B61":   PN = "B61"  !CDS_PN = "B61";
"GND_B64":   PN = "B64"  !CDS_PN = "B64";
"GND_B67":   PN = "B67"  !CDS_PN = "B67";
"GND_OA10":   PN = "OA10"  !CDS_PN = "OA10";
"GND_OA13":   PN = "OA13"  !CDS_PN = "OA13";
"GND_OB10":   PN = "OB10"  !CDS_PN = "OB10";
"GND_OB13":   PN = "OB13"  !CDS_PN = "OB13";
"LD#":   PN = "OB3"  !CDS_PN = "OB3";
"MAIN_PWR_EN":   PN = "OB2"  !CDS_PN = "OB2";
"NIC_PWR_GOOD":   PN = "OB1"  !CDS_PN = "OB1";
"PERN0":   PN = "A17"  !CDS_PN = "A17";
"PERN1":   PN = "A20"  !CDS_PN = "A20";
"PERN2":   PN = "A23"  !CDS_PN = "A23";
"PERN3":   PN = "A26"  !CDS_PN = "A26";
"PERN4":   PN = "A30"  !CDS_PN = "A30";
"PERN5":   PN = "A33"  !CDS_PN = "A33";
"PERN6":   PN = "A36"  !CDS_PN = "A36";
"PERN7":   PN = "A39"  !CDS_PN = "A39";
"PERN8":   PN = "A44"  !CDS_PN = "A44";
"PERN9":   PN = "A47"  !CDS_PN = "A47";
"PERN10":   PN = "A50"  !CDS_PN = "A50";
"PERN11":   PN = "A53"  !CDS_PN = "A53";
"PERN12":   PN = "A56"  !CDS_PN = "A56";
"PERN13":   PN = "A59"  !CDS_PN = "A59";
"PERN14":   PN = "A62"  !CDS_PN = "A62";
"PERN15":   PN = "A65"  !CDS_PN = "A65";
"PERP0":   PN = "A18"  !CDS_PN = "A18";
"PERP1":   PN = "A21"  !CDS_PN = "A21";
"PERP2":   PN = "A24"  !CDS_PN = "A24";
"PERP3":   PN = "A27"  !CDS_PN = "A27";
"PERP4":   PN = "A31"  !CDS_PN = "A31";
"PERP5":   PN = "A34"  !CDS_PN = "A34";
"PERP6":   PN = "A37"  !CDS_PN = "A37";
"PERP7":   PN = "A40"  !CDS_PN = "A40";
"PERP8":   PN = "A45"  !CDS_PN = "A45";
"PERP9":   PN = "A48"  !CDS_PN = "A48";
"PERP10":   PN = "A51"  !CDS_PN = "A51";
"PERP11":   PN = "A54"  !CDS_PN = "A54";
"PERP12":   PN = "A57"  !CDS_PN = "A57";
"PERP13":   PN = "A60"  !CDS_PN = "A60";
"PERP14":   PN = "A63"  !CDS_PN = "A63";
"PERP15":   PN = "A66"  !CDS_PN = "A66";
"PERST0#":   PN = "B10"  !CDS_PN = "B10";
"PERST1#":   PN = "A11"  !CDS_PN = "A11";
"PERST2#":   PN = "OA1"  !CDS_PN = "OA1";
"PERST3#":   PN = "OA2"  !CDS_PN = "OA2";
"PETN0":   PN = "B17"  !CDS_PN = "B17";
"PETN1":   PN = "B20"  !CDS_PN = "B20";
"PETN2":   PN = "B23"  !CDS_PN = "B23";
"PETN3":   PN = "B26"  !CDS_PN = "B26";
"PETN4":   PN = "B30"  !CDS_PN = "B30";
"PETN5":   PN = "B33"  !CDS_PN = "B33";
"PETN6":   PN = "B36"  !CDS_PN = "B36";
"PETN7":   PN = "B39"  !CDS_PN = "B39";
"PETN8":   PN = "B44"  !CDS_PN = "B44";
"PETN9":   PN = "B47"  !CDS_PN = "B47";
"PETN10":   PN = "B50"  !CDS_PN = "B50";
"PETN11":   PN = "B53"  !CDS_PN = "B53";
"PETN12":   PN = "B56"  !CDS_PN = "B56";
"PETN13":   PN = "B59"  !CDS_PN = "B59";
"PETN14":   PN = "B62"  !CDS_PN = "B62";
"PETN15":   PN = "B65"  !CDS_PN = "B65";
"PETP0":   PN = "B18"  !CDS_PN = "B18";
"PETP1":   PN = "B21"  !CDS_PN = "B21";
"PETP2":   PN = "B24"  !CDS_PN = "B24";
"PETP3":   PN = "B27"  !CDS_PN = "B27";
"PETP4":   PN = "B31"  !CDS_PN = "B31";
"PETP5":   PN = "B34"  !CDS_PN = "B34";
"PETP6":   PN = "B37"  !CDS_PN = "B37";
"PETP7":   PN = "B40"  !CDS_PN = "B40";
"PETP8":   PN = "B45"  !CDS_PN = "B45";
"PETP9":   PN = "B48"  !CDS_PN = "B48";
"PETP10":   PN = "B51"  !CDS_PN = "B51";
"PETP11":   PN = "B54"  !CDS_PN = "B54";
"PETP12":   PN = "B57"  !CDS_PN = "B57";
"PETP13":   PN = "B60"  !CDS_PN = "B60";
"PETP14":   PN = "B63"  !CDS_PN = "B63";
"PETP15":   PN = "B66"  !CDS_PN = "B66";
"PRSNTA#":   PN = "A10"  !CDS_PN = "A10";
"PRSNTB0#":   PN = "B42"  !CDS_PN = "B42";
"PRSNTB1#":   PN = "A42"  !CDS_PN = "A42";
"PRSNTB2#":   PN = "A12"  !CDS_PN = "A12";
"PRSNTB3#":   PN = "B70"  !CDS_PN = "B70";
"PWRBRK0#":   PN = "A70"  !CDS_PN = "A70";
"RBT_ARB_IN":   PN = "OA4"  !CDS_PN = "OA4";
"RBT_ARB_OUT":   PN = "OA5"  !CDS_PN = "OA5";
"RBT_CLK_IN":   PN = "OA14"  !CDS_PN = "OA14";
"RBT_CRS_DV":   PN = "OB14"  !CDS_PN = "OB14";
"RBT_RXD0":   PN = "OB9"  !CDS_PN = "OB9";
"RBT_RXD1":   PN = "OB8"  !CDS_PN = "OB8";
"RBT_TX_EN":   PN = "OA7"  !CDS_PN = "OA7";
"RBT_TXD0":   PN = "OA9"  !CDS_PN = "OA9";
"RBT_TXD1":   PN = "OA8"  !CDS_PN = "OA8";
"REFCLKN0":   PN = "B14"  !CDS_PN = "B14";
"REFCLKN1":   PN = "A14"  !CDS_PN = "A14";
"REFCLKN2":   PN = "OB11"  !CDS_PN = "OB11";
"REFCLKN3":   PN = "OA11"  !CDS_PN = "OA11";
"REFCLKP0":   PN = "B15"  !CDS_PN = "B15";
"REFCLKP1":   PN = "A15"  !CDS_PN = "A15";
"REFCLKP2":   PN = "OB12"  !CDS_PN = "OB12";
"REFCLKP3":   PN = "OA12"  !CDS_PN = "OA12";
"RFU1_NC_B68":   PN = "B68"  !CDS_PN = "B68";
"RFU1_NC_B69":   PN = "B69"  !CDS_PN = "B69";
"SLOT_ID0":   PN = "OB7"  !CDS_PN = "OB7";
"SLOT_ID1":   PN = "OA6"  !CDS_PN = "OA6";
"SMCLK":   PN = "A7"  !CDS_PN = "A7";
"SMDAT":   PN = "A8"  !CDS_PN = "A8";
"SMRST#":   PN = "A9"  !CDS_PN = "A9";
"USB_DATN":   PN = "A68"  !CDS_PN = "A68";
"USB_DATP":   PN = "A69"  !CDS_PN = "A69";
"WAKE#":   PN = "OA3"  !CDS_PN = "OA3";
BODY = "Q_RES","I33": #LOCATION = "R2416" !CDS_LOCATION = "R2416" &SEC = "1" #&CDS_SEC = "1";
"A":   PN = "1"  !CDS_PN = "1";
"B":   PN = "2"  !CDS_PN = "2";
BODY = "Q_RES","I34": #LOCATION = "R2418" !CDS_LOCATION = "R2418" &SEC = "1" #&CDS_SEC = "1";
"A":   PN = "1"  !CDS_PN = "1";
"B":   PN = "2"  !CDS_PN = "2";
BODY = "Q_RES","I35": #LOCATION = "R2417" !CDS_LOCATION = "R2417" &SEC = "1" #&CDS_SEC = "1";
"A":   PN = "1"  !CDS_PN = "1";
"B":   PN = "2"  !CDS_PN = "2";
BODY = "Q_RES","I42": #LOCATION = "R6026" !CDS_LOCATION = "R6026" &SEC = "1" #&CDS_SEC = "1";
"A":   PN = "1"  !CDS_PN = "1";
"B":   PN = "2"  !CDS_PN = "2";
BODY = "Q_RES","I60": #LOCATION = "R2415" !CDS_LOCATION = "R2415" &SEC = "1" #&CDS_SEC = "1";
"A":   PN = "1"  !CDS_PN = "1";
"B":   PN = "2"  !CDS_PN = "2";
BODY = "Q_RES","I101": #LOCATION = "R2422" !CDS_LOCATION = "R2422" &SEC = "1" #&CDS_SEC = "1";
"A":   PN = "1"  !CDS_PN = "1";
"B":   PN = "2"  !CDS_PN = "2";
BODY = "Q_RES","I102": #LOCATION = "R3239" !CDS_LOCATION = "R3239" &SEC = "1" #&CDS_SEC = "1";
"A":   PN = "1"  !CDS_PN = "1";
"B":   PN = "2"  !CDS_PN = "2";
BODY = "Q_RES","I103": #LOCATION = "R3238" !CDS_LOCATION = "R3238" &SEC = "1" #&CDS_SEC = "1";
"A":   PN = "1"  !CDS_PN = "1";
"B":   PN = "2"  !CDS_PN = "2";
BODY = "Q_RES","I104": #LOCATION = "R2419" !CDS_LOCATION = "R2419" &SEC = "1" #&CDS_SEC = "1";
"A":   PN = "1"  !CDS_PN = "1";
"B":   PN = "2"  !CDS_PN = "2";
BODY = "Q_RES","I105": #LOCATION = "R2420" !CDS_LOCATION = "R2420" &SEC = "1" #&CDS_SEC = "1";
"A":   PN = "1"  !CDS_PN = "1";
"B":   PN = "2"  !CDS_PN = "2";
BODY = "Q_RES","I123": #LOCATION = "R6000" !CDS_LOCATION = "R6000" &SEC = "1" #&CDS_SEC = "1";
"A":   PN = "1"  !CDS_PN = "1";
"B":   PN = "2"  !CDS_PN = "2";
BODY = "Q_RES","I131": #LOCATION = "R6012" !CDS_LOCATION = "R6012" &SEC = "1" #&CDS_SEC = "1";
"A":   PN = "1"  !CDS_PN = "1";
"B":   PN = "2"  !CDS_PN = "2";
BODY = "Q_RES","I132": #LOCATION = "R6011" !CDS_LOCATION = "R6011" &SEC = "1" #&CDS_SEC = "1";
"A":   PN = "1"  !CDS_PN = "1";
"B":   PN = "2"  !CDS_PN = "2";
BODY = "Q_RES","I133": #LOCATION = "R6010" !CDS_LOCATION = "R6010" &SEC = "1" #&CDS_SEC = "1";
"A":   PN = "1"  !CDS_PN = "1";
"B":   PN = "2"  !CDS_PN = "2";
BODY = "Q_RES","I134": #LOCATION = "R6009" !CDS_LOCATION = "R6009" &SEC = "1" #&CDS_SEC = "1";
"A":   PN = "1"  !CDS_PN = "1";
"B":   PN = "2"  !CDS_PN = "2";
BODY = "Q_RES","I135": #LOCATION = "R6008" !CDS_LOCATION = "R6008" &SEC = "1" #&CDS_SEC = "1";
"A":   PN = "1"  !CDS_PN = "1";
"B":   PN = "2"  !CDS_PN = "2";
BODY = "Q_RES","I169": #LOCATION = "R3778" !CDS_LOCATION = "R3778" &SEC = "1" #&CDS_SEC = "1";
"A":   PN = "1"  !CDS_PN = "1";
"B":   PN = "2"  !CDS_PN = "2";
BODY = "Q_RES","I174": #LOCATION = "R6028" !CDS_LOCATION = "R6028" &SEC = "1" #&CDS_SEC = "1";
"A":   PN = "1"  !CDS_PN = "1";
"B":   PN = "2"  !CDS_PN = "2";
BODY = "Q_RES","I177": #LOCATION = "R6064" !CDS_LOCATION = "R6064" &SEC = "1" #&CDS_SEC = "1";
"A":   PN = "1"  !CDS_PN = "1";
"B":   PN = "2"  !CDS_PN = "2";
BODY = "Q_RES","I178": #LOCATION = "R6065" !CDS_LOCATION = "R6065" &SEC = "1" #&CDS_SEC = "1";
"A":   PN = "1"  !CDS_PN = "1";
"B":   PN = "2"  !CDS_PN = "2";
BODY = "Q_RES","I190": #LOCATION = "R4507" !CDS_LOCATION = "R4507" &SEC = "1" #&CDS_SEC = "1";
"A":   PN = "1"  !CDS_PN = "1";
"B":   PN = "2"  !CDS_PN = "2";
BODY = "Q_RES","I191": #LOCATION = "R4506" !CDS_LOCATION = "R4506" &SEC = "1" #&CDS_SEC = "1";
"A":   PN = "1"  !CDS_PN = "1";
"B":   PN = "2"  !CDS_PN = "2";
BODY = "Q_RES","I195": #LOCATION = "R2424" !CDS_LOCATION = "R2424" &SEC = "1" #&CDS_SEC = "1";
"A":   PN = "1"  !CDS_PN = "1";
"B":   PN = "2"  !CDS_PN = "2";
BODY = "Q_RES","I196": #LOCATION = "R2423" !CDS_LOCATION = "R2423" &SEC = "1" #&CDS_SEC = "1";
"A":   PN = "1"  !CDS_PN = "1";
"B":   PN = "2"  !CDS_PN = "2";
BODY = "Q_RES","I214": #LOCATION = "R6071" !CDS_LOCATION = "R6071" &SEC = "1" #&CDS_SEC = "1";
"A":   PN = "1"  !CDS_PN = "1";
"B":   PN = "2"  !CDS_PN = "2";
BODY = "Q_RES","I215": #LOCATION = "R8101" !CDS_LOCATION = "R8101" &SEC = "1" #&CDS_SEC = "1";
"A":   PN = "1"  !CDS_PN = "1";
"B":   PN = "2"  !CDS_PN = "2";
BODY = "Q_CAP","I219": #LOCATION = "C6000" !CDS_LOCATION = "C6000" &SEC = "1" #&CDS_SEC = "1";
"A":   PN = "1"  !CDS_PN = "1";
"B":   PN = "2"  !CDS_PN = "2";
BODY = "Q_RES","I220": #LOCATION = "R4809" !CDS_LOCATION = "R4809" &SEC = "1" #&CDS_SEC = "1";
"A":   PN = "1"  !CDS_PN = "1";
"B":   PN = "2"  !CDS_PN = "2";
DRAWING = "@t6g_mb_lib.t6g(sch_1):page349";
BODY = "Q_RES","I28": #LOCATION = "R6017" !CDS_LOCATION = "R6017" &SEC = "1" #&CDS_SEC = "1";
"A":   PN = "1"  !CDS_PN = "1";
"B":   PN = "2"  !CDS_PN = "2";
BODY = "Q_RES","I29": #LOCATION = "R6016" !CDS_LOCATION = "R6016" &SEC = "1" #&CDS_SEC = "1";
"A":   PN = "1"  !CDS_PN = "1";
"B":   PN = "2"  !CDS_PN = "2";
BODY = "Q_RES","I30": #LOCATION = "R1546" !CDS_LOCATION = "R1546" &SEC = "1" #&CDS_SEC = "1";
"A":   PN = "1"  !CDS_PN = "1";
"B":   PN = "2"  !CDS_PN = "2";
BODY = "Q_RES","I32": #LOCATION = "R6027" !CDS_LOCATION = "R6027" &SEC = "1" #&CDS_SEC = "1";
"A":   PN = "1"  !CDS_PN = "1";
"B":   PN = "2"  !CDS_PN = "2";
BODY = "Q_RES","I57": #LOCATION = "R1447" !CDS_LOCATION = "R1447" &SEC = "1" #&CDS_SEC = "1";
"A":   PN = "1"  !CDS_PN = "1";
"B":   PN = "2"  !CDS_PN = "2";
BODY = "Q_RES","I84": #LOCATION = "R4152" !CDS_LOCATION = "R4152" &SEC = "1" #&CDS_SEC = "1";
"A":   PN = "1"  !CDS_PN = "1";
"B":   PN = "2"  !CDS_PN = "2";
BODY = "Q_CAP","I112": #LOCATION = "C63" !CDS_LOCATION = "C63" &SEC = "1" #&CDS_SEC = "1";
"A":   PN = "1"  !CDS_PN = "1";
"B":   PN = "2"  !CDS_PN = "2";
BODY = "Q_RES","I115": #LOCATION = "R3243" !CDS_LOCATION = "R3243" &SEC = "1" #&CDS_SEC = "1";
"A":   PN = "1"  !CDS_PN = "1";
"B":   PN = "2"  !CDS_PN = "2";
BODY = "Q_RES","I116": #LOCATION = "R131" !CDS_LOCATION = "R131" &SEC = "1" #&CDS_SEC = "1";
"A":   PN = "1"  !CDS_PN = "1";
"B":   PN = "2"  !CDS_PN = "2";
BODY = "Q_RES","I120": #LOCATION = "R3240" !CDS_LOCATION = "R3240" &SEC = "1" #&CDS_SEC = "1";
"A":   PN = "1"  !CDS_PN = "1";
"B":   PN = "2"  !CDS_PN = "2";
BODY = "Q_RES","I121": #LOCATION = "R3227" !CDS_LOCATION = "R3227" &SEC = "1" #&CDS_SEC = "1";
"A":   PN = "1"  !CDS_PN = "1";
"B":   PN = "2"  !CDS_PN = "2";
BODY = "Q_RES","I122": #LOCATION = "R3226" !CDS_LOCATION = "R3226" &SEC = "1" #&CDS_SEC = "1";
"A":   PN = "1"  !CDS_PN = "1";
"B":   PN = "2"  !CDS_PN = "2";
BODY = "Q_RES","I123": #LOCATION = "R3004" !CDS_LOCATION = "R3004" &SEC = "1" #&CDS_SEC = "1";
"A":   PN = "1"  !CDS_PN = "1";
"B":   PN = "2"  !CDS_PN = "2";
BODY = "Q_RES","I124": #LOCATION = "R2999" !CDS_LOCATION = "R2999" &SEC = "1" #&CDS_SEC = "1";
"A":   PN = "1"  !CDS_PN = "1";
"B":   PN = "2"  !CDS_PN = "2";
BODY = "Q_RES","I125": #LOCATION = "R2213" !CDS_LOCATION = "R2213" &SEC = "1" #&CDS_SEC = "1";
"A":   PN = "1"  !CDS_PN = "1";
"B":   PN = "2"  !CDS_PN = "2";
BODY = "Q_RES","I126": #LOCATION = "R2212" !CDS_LOCATION = "R2212" &SEC = "1" #&CDS_SEC = "1";
"A":   PN = "1"  !CDS_PN = "1";
"B":   PN = "2"  !CDS_PN = "2";
BODY = "Q_RES","I127": #LOCATION = "R1460" !CDS_LOCATION = "R1460" &SEC = "1" #&CDS_SEC = "1";
"A":   PN = "1"  !CDS_PN = "1";
"B":   PN = "2"  !CDS_PN = "2";
BODY = "Q_RES","I128": #LOCATION = "R332" !CDS_LOCATION = "R332" &SEC = "1" #&CDS_SEC = "1";
"A":   PN = "1"  !CDS_PN = "1";
"B":   PN = "2"  !CDS_PN = "2";
BODY = "Q_RES","I129": #LOCATION = "R331" !CDS_LOCATION = "R331" &SEC = "1" #&CDS_SEC = "1";
"A":   PN = "1"  !CDS_PN = "1";
"B":   PN = "2"  !CDS_PN = "2";
BODY = "Q_RES","I130": #LOCATION = "R330" !CDS_LOCATION = "R330" &SEC = "1" #&CDS_SEC = "1";
"A":   PN = "1"  !CDS_PN = "1";
"B":   PN = "2"  !CDS_PN = "2";
BODY = "Q_RES","I131": #LOCATION = "R6036" !CDS_LOCATION = "R6036" &SEC = "1" #&CDS_SEC = "1";
"A":   PN = "1"  !CDS_PN = "1";
"B":   PN = "2"  !CDS_PN = "2";
BODY = "Q_RES","I132": #LOCATION = "R6037" !CDS_LOCATION = "R6037" &SEC = "1" #&CDS_SEC = "1";
"A":   PN = "1"  !CDS_PN = "1";
"B":   PN = "2"  !CDS_PN = "2";
BODY = "Q_RES","I133": #LOCATION = "R329" !CDS_LOCATION = "R329" &SEC = "1" #&CDS_SEC = "1";
"A":   PN = "1"  !CDS_PN = "1";
"B":   PN = "2"  !CDS_PN = "2";
BODY = "Q_RES","I134": #LOCATION = "R1386" !CDS_LOCATION = "R1386" &SEC = "1" #&CDS_SEC = "1";
"A":   PN = "1"  !CDS_PN = "1";
"B":   PN = "2"  !CDS_PN = "2";
BODY = "Q_RES","I135": #LOCATION = "R1385" !CDS_LOCATION = "R1385" &SEC = "1" #&CDS_SEC = "1";
"A":   PN = "1"  !CDS_PN = "1";
"B":   PN = "2"  !CDS_PN = "2";
BODY = "Q_RES","I136": #LOCATION = "R1384" !CDS_LOCATION = "R1384" &SEC = "1" #&CDS_SEC = "1";
"A":   PN = "1"  !CDS_PN = "1";
"B":   PN = "2"  !CDS_PN = "2";
BODY = "Q_RES","I137": #LOCATION = "R3062" !CDS_LOCATION = "R3062" &SEC = "1" #&CDS_SEC = "1";
"A":   PN = "1"  !CDS_PN = "1";
"B":   PN = "2"  !CDS_PN = "2";
BODY = "Q_RES","I138": #LOCATION = "R1319" !CDS_LOCATION = "R1319" &SEC = "1" #&CDS_SEC = "1";
"A":   PN = "1"  !CDS_PN = "1";
"B":   PN = "2"  !CDS_PN = "2";
BODY = "Q_RES","I145": #LOCATION = "R888" !CDS_LOCATION = "R888" &SEC = "1" #&CDS_SEC = "1";
"A":   PN = "1"  !CDS_PN = "1";
"B":   PN = "2"  !CDS_PN = "2";
BODY = "Q_RES","I147": #LOCATION = "R890" !CDS_LOCATION = "R890" &SEC = "1" #&CDS_SEC = "1";
"A":   PN = "1"  !CDS_PN = "1";
"B":   PN = "2"  !CDS_PN = "2";
BODY = "CONN4_HFK1040L0P1L7H","I148": #LOCATION = "J8" !CDS_LOCATION = "J8" &SEC = "1" #&CDS_SEC = "1";
"1":   PN = "1"  !CDS_PN = "1";
"2":   PN = "2"  !CDS_PN = "2";
"3":   PN = "3"  !CDS_PN = "3";
"4":   PN = "4"  !CDS_PN = "4";
BODY = "Q_RES","I9": #LOCATION = "R1494" !CDS_LOCATION = "R1494" &SEC = "1" #&CDS_SEC = "1";
"A":   PN = "1"  !CDS_PN = "1";
"B":   PN = "2"  !CDS_PN = "2";
BODY = "Q_RES","I10": #LOCATION = "R1321" !CDS_LOCATION = "R1321" &SEC = "1" #&CDS_SEC = "1";
"A":   PN = "1"  !CDS_PN = "1";
"B":   PN = "2"  !CDS_PN = "2";
BODY = "Q_RES","I17": #LOCATION = "R633" !CDS_LOCATION = "R633" &SEC = "1" #&CDS_SEC = "1";
"A":   PN = "1"  !CDS_PN = "1";
"B":   PN = "2"  !CDS_PN = "2";
BODY = "Q_RES","I18": #LOCATION = "R632" !CDS_LOCATION = "R632" &SEC = "1" #&CDS_SEC = "1";
"A":   PN = "1"  !CDS_PN = "1";
"B":   PN = "2"  !CDS_PN = "2";
BODY = "Q_RES","I20": #LOCATION = "R6024" !CDS_LOCATION = "R6024" &SEC = "1" #&CDS_SEC = "1";
"A":   PN = "1"  !CDS_PN = "1";
"B":   PN = "2"  !CDS_PN = "2";
BODY = "Q_RES","I21": #LOCATION = "R6023" !CDS_LOCATION = "R6023" &SEC = "1" #&CDS_SEC = "1";
"A":   PN = "1"  !CDS_PN = "1";
"B":   PN = "2"  !CDS_PN = "2";
BODY = "Q_RES","I22": #LOCATION = "R6021" !CDS_LOCATION = "R6021" &SEC = "1" #&CDS_SEC = "1";
"A":   PN = "1"  !CDS_PN = "1";
"B":   PN = "2"  !CDS_PN = "2";
BODY = "Q_RES","I23": #LOCATION = "R6022" !CDS_LOCATION = "R6022" &SEC = "1" #&CDS_SEC = "1";
"A":   PN = "1"  !CDS_PN = "1";
"B":   PN = "2"  !CDS_PN = "2";
BODY = "Q_RES","I24": #LOCATION = "R6020" !CDS_LOCATION = "R6020" &SEC = "1" #&CDS_SEC = "1";
"A":   PN = "1"  !CDS_PN = "1";
"B":   PN = "2"  !CDS_PN = "2";
BODY = "Q_RES","I25": #LOCATION = "R6019" !CDS_LOCATION = "R6019" &SEC = "1" #&CDS_SEC = "1";
"A":   PN = "1"  !CDS_PN = "1";
"B":   PN = "2"  !CDS_PN = "2";
BODY = "Q_RES","I27": #LOCATION = "R6018" !CDS_LOCATION = "R6018" &SEC = "1" #&CDS_SEC = "1";
"A":   PN = "1"  !CDS_PN = "1";
"B":   PN = "2"  !CDS_PN = "2";
BODY = "Q_RES","I48": #LOCATION = "R1496" !CDS_LOCATION = "R1496" &SEC = "1" #&CDS_SEC = "1";
"A":   PN = "1"  !CDS_PN = "1";
"B":   PN = "2"  !CDS_PN = "2";
BODY = "Q_RES","I49": #LOCATION = "R1495" !CDS_LOCATION = "R1495" &SEC = "1" #&CDS_SEC = "1";
"A":   PN = "1"  !CDS_PN = "1";
"B":   PN = "2"  !CDS_PN = "2";
BODY = "Q_RES","I56": #LOCATION = "R1453" !CDS_LOCATION = "R1453" &SEC = "1" #&CDS_SEC = "1";
"A":   PN = "1"  !CDS_PN = "1";
"B":   PN = "2"  !CDS_PN = "2";
BODY = "Q_CAP","I69": #LOCATION = "C62" !CDS_LOCATION = "C62" &SEC = "1" #&CDS_SEC = "1";
"A":   PN = "1"  !CDS_PN = "1";
"B":   PN = "2"  !CDS_PN = "2";
BODY = "Q_RES","I81": #LOCATION = "R3340" !CDS_LOCATION = "R3340" &SEC = "1" #&CDS_SEC = "1";
"A":   PN = "1"  !CDS_PN = "1";
"B":   PN = "2"  !CDS_PN = "2";
BODY = "Q_RES","I82": #LOCATION = "R3341" !CDS_LOCATION = "R3341" &SEC = "1" #&CDS_SEC = "1";
"A":   PN = "1"  !CDS_PN = "1";
"B":   PN = "2"  !CDS_PN = "2";
BODY = "Q_RES","I83": #LOCATION = "R4151" !CDS_LOCATION = "R4151" &SEC = "1" #&CDS_SEC = "1";
"A":   PN = "1"  !CDS_PN = "1";
"B":   PN = "2"  !CDS_PN = "2";
BODY = "Q_RES","I89": #LOCATION = "R4149" !CDS_LOCATION = "R4149" &SEC = "1" #&CDS_SEC = "1";
"A":   PN = "1"  !CDS_PN = "1";
"B":   PN = "2"  !CDS_PN = "2";
BODY = "Q_RES","I90": #LOCATION = "R4150" !CDS_LOCATION = "R4150" &SEC = "1" #&CDS_SEC = "1";
"A":   PN = "1"  !CDS_PN = "1";
"B":   PN = "2"  !CDS_PN = "2";
BODY = "Q_RES","I91": #LOCATION = "R2995" !CDS_LOCATION = "R2995" &SEC = "1" #&CDS_SEC = "1";
"A":   PN = "1"  !CDS_PN = "1";
"B":   PN = "2"  !CDS_PN = "2";
BODY = "Q_RES","I92": #LOCATION = "R2996" !CDS_LOCATION = "R2996" &SEC = "1" #&CDS_SEC = "1";
"A":   PN = "1"  !CDS_PN = "1";
"B":   PN = "2"  !CDS_PN = "2";
BODY = "Q_RES","I113": #LOCATION = "R130" !CDS_LOCATION = "R130" &SEC = "1" #&CDS_SEC = "1";
"A":   PN = "1"  !CDS_PN = "1";
"B":   PN = "2"  !CDS_PN = "2";
BODY = "Q_RES","I119": #LOCATION = "R3242" !CDS_LOCATION = "R3242" &SEC = "1" #&CDS_SEC = "1";
"A":   PN = "1"  !CDS_PN = "1";
"B":   PN = "2"  !CDS_PN = "2";
BODY = "Q_RES","I142": #LOCATION = "R889" !CDS_LOCATION = "R889" &SEC = "1" #&CDS_SEC = "1";
"A":   PN = "1"  !CDS_PN = "1";
"B":   PN = "2"  !CDS_PN = "2";
BODY = "Q_RES","I144": #LOCATION = "R891" !CDS_LOCATION = "R891" &SEC = "1" #&CDS_SEC = "1";
"A":   PN = "1"  !CDS_PN = "1";
"B":   PN = "2"  !CDS_PN = "2";
BODY = "Q_RES","I149": #LOCATION = "R3241" !CDS_LOCATION = "R3241" &SEC = "1" #&CDS_SEC = "1";
"A":   PN = "1"  !CDS_PN = "1";
"B":   PN = "2"  !CDS_PN = "2";
BODY = "Q_RES","I150": #LOCATION = "R6066" !CDS_LOCATION = "R6066" &SEC = "1" #&CDS_SEC = "1";
"A":   PN = "1"  !CDS_PN = "1";
"B":   PN = "2"  !CDS_PN = "2";
BODY = "Q_RES","I151": #LOCATION = "R6068" !CDS_LOCATION = "R6068" &SEC = "1" #&CDS_SEC = "1";
"A":   PN = "1"  !CDS_PN = "1";
"B":   PN = "2"  !CDS_PN = "2";
BODY = "Q_RES","I158": #LOCATION = "R6069" !CDS_LOCATION = "R6069" &SEC = "1" #&CDS_SEC = "1";
"A":   PN = "1"  !CDS_PN = "1";
"B":   PN = "2"  !CDS_PN = "2";
BODY = "Q_RES","I159": #LOCATION = "R6067" !CDS_LOCATION = "R6067" &SEC = "1" #&CDS_SEC = "1";
"A":   PN = "1"  !CDS_PN = "1";
"B":   PN = "2"  !CDS_PN = "2";
BODY = "Q_RES","I161": #LOCATION = "R6070" !CDS_LOCATION = "R6070" &SEC = "1" #&CDS_SEC = "1";
"A":   PN = "1"  !CDS_PN = "1";
"B":   PN = "2"  !CDS_PN = "2";
BODY = "Q_RES","I172": #LOCATION = "R348" !CDS_LOCATION = "R348" &SEC = "1" #&CDS_SEC = "1";
"A":   PN = "1"  !CDS_PN = "1";
"B":   PN = "2"  !CDS_PN = "2";
BODY = "Q_RES","I173": #LOCATION = "R347" !CDS_LOCATION = "R347" &SEC = "1" #&CDS_SEC = "1";
"A":   PN = "1"  !CDS_PN = "1";
"B":   PN = "2"  !CDS_PN = "2";
BODY = "Q_RES","I176": #LOCATION = "R1497" !CDS_LOCATION = "R1497" &SEC = "1" #&CDS_SEC = "1";
"A":   PN = "1"  !CDS_PN = "1";
"B":   PN = "2"  !CDS_PN = "2";
BODY = "Q_RES","I181": #LOCATION = "R6076" !CDS_LOCATION = "R6076" &SEC = "1" #&CDS_SEC = "1";
"A":   PN = "1"  !CDS_PN = "1";
"B":   PN = "2"  !CDS_PN = "2";
BODY = "Q_RES","I182": #LOCATION = "R6077" !CDS_LOCATION = "R6077" &SEC = "1" #&CDS_SEC = "1";
"A":   PN = "1"  !CDS_PN = "1";
"B":   PN = "2"  !CDS_PN = "2";
BODY = "Q_RES","I183": #LOCATION = "R1498" !CDS_LOCATION = "R1498" &SEC = "1" #&CDS_SEC = "1";
"A":   PN = "1"  !CDS_PN = "1";
"B":   PN = "2"  !CDS_PN = "2";
BODY = "Q_RES","I184": #LOCATION = "R350" !CDS_LOCATION = "R350" &SEC = "1" #&CDS_SEC = "1";
"A":   PN = "1"  !CDS_PN = "1";
"B":   PN = "2"  !CDS_PN = "2";
BODY = "Q_RES","I185": #LOCATION = "R349" !CDS_LOCATION = "R349" &SEC = "1" #&CDS_SEC = "1";
"A":   PN = "1"  !CDS_PN = "1";
"B":   PN = "2"  !CDS_PN = "2";
BODY = "Q_RES","I186": #LOCATION = "R352" !CDS_LOCATION = "R352" &SEC = "1" #&CDS_SEC = "1";
"A":   PN = "1"  !CDS_PN = "1";
"B":   PN = "2"  !CDS_PN = "2";
BODY = "Q_RES","I187": #LOCATION = "R351" !CDS_LOCATION = "R351" &SEC = "1" #&CDS_SEC = "1";
"A":   PN = "1"  !CDS_PN = "1";
"B":   PN = "2"  !CDS_PN = "2";
BODY = "Q_RES","I198": #LOCATION = "R6784" !CDS_LOCATION = "R6784" &SEC = "1" #&CDS_SEC = "1";
"A":   PN = "1"  !CDS_PN = "1";
"B":   PN = "2"  !CDS_PN = "2";
BODY = "Q_RES","I199": #LOCATION = "R6785" !CDS_LOCATION = "R6785" &SEC = "1" #&CDS_SEC = "1";
"A":   PN = "1"  !CDS_PN = "1";
"B":   PN = "2"  !CDS_PN = "2";
BODY = "Q_RES","I206": #LOCATION = "R6859" !CDS_LOCATION = "R6859" &SEC = "1" #&CDS_SEC = "1";
"A":   PN = "1"  !CDS_PN = "1";
"B":   PN = "2"  !CDS_PN = "2";
BODY = "Q_RES","I207": #LOCATION = "R6858" !CDS_LOCATION = "R6858" &SEC = "1" #&CDS_SEC = "1";
"A":   PN = "1"  !CDS_PN = "1";
"B":   PN = "2"  !CDS_PN = "2";
BODY = "Q_RES","I218": #LOCATION = "R6862" !CDS_LOCATION = "R6862" &SEC = "1" #&CDS_SEC = "1";
"A":   PN = "1"  !CDS_PN = "1";
"B":   PN = "2"  !CDS_PN = "2";
BODY = "Q_RES","I219": #LOCATION = "R6863" !CDS_LOCATION = "R6863" &SEC = "1" #&CDS_SEC = "1";
"A":   PN = "1"  !CDS_PN = "1";
"B":   PN = "2"  !CDS_PN = "2";
BODY = "Q_RES","I220": #LOCATION = "R6864" !CDS_LOCATION = "R6864" &SEC = "1" #&CDS_SEC = "1";
"A":   PN = "1"  !CDS_PN = "1";
"B":   PN = "2"  !CDS_PN = "2";
BODY = "Q_RES","I221": #LOCATION = "R6865" !CDS_LOCATION = "R6865" &SEC = "1" #&CDS_SEC = "1";
"A":   PN = "1"  !CDS_PN = "1";
"B":   PN = "2"  !CDS_PN = "2";
BODY = "Q_RES","I222": #LOCATION = "R1516" !CDS_LOCATION = "R1516" &SEC = "1" #&CDS_SEC = "1";
"A":   PN = "1"  !CDS_PN = "1";
"B":   PN = "2"  !CDS_PN = "2";
BODY = "Q_RES","I223": #LOCATION = "R1517" !CDS_LOCATION = "R1517" &SEC = "1" #&CDS_SEC = "1";
"A":   PN = "1"  !CDS_PN = "1";
"B":   PN = "2"  !CDS_PN = "2";
BODY = "Q_RES","I224": #LOCATION = "R308" !CDS_LOCATION = "R308" &SEC = "1" #&CDS_SEC = "1";
"A":   PN = "1"  !CDS_PN = "1";
"B":   PN = "2"  !CDS_PN = "2";
BODY = "Q_RES","I225": #LOCATION = "R309" !CDS_LOCATION = "R309" #SEC = "1" !CDS_SEC = "1";
"A":   PN = "1"  !CDS_PN = "1";
"B":   PN = "2"  !CDS_PN = "2";
BODY = "Q_RES","I226": #LOCATION = "R6856" !CDS_LOCATION = "R6856" &SEC = "1" #&CDS_SEC = "1";
"A":   PN = "1"  !CDS_PN = "1";
"B":   PN = "2"  !CDS_PN = "2";
BODY = "Q_RES","I227": #LOCATION = "R6857" !CDS_LOCATION = "R6857" &SEC = "1" #&CDS_SEC = "1";
"A":   PN = "1"  !CDS_PN = "1";
"B":   PN = "2"  !CDS_PN = "2";
BODY = "Q_RES","I228": #LOCATION = "R6782" !CDS_LOCATION = "R6782" #SEC = "1" !CDS_SEC = "1";
"A":   PN = "1"  !CDS_PN = "1";
"B":   PN = "2"  !CDS_PN = "2";
BODY = "Q_RES","I229": #LOCATION = "R6783" !CDS_LOCATION = "R6783" &SEC = "1" #&CDS_SEC = "1";
"A":   PN = "1"  !CDS_PN = "1";
"B":   PN = "2"  !CDS_PN = "2";
BODY = "Q_RES","I231": #LOCATION = "R364" !CDS_LOCATION = "R364" #SEC = "1" !CDS_SEC = "1";
"A":   PN = "1"  !CDS_PN = "1";
"B":   PN = "2"  !CDS_PN = "2";
DRAWING = "@t6g_mb_lib.t6g(sch_1):page246";
BODY = "Q_RES","I2": #LOCATION = "R2694" !CDS_LOCATION = "R2694" &SEC = "1" #&CDS_SEC = "1";
"A":   PN = "1"  !CDS_PN = "1";
"B":   PN = "2"  !CDS_PN = "2";
BODY = "Q_RES","I3": #LOCATION = "R2693" !CDS_LOCATION = "R2693" &SEC = "1" #&CDS_SEC = "1";
"A":   PN = "1"  !CDS_PN = "1";
"B":   PN = "2"  !CDS_PN = "2";
BODY = "Q_RES","I6": #LOCATION = "R2696" !CDS_LOCATION = "R2696" &SEC = "1" #&CDS_SEC = "1";
"A":   PN = "1"  !CDS_PN = "1";
"B":   PN = "2"  !CDS_PN = "2";
BODY = "Q_RES","I7": #LOCATION = "R2695" !CDS_LOCATION = "R2695" &SEC = "1" #&CDS_SEC = "1";
"A":   PN = "1"  !CDS_PN = "1";
"B":   PN = "2"  !CDS_PN = "2";
BODY = "Q_RES","I35": #LOCATION = "R2921" !CDS_LOCATION = "R2921" &SEC = "1" #&CDS_SEC = "1";
"A":   PN = "1"  !CDS_PN = "1";
"B":   PN = "2"  !CDS_PN = "2";
BODY = "Q_RES","I31": #LOCATION = "R2922" !CDS_LOCATION = "R2922" &SEC = "1" #&CDS_SEC = "1";
"A":   PN = "1"  !CDS_PN = "1";
"B":   PN = "2"  !CDS_PN = "2";
BODY = "Q_RES","I37": #LOCATION = "R2923" !CDS_LOCATION = "R2923" &SEC = "1" #&CDS_SEC = "1";
"A":   PN = "1"  !CDS_PN = "1";
"B":   PN = "2"  !CDS_PN = "2";
BODY = "Q_RES","I39": #LOCATION = "R9012" !CDS_LOCATION = "R9012" &SEC = "1" #&CDS_SEC = "1";
"A":   PN = "1"  !CDS_PN = "1";
"B":   PN = "2"  !CDS_PN = "2";
BODY = "Q_RES","I40": #LOCATION = "R9010" !CDS_LOCATION = "R9010" &SEC = "1" #&CDS_SEC = "1";
"A":   PN = "1"  !CDS_PN = "1";
"B":   PN = "2"  !CDS_PN = "2";
BODY = "Q_RES","I41": #LOCATION = "R8004" !CDS_LOCATION = "R8004" &SEC = "1" #&CDS_SEC = "1";
"A":   PN = "1"  !CDS_PN = "1";
"B":   PN = "2"  !CDS_PN = "2";
BODY = "Q_RES","I42": #LOCATION = "R9019" !CDS_LOCATION = "R9019" &SEC = "1" #&CDS_SEC = "1";
"A":   PN = "1"  !CDS_PN = "1";
"B":   PN = "2"  !CDS_PN = "2";
BODY = "Q_RES","I43": #LOCATION = "R9013" !CDS_LOCATION = "R9013" &SEC = "1" #&CDS_SEC = "1";
"A":   PN = "1"  !CDS_PN = "1";
"B":   PN = "2"  !CDS_PN = "2";
BODY = "Q_RES","I44": #LOCATION = "R9018" !CDS_LOCATION = "R9018" &SEC = "1" #&CDS_SEC = "1";
"A":   PN = "1"  !CDS_PN = "1";
"B":   PN = "2"  !CDS_PN = "2";
BODY = "Q_RES","I45": #LOCATION = "R9011" !CDS_LOCATION = "R9011" &SEC = "1" #&CDS_SEC = "1";
"A":   PN = "1"  !CDS_PN = "1";
"B":   PN = "2"  !CDS_PN = "2";
BODY = "Q_RES","I46": #LOCATION = "R9001" !CDS_LOCATION = "R9001" &SEC = "1" #&CDS_SEC = "1";
"A":   PN = "1"  !CDS_PN = "1";
"B":   PN = "2"  !CDS_PN = "2";
BODY = "Q_RES","I47": #LOCATION = "R3518" !CDS_LOCATION = "R3518" &SEC = "1" #&CDS_SEC = "1";
"A":   PN = "1"  !CDS_PN = "1";
"B":   PN = "2"  !CDS_PN = "2";
BODY = "Q_RES","I55": #LOCATION = "R3517" !CDS_LOCATION = "R3517" &SEC = "1" #&CDS_SEC = "1";
"A":   PN = "1"  !CDS_PN = "1";
"B":   PN = "2"  !CDS_PN = "2";
BODY = "Q_RES","I56": #LOCATION = "R3516" !CDS_LOCATION = "R3516" &SEC = "1" #&CDS_SEC = "1";
"A":   PN = "1"  !CDS_PN = "1";
"B":   PN = "2"  !CDS_PN = "2";
BODY = "Q_RES","I57": #LOCATION = "R3499" !CDS_LOCATION = "R3499" &SEC = "1" #&CDS_SEC = "1";
"A":   PN = "1"  !CDS_PN = "1";
"B":   PN = "2"  !CDS_PN = "2";
BODY = "Q_RES","I58": #LOCATION = "R2983" !CDS_LOCATION = "R2983" &SEC = "1" #&CDS_SEC = "1";
"A":   PN = "1"  !CDS_PN = "1";
"B":   PN = "2"  !CDS_PN = "2";
BODY = "Q_RES","I59": #LOCATION = "R2848" !CDS_LOCATION = "R2848" &SEC = "1" #&CDS_SEC = "1";
"A":   PN = "1"  !CDS_PN = "1";
"B":   PN = "2"  !CDS_PN = "2";
BODY = "Q_CAP","I61": #LOCATION = "C1713" !CDS_LOCATION = "C1713" &SEC = "1" #&CDS_SEC = "1";
"A":   PN = "1"  !CDS_PN = "1";
"B":   PN = "2"  !CDS_PN = "2";
BODY = "Q_RES","I82": #LOCATION = "R2982" !CDS_LOCATION = "R2982" &SEC = "1" #&CDS_SEC = "1";
"A":   PN = "1"  !CDS_PN = "1";
"B":   PN = "2"  !CDS_PN = "2";
BODY = "PCA9539RPW","I83": #LOCATION = "U181" !CDS_LOCATION = "U181" #SEC = "1" !CDS_SEC = "1";
"A0":   PN = "21"  !CDS_PN = "21";
"A1":   PN = "2"  !CDS_PN = "2";
"INT":   PN = "1"  !CDS_PN = "1";
"IO0_0":   PN = "4"  !CDS_PN = "4";
"IO0_1":   PN = "5"  !CDS_PN = "5";
"IO0_2":   PN = "6"  !CDS_PN = "6";
"IO0_3":   PN = "7"  !CDS_PN = "7";
"IO0_4":   PN = "8"  !CDS_PN = "8";
"IO0_5":   PN = "9"  !CDS_PN = "9";
"IO0_6":   PN = "10"  !CDS_PN = "10";
"IO0_7":   PN = "11"  !CDS_PN = "11";
"IO1_0":   PN = "13"  !CDS_PN = "13";
"IO1_1":   PN = "14"  !CDS_PN = "14";
"IO1_2":   PN = "15"  !CDS_PN = "15";
"IO1_3":   PN = "16"  !CDS_PN = "16";
"IO1_4":   PN = "17"  !CDS_PN = "17";
"IO1_5":   PN = "18"  !CDS_PN = "18";
"IO1_6":   PN = "19"  !CDS_PN = "19";
"IO1_7":   PN = "20"  !CDS_PN = "20";
"RESET":   PN = "3"  !CDS_PN = "3";
"SCL":   PN = "22"  !CDS_PN = "22";
"SDA":   PN = "23"  !CDS_PN = "23";
"VDD":   PN = "24"  !CDS_PN = "24";
"VSS":   PN = "12"  !CDS_PN = "12";
DRAWING = "@t6g_mb_lib.t6g(sch_1):page232";
BODY = "Q_RES","I6": #LOCATION = "R3327" !CDS_LOCATION = "R3327" &SEC = "1" #&CDS_SEC = "1";
"A":   PN = "1"  !CDS_PN = "1";
"B":   PN = "2"  !CDS_PN = "2";
BODY = "Q_RES","I7": #LOCATION = "R3326" !CDS_LOCATION = "R3326" &SEC = "1" #&CDS_SEC = "1";
"A":   PN = "1"  !CDS_PN = "1";
"B":   PN = "2"  !CDS_PN = "2";
BODY = "Q_RES","I8": #LOCATION = "R4514" !CDS_LOCATION = "R4514" &SEC = "1" #&CDS_SEC = "1";
"A":   PN = "1"  !CDS_PN = "1";
"B":   PN = "2"  !CDS_PN = "2";
BODY = "Q_XTAL_4P_13BI_24GND","I14": #LOCATION = "Y8003" !CDS_LOCATION = "Y8003" &SEC = "1" #&CDS_SEC = "1";
"G1":   PN = "2"  !CDS_PN = "2";
"G2":   PN = "4"  !CDS_PN = "4";
"X1":   PN = "1"  !CDS_PN = "1";
"X2":   PN = "3"  !CDS_PN = "3";
BODY = "Q_RES","I16": #LOCATION = "R4076" !CDS_LOCATION = "R4076" &SEC = "1" #&CDS_SEC = "1";
"A":   PN = "1"  !CDS_PN = "1";
"B":   PN = "2"  !CDS_PN = "2";
BODY = "Q_RES","I22": #LOCATION = "R4075" !CDS_LOCATION = "R4075" &SEC = "1" #&CDS_SEC = "1";
"A":   PN = "1"  !CDS_PN = "1";
"B":   PN = "2"  !CDS_PN = "2";
BODY = "74LVC1G32GW","I26": #LOCATION = "U248" !CDS_LOCATION = "U248" &SEC = "1" #&CDS_SEC = "1";
"GND":   PN = "3"  !CDS_PN = "3";
"I0":   PN = "1"  !CDS_PN = "1";
"I1":   PN = "2"  !CDS_PN = "2";
"O":   PN = "4"  !CDS_PN = "4";
"VCC":   PN = "5"  !CDS_PN = "5";
BODY = "Q_CAP","I28": #LOCATION = "C1882" !CDS_LOCATION = "C1882" &SEC = "1" #&CDS_SEC = "1";
"A":   PN = "1"  !CDS_PN = "1";
"B":   PN = "2"  !CDS_PN = "2";
BODY = "Q_RES","I31": #LOCATION = "R4501" !CDS_LOCATION = "R4501" &SEC = "1" #&CDS_SEC = "1";
"A":   PN = "1"  !CDS_PN = "1";
"B":   PN = "2"  !CDS_PN = "2";
BODY = "Q_INDUCTOR","I33": #LOCATION = "L17" !CDS_LOCATION = "L17" &SEC = "1" #&CDS_SEC = "1";
"1":   PN = "1"  !CDS_PN = "1";
"2":   PN = "2"  !CDS_PN = "2";
BODY = "Q_CAP","I36": #LOCATION = "C1883" !CDS_LOCATION = "C1883" &SEC = "1" #&CDS_SEC = "1";
"A":   PN = "1"  !CDS_PN = "1";
"B":   PN = "2"  !CDS_PN = "2";
BODY = "Q_CAP","I37": #LOCATION = "C2257" !CDS_LOCATION = "C2257" &SEC = "1" #&CDS_SEC = "1";
"A":   PN = "1"  !CDS_PN = "1";
"B":   PN = "2"  !CDS_PN = "2";
BODY = "Q_CAP","I40": #LOCATION = "C1886" !CDS_LOCATION = "C1886" &SEC = "1" #&CDS_SEC = "1";
"A":   PN = "1"  !CDS_PN = "1";
"B":   PN = "2"  !CDS_PN = "2";
BODY = "Q_CAP","I41": #LOCATION = "C1889" !CDS_LOCATION = "C1889" &SEC = "1" #&CDS_SEC = "1";
"A":   PN = "1"  !CDS_PN = "1";
"B":   PN = "2"  !CDS_PN = "2";
BODY = "Q_CAP","I42": #LOCATION = "C95" !CDS_LOCATION = "C95" &SEC = "1" #&CDS_SEC = "1";
"A":   PN = "1"  !CDS_PN = "1";
"B":   PN = "2"  !CDS_PN = "2";
BODY = "Q_RES","I43": #LOCATION = "R4077" !CDS_LOCATION = "R4077" &SEC = "1" #&CDS_SEC = "1";
"A":   PN = "1"  !CDS_PN = "1";
"B":   PN = "2"  !CDS_PN = "2";
BODY = "Q_RES","I46": #LOCATION = "R4079" !CDS_LOCATION = "R4079" &SEC = "1" #&CDS_SEC = "1";
"A":   PN = "1"  !CDS_PN = "1";
"B":   PN = "2"  !CDS_PN = "2";
BODY = "Q_RES","I47": #LOCATION = "R4078" !CDS_LOCATION = "R4078" &SEC = "1" #&CDS_SEC = "1";
"A":   PN = "1"  !CDS_PN = "1";
"B":   PN = "2"  !CDS_PN = "2";
BODY = "Q_RES","I50": #LOCATION = "R3338" !CDS_LOCATION = "R3338" &SEC = "1" #&CDS_SEC = "1";
"A":   PN = "1"  !CDS_PN = "1";
"B":   PN = "2"  !CDS_PN = "2";
BODY = "Q_RES","I51": #LOCATION = "R3337" !CDS_LOCATION = "R3337" &SEC = "1" #&CDS_SEC = "1";
"A":   PN = "1"  !CDS_PN = "1";
"B":   PN = "2"  !CDS_PN = "2";
BODY = "Q_RES","I52": #LOCATION = "R3336" !CDS_LOCATION = "R3336" &SEC = "1" #&CDS_SEC = "1";
"A":   PN = "1"  !CDS_PN = "1";
"B":   PN = "2"  !CDS_PN = "2";
BODY = "Q_RES","I53": #LOCATION = "R3335" !CDS_LOCATION = "R3335" &SEC = "1" #&CDS_SEC = "1";
"A":   PN = "1"  !CDS_PN = "1";
"B":   PN = "2"  !CDS_PN = "2";
BODY = "Q_RES","I55": #LOCATION = "R4082" !CDS_LOCATION = "R4082" &SEC = "1" #&CDS_SEC = "1";
"A":   PN = "1"  !CDS_PN = "1";
"B":   PN = "2"  !CDS_PN = "2";
BODY = "Q_RES","I56": #LOCATION = "R4081" !CDS_LOCATION = "R4081" &SEC = "1" #&CDS_SEC = "1";
"A":   PN = "1"  !CDS_PN = "1";
"B":   PN = "2"  !CDS_PN = "2";
BODY = "Q_RES","I59": #LOCATION = "R4080" !CDS_LOCATION = "R4080" &SEC = "1" #&CDS_SEC = "1";
"A":   PN = "1"  !CDS_PN = "1";
"B":   PN = "2"  !CDS_PN = "2";
BODY = "Q_CAP","I68": #LOCATION = "C1884" !CDS_LOCATION = "C1884" &SEC = "1" #&CDS_SEC = "1";
"A":   PN = "1"  !CDS_PN = "1";
"B":   PN = "2"  !CDS_PN = "2";
BODY = "Q_CAP","I69": #LOCATION = "C97" !CDS_LOCATION = "C97" &SEC = "1" #&CDS_SEC = "1";
"A":   PN = "1"  !CDS_PN = "1";
"B":   PN = "2"  !CDS_PN = "2";
BODY = "Q_RES","I73": #LOCATION = "R4521" !CDS_LOCATION = "R4521" &SEC = "1" #&CDS_SEC = "1";
"A":   PN = "1"  !CDS_PN = "1";
"B":   PN = "2"  !CDS_PN = "2";
BODY = "Q_RES","I74": #LOCATION = "R3322" !CDS_LOCATION = "R3322" &SEC = "1" #&CDS_SEC = "1";
"A":   PN = "1"  !CDS_PN = "1";
"B":   PN = "2"  !CDS_PN = "2";
BODY = "Q_CAP","I75": #LOCATION = "C71" !CDS_LOCATION = "C71" &SEC = "1" #&CDS_SEC = "1";
"A":   PN = "1"  !CDS_PN = "1";
"B":   PN = "2"  !CDS_PN = "2";
BODY = "Q_CAP","I76": #LOCATION = "C94" !CDS_LOCATION = "C94" &SEC = "1" #&CDS_SEC = "1";
"A":   PN = "1"  !CDS_PN = "1";
"B":   PN = "2"  !CDS_PN = "2";
BODY = "9FGL0251DKILFT","I77": #LOCATION = "U247" !CDS_LOCATION = "U247" #SEC = "1" !CDS_SEC = "1";
"^CKPWRGD_PD#":   PN = "22"  !CDS_PN = "22";
"^VSS_EN_TRI":   PN = "23"  !CDS_PN = "23";
"DIF0":   PN = "13"  !CDS_PN = "13";
"DIF0#":   PN = "14"  !CDS_PN = "14";
"DIF1":   PN = "17"  !CDS_PN = "17";
"DIF1#":   PN = "18"  !CDS_PN = "18";
"GND_10":   PN = "10"  !CDS_PN = "10";
"GND_21":   PN = "21"  !CDS_PN = "21";
"GNDA":   PN = "15"  !CDS_PN = "15";
"GNDDIG":   PN = "6"  !CDS_PN = "6";
"GNDREF":   PN = "5"  !CDS_PN = "5";
"GNDXTAL":   PN = "24"  !CDS_PN = "24";
"SCLK_3.3":   PN = "8"  !CDS_PN = "8";
"SDATA_3.3":   PN = "9"  !CDS_PN = "9";
"TH_GND":   PN = "25"  !CDS_PN = "25";
"VDD3.3_11":   PN = "11"  !CDS_PN = "11";
"VDD3.3_20":   PN = "20"  !CDS_PN = "20";
"VDDA3.3":   PN = "16"  !CDS_PN = "16";
"VDDDIG3.3":   PN = "7"  !CDS_PN = "7";
"VDDXTAL3.3":   PN = "3"  !CDS_PN = "3";
"VOE0#":   PN = "12"  !CDS_PN = "12";
"VOE1#":   PN = "19"  !CDS_PN = "19";
"VSADR||REF3.3":   PN = "4"  !CDS_PN = "4";
"X2":   PN = "2"  !CDS_PN = "2";
"XIN||CLKIN_25":   PN = "1"  !CDS_PN = "1";
DRAWING = "@t6g_mb_lib.t6g(sch_1):page80";
BODY = "Q_RES","I30": #LOCATION = "R283" !CDS_LOCATION = "R283" &SEC = "1" #&CDS_SEC = "1";
"A":   PN = "1"  !CDS_PN = "1";
"B":   PN = "2"  !CDS_PN = "2";
BODY = "Q_RES","I31": #LOCATION = "R282" !CDS_LOCATION = "R282" &SEC = "1" #&CDS_SEC = "1";
"A":   PN = "1"  !CDS_PN = "1";
"B":   PN = "2"  !CDS_PN = "2";
BODY = "Q_RES","I32": #LOCATION = "R218" !CDS_LOCATION = "R218" &SEC = "1" #&CDS_SEC = "1";
"A":   PN = "1"  !CDS_PN = "1";
"B":   PN = "2"  !CDS_PN = "2";
BODY = "Q_RES","I33": #LOCATION = "R176" !CDS_LOCATION = "R176" &SEC = "1" #&CDS_SEC = "1";
"A":   PN = "1"  !CDS_PN = "1";
"B":   PN = "2"  !CDS_PN = "2";
BODY = "Q_RES","I34": #LOCATION = "R6047" !CDS_LOCATION = "R6047" &SEC = "1" #&CDS_SEC = "1";
"A":   PN = "1"  !CDS_PN = "1";
"B":   PN = "2"  !CDS_PN = "2";
BODY = "Q_RES","I35": #LOCATION = "R5099" !CDS_LOCATION = "R5099" &SEC = "1" #&CDS_SEC = "1";
"A":   PN = "1"  !CDS_PN = "1";
"B":   PN = "2"  !CDS_PN = "2";
BODY = "Q_RES","I36": #LOCATION = "R224" !CDS_LOCATION = "R224" &SEC = "1" #&CDS_SEC = "1";
"A":   PN = "1"  !CDS_PN = "1";
"B":   PN = "2"  !CDS_PN = "2";
BODY = "Q_RES","I125": #LOCATION = "R798" !CDS_LOCATION = "R798" &SEC = "1" #&CDS_SEC = "1";
"A":   PN = "1"  !CDS_PN = "1";
"B":   PN = "2"  !CDS_PN = "2";
BODY = "Q_RES","I126": #LOCATION = "R265" !CDS_LOCATION = "R265" &SEC = "1" #&CDS_SEC = "1";
"A":   PN = "1"  !CDS_PN = "1";
"B":   PN = "2"  !CDS_PN = "2";
BODY = "Q_RES","I127": #LOCATION = "R1202" !CDS_LOCATION = "R1202" &SEC = "1" #&CDS_SEC = "1";
"A":   PN = "1"  !CDS_PN = "1";
"B":   PN = "2"  !CDS_PN = "2";
BODY = "Q_RES","I128": #LOCATION = "R252" !CDS_LOCATION = "R252" &SEC = "1" #&CDS_SEC = "1";
"A":   PN = "1"  !CDS_PN = "1";
"B":   PN = "2"  !CDS_PN = "2";
BODY = "Q_RES","I129": #LOCATION = "R186" !CDS_LOCATION = "R186" &SEC = "1" #&CDS_SEC = "1";
"A":   PN = "1"  !CDS_PN = "1";
"B":   PN = "2"  !CDS_PN = "2";
BODY = "Q_RES","I130": #LOCATION = "R957" !CDS_LOCATION = "R957" &SEC = "1" #&CDS_SEC = "1";
"A":   PN = "1"  !CDS_PN = "1";
"B":   PN = "2"  !CDS_PN = "2";
BODY = "Q_RES","I154": #LOCATION = "R158" !CDS_LOCATION = "R158" &SEC = "1" #&CDS_SEC = "1";
"A":   PN = "1"  !CDS_PN = "1";
"B":   PN = "2"  !CDS_PN = "2";
BODY = "Q_RES","I155": #LOCATION = "R395" !CDS_LOCATION = "R395" &SEC = "1" #&CDS_SEC = "1";
"A":   PN = "1"  !CDS_PN = "1";
"B":   PN = "2"  !CDS_PN = "2";
BODY = "Q_RES","I156": #LOCATION = "R1564" !CDS_LOCATION = "R1564" &SEC = "1" #&CDS_SEC = "1";
"A":   PN = "1"  !CDS_PN = "1";
"B":   PN = "2"  !CDS_PN = "2";
BODY = "Q_RES","I157": #LOCATION = "R1616" !CDS_LOCATION = "R1616" &SEC = "1" #&CDS_SEC = "1";
"A":   PN = "1"  !CDS_PN = "1";
"B":   PN = "2"  !CDS_PN = "2";
BODY = "Q_RES","I158": #LOCATION = "R1359" !CDS_LOCATION = "R1359" &SEC = "1" #&CDS_SEC = "1";
"A":   PN = "1"  !CDS_PN = "1";
"B":   PN = "2"  !CDS_PN = "2";
BODY = "Q_RES","I159": #LOCATION = "R372" !CDS_LOCATION = "R372" &SEC = "1" #&CDS_SEC = "1";
"A":   PN = "1"  !CDS_PN = "1";
"B":   PN = "2"  !CDS_PN = "2";
BODY = "Q_RES","I160": #LOCATION = "R174" !CDS_LOCATION = "R174" &SEC = "1" #&CDS_SEC = "1";
"A":   PN = "1"  !CDS_PN = "1";
"B":   PN = "2"  !CDS_PN = "2";
BODY = "Q_RES","I161": #LOCATION = "R161" !CDS_LOCATION = "R161" &SEC = "1" #&CDS_SEC = "1";
"A":   PN = "1"  !CDS_PN = "1";
"B":   PN = "2"  !CDS_PN = "2";
BODY = "Q_RES","I162": #LOCATION = "R251" !CDS_LOCATION = "R251" &SEC = "1" #&CDS_SEC = "1";
"A":   PN = "1"  !CDS_PN = "1";
"B":   PN = "2"  !CDS_PN = "2";
BODY = "Q_RES","I163": #LOCATION = "R173" !CDS_LOCATION = "R173" &SEC = "1" #&CDS_SEC = "1";
"A":   PN = "1"  !CDS_PN = "1";
"B":   PN = "2"  !CDS_PN = "2";
BODY = "Q_RES","I164": #LOCATION = "R588" !CDS_LOCATION = "R588" &SEC = "1" #&CDS_SEC = "1";
"A":   PN = "1"  !CDS_PN = "1";
"B":   PN = "2"  !CDS_PN = "2";
BODY = "Q_RES","I165": #LOCATION = "R277" !CDS_LOCATION = "R277" &SEC = "1" #&CDS_SEC = "1";
"A":   PN = "1"  !CDS_PN = "1";
"B":   PN = "2"  !CDS_PN = "2";
BODY = "Q_RES","I166": #LOCATION = "R937" !CDS_LOCATION = "R937" &SEC = "1" #&CDS_SEC = "1";
"A":   PN = "1"  !CDS_PN = "1";
"B":   PN = "2"  !CDS_PN = "2";
BODY = "Q_RES","I167": #LOCATION = "R856" !CDS_LOCATION = "R856" &SEC = "1" #&CDS_SEC = "1";
"A":   PN = "1"  !CDS_PN = "1";
"B":   PN = "2"  !CDS_PN = "2";
BODY = "Q_RES","I168": #LOCATION = "R708" !CDS_LOCATION = "R708" &SEC = "1" #&CDS_SEC = "1";
"A":   PN = "1"  !CDS_PN = "1";
"B":   PN = "2"  !CDS_PN = "2";
BODY = "Q_RES","I169": #LOCATION = "R1551" !CDS_LOCATION = "R1551" &SEC = "1" #&CDS_SEC = "1";
"A":   PN = "1"  !CDS_PN = "1";
"B":   PN = "2"  !CDS_PN = "2";
BODY = "Q_RES","I170": #LOCATION = "R1552" !CDS_LOCATION = "R1552" &SEC = "1" #&CDS_SEC = "1";
"A":   PN = "1"  !CDS_PN = "1";
"B":   PN = "2"  !CDS_PN = "2";
BODY = "Q_RES","I171": #LOCATION = "R1550" !CDS_LOCATION = "R1550" &SEC = "1" #&CDS_SEC = "1";
"A":   PN = "1"  !CDS_PN = "1";
"B":   PN = "2"  !CDS_PN = "2";
BODY = "Q_RES","I172": #LOCATION = "R1558" !CDS_LOCATION = "R1558" &SEC = "1" #&CDS_SEC = "1";
"A":   PN = "1"  !CDS_PN = "1";
"B":   PN = "2"  !CDS_PN = "2";
BODY = "Q_RES","I173": #LOCATION = "R1549" !CDS_LOCATION = "R1549" &SEC = "1" #&CDS_SEC = "1";
"A":   PN = "1"  !CDS_PN = "1";
"B":   PN = "2"  !CDS_PN = "2";
BODY = "Q_RES","I174": #LOCATION = "R1553" !CDS_LOCATION = "R1553" &SEC = "1" #&CDS_SEC = "1";
"A":   PN = "1"  !CDS_PN = "1";
"B":   PN = "2"  !CDS_PN = "2";
BODY = "Q_RES","I22": #LOCATION = "R199" !CDS_LOCATION = "R199" &SEC = "1" #&CDS_SEC = "1";
"A":   PN = "1"  !CDS_PN = "1";
"B":   PN = "2"  !CDS_PN = "2";
BODY = "Q_RES","I25": #LOCATION = "R648" !CDS_LOCATION = "R648" &SEC = "1" #&CDS_SEC = "1";
"A":   PN = "1"  !CDS_PN = "1";
"B":   PN = "2"  !CDS_PN = "2";
BODY = "Q_RES","I28": #LOCATION = "R6048" !CDS_LOCATION = "R6048" &SEC = "1" #&CDS_SEC = "1";
"A":   PN = "1"  !CDS_PN = "1";
"B":   PN = "2"  !CDS_PN = "2";
BODY = "Q_RES","I29": #LOCATION = "R1282" !CDS_LOCATION = "R1282" &SEC = "1" #&CDS_SEC = "1";
"A":   PN = "1"  !CDS_PN = "1";
"B":   PN = "2"  !CDS_PN = "2";
BODY = "Q_RES","I57": #LOCATION = "R289" !CDS_LOCATION = "R289" &SEC = "1" #&CDS_SEC = "1";
"A":   PN = "1"  !CDS_PN = "1";
"B":   PN = "2"  !CDS_PN = "2";
BODY = "Q_RES","I58": #LOCATION = "R279" !CDS_LOCATION = "R279" &SEC = "1" #&CDS_SEC = "1";
"A":   PN = "1"  !CDS_PN = "1";
"B":   PN = "2"  !CDS_PN = "2";
BODY = "Q_RES","I59": #LOCATION = "R280" !CDS_LOCATION = "R280" &SEC = "1" #&CDS_SEC = "1";
"A":   PN = "1"  !CDS_PN = "1";
"B":   PN = "2"  !CDS_PN = "2";
BODY = "Q_RES","I60": #LOCATION = "R6055" !CDS_LOCATION = "R6055" &SEC = "1" #&CDS_SEC = "1";
"A":   PN = "1"  !CDS_PN = "1";
"B":   PN = "2"  !CDS_PN = "2";
BODY = "Q_RES","I61": #LOCATION = "R209" !CDS_LOCATION = "R209" &SEC = "1" #&CDS_SEC = "1";
"A":   PN = "1"  !CDS_PN = "1";
"B":   PN = "2"  !CDS_PN = "2";
BODY = "Q_RES","I62": #LOCATION = "R286" !CDS_LOCATION = "R286" &SEC = "1" #&CDS_SEC = "1";
"A":   PN = "1"  !CDS_PN = "1";
"B":   PN = "2"  !CDS_PN = "2";
BODY = "Q_RES","I63": #LOCATION = "R1563" !CDS_LOCATION = "R1563" &SEC = "1" #&CDS_SEC = "1";
"A":   PN = "1"  !CDS_PN = "1";
"B":   PN = "2"  !CDS_PN = "2";
BODY = "Q_RES","I64": #LOCATION = "R6046" !CDS_LOCATION = "R6046" &SEC = "1" #&CDS_SEC = "1";
"A":   PN = "1"  !CDS_PN = "1";
"B":   PN = "2"  !CDS_PN = "2";
BODY = "Q_RES","I65": #LOCATION = "R208" !CDS_LOCATION = "R208" &SEC = "1" #&CDS_SEC = "1";
"A":   PN = "1"  !CDS_PN = "1";
"B":   PN = "2"  !CDS_PN = "2";
BODY = "Q_RES","I66": #LOCATION = "R228" !CDS_LOCATION = "R228" &SEC = "1" #&CDS_SEC = "1";
"A":   PN = "1"  !CDS_PN = "1";
"B":   PN = "2"  !CDS_PN = "2";
BODY = "Q_RES","I100": #LOCATION = "R194" !CDS_LOCATION = "R194" &SEC = "1" #&CDS_SEC = "1";
"A":   PN = "1"  !CDS_PN = "1";
"B":   PN = "2"  !CDS_PN = "2";
BODY = "Q_RES","I101": #LOCATION = "R1281" !CDS_LOCATION = "R1281" &SEC = "1" #&CDS_SEC = "1";
"A":   PN = "1"  !CDS_PN = "1";
"B":   PN = "2"  !CDS_PN = "2";
BODY = "Q_RES","I102": #LOCATION = "R1280" !CDS_LOCATION = "R1280" &SEC = "1" #&CDS_SEC = "1";
"A":   PN = "1"  !CDS_PN = "1";
"B":   PN = "2"  !CDS_PN = "2";
BODY = "Q_RES","I103": #LOCATION = "R1279" !CDS_LOCATION = "R1279" &SEC = "1" #&CDS_SEC = "1";
"A":   PN = "1"  !CDS_PN = "1";
"B":   PN = "2"  !CDS_PN = "2";
BODY = "Q_RES","I104": #LOCATION = "R215" !CDS_LOCATION = "R215" &SEC = "1" #&CDS_SEC = "1";
"A":   PN = "1"  !CDS_PN = "1";
"B":   PN = "2"  !CDS_PN = "2";
BODY = "Q_RES","I105": #LOCATION = "R1278" !CDS_LOCATION = "R1278" &SEC = "1" #&CDS_SEC = "1";
"A":   PN = "1"  !CDS_PN = "1";
"B":   PN = "2"  !CDS_PN = "2";
BODY = "Q_RES","I106": #LOCATION = "R203" !CDS_LOCATION = "R203" &SEC = "1" #&CDS_SEC = "1";
"A":   PN = "1"  !CDS_PN = "1";
"B":   PN = "2"  !CDS_PN = "2";
BODY = "Q_RES","I107": #LOCATION = "R371" !CDS_LOCATION = "R371" &SEC = "1" #&CDS_SEC = "1";
"A":   PN = "1"  !CDS_PN = "1";
"B":   PN = "2"  !CDS_PN = "2";
BODY = "Q_RES","I108": #LOCATION = "R219" !CDS_LOCATION = "R219" &SEC = "1" #&CDS_SEC = "1";
"A":   PN = "1"  !CDS_PN = "1";
"B":   PN = "2"  !CDS_PN = "2";
BODY = "Q_RES","I109": #LOCATION = "R196" !CDS_LOCATION = "R196" &SEC = "1" #&CDS_SEC = "1";
"A":   PN = "1"  !CDS_PN = "1";
"B":   PN = "2"  !CDS_PN = "2";
BODY = "Q_RES","I110": #LOCATION = "R242" !CDS_LOCATION = "R242" &SEC = "1" #&CDS_SEC = "1";
"A":   PN = "1"  !CDS_PN = "1";
"B":   PN = "2"  !CDS_PN = "2";
BODY = "Q_RES","I111": #LOCATION = "R159" !CDS_LOCATION = "R159" &SEC = "1" #&CDS_SEC = "1";
"A":   PN = "1"  !CDS_PN = "1";
"B":   PN = "2"  !CDS_PN = "2";
BODY = "Q_RES","I112": #LOCATION = "R463" !CDS_LOCATION = "R463" &SEC = "1" #&CDS_SEC = "1";
"A":   PN = "1"  !CDS_PN = "1";
"B":   PN = "2"  !CDS_PN = "2";
BODY = "Q_RES","I113": #LOCATION = "R57" !CDS_LOCATION = "R57" &SEC = "1" #&CDS_SEC = "1";
"A":   PN = "1"  !CDS_PN = "1";
"B":   PN = "2"  !CDS_PN = "2";
BODY = "Q_RES","I114": #LOCATION = "R241" !CDS_LOCATION = "R241" &SEC = "1" #&CDS_SEC = "1";
"A":   PN = "1"  !CDS_PN = "1";
"B":   PN = "2"  !CDS_PN = "2";
BODY = "Q_RES","I115": #LOCATION = "R272" !CDS_LOCATION = "R272" &SEC = "1" #&CDS_SEC = "1";
"A":   PN = "1"  !CDS_PN = "1";
"B":   PN = "2"  !CDS_PN = "2";
BODY = "Q_RES","I116": #LOCATION = "R253" !CDS_LOCATION = "R253" &SEC = "1" #&CDS_SEC = "1";
"A":   PN = "1"  !CDS_PN = "1";
"B":   PN = "2"  !CDS_PN = "2";
BODY = "Q_RES","I117": #LOCATION = "R216" !CDS_LOCATION = "R216" &SEC = "1" #&CDS_SEC = "1";
"A":   PN = "1"  !CDS_PN = "1";
"B":   PN = "2"  !CDS_PN = "2";
BODY = "Q_RES","I118": #LOCATION = "R217" !CDS_LOCATION = "R217" &SEC = "1" #&CDS_SEC = "1";
"A":   PN = "1"  !CDS_PN = "1";
"B":   PN = "2"  !CDS_PN = "2";
BODY = "Q_RES","I119": #LOCATION = "R273" !CDS_LOCATION = "R273" &SEC = "1" #&CDS_SEC = "1";
"A":   PN = "1"  !CDS_PN = "1";
"B":   PN = "2"  !CDS_PN = "2";
BODY = "Q_RES","I120": #LOCATION = "R197" !CDS_LOCATION = "R197" &SEC = "1" #&CDS_SEC = "1";
"A":   PN = "1"  !CDS_PN = "1";
"B":   PN = "2"  !CDS_PN = "2";
BODY = "Q_RES","I121": #LOCATION = "R255" !CDS_LOCATION = "R255" &SEC = "1" #&CDS_SEC = "1";
"A":   PN = "1"  !CDS_PN = "1";
"B":   PN = "2"  !CDS_PN = "2";
BODY = "Q_RES","I122": #LOCATION = "R198" !CDS_LOCATION = "R198" &SEC = "1" #&CDS_SEC = "1";
"A":   PN = "1"  !CDS_PN = "1";
"B":   PN = "2"  !CDS_PN = "2";
BODY = "Q_RES","I67": #LOCATION = "R230" !CDS_LOCATION = "R230" &SEC = "1" #&CDS_SEC = "1";
"A":   PN = "1"  !CDS_PN = "1";
"B":   PN = "2"  !CDS_PN = "2";
BODY = "Q_RES","I68": #LOCATION = "R229" !CDS_LOCATION = "R229" &SEC = "1" #&CDS_SEC = "1";
"A":   PN = "1"  !CDS_PN = "1";
"B":   PN = "2"  !CDS_PN = "2";
BODY = "Q_RES","I123": #LOCATION = "R254" !CDS_LOCATION = "R254" &SEC = "1" #&CDS_SEC = "1";
"A":   PN = "1"  !CDS_PN = "1";
"B":   PN = "2"  !CDS_PN = "2";
BODY = "Q_RES","I131": #LOCATION = "R685" !CDS_LOCATION = "R685" &SEC = "1" #&CDS_SEC = "1";
"A":   PN = "1"  !CDS_PN = "1";
"B":   PN = "2"  !CDS_PN = "2";
BODY = "Q_RES","I175": #LOCATION = "R1557" !CDS_LOCATION = "R1557" &SEC = "1" #&CDS_SEC = "1";
"A":   PN = "1"  !CDS_PN = "1";
"B":   PN = "2"  !CDS_PN = "2";
BODY = "Q_RES","I176": #LOCATION = "R1556" !CDS_LOCATION = "R1556" &SEC = "1" #&CDS_SEC = "1";
"A":   PN = "1"  !CDS_PN = "1";
"B":   PN = "2"  !CDS_PN = "2";
BODY = "Q_RES","I177": #LOCATION = "R258" !CDS_LOCATION = "R258" &SEC = "1" #&CDS_SEC = "1";
"A":   PN = "1"  !CDS_PN = "1";
"B":   PN = "2"  !CDS_PN = "2";
BODY = "Q_RES","I178": #LOCATION = "R1203" !CDS_LOCATION = "R1203" &SEC = "1" #&CDS_SEC = "1";
"A":   PN = "1"  !CDS_PN = "1";
"B":   PN = "2"  !CDS_PN = "2";
BODY = "Q_RES","I179": #LOCATION = "R193" !CDS_LOCATION = "R193" &SEC = "1" #&CDS_SEC = "1";
"A":   PN = "1"  !CDS_PN = "1";
"B":   PN = "2"  !CDS_PN = "2";
BODY = "Q_RES","I180": #LOCATION = "R250" !CDS_LOCATION = "R250" &SEC = "1" #&CDS_SEC = "1";
"A":   PN = "1"  !CDS_PN = "1";
"B":   PN = "2"  !CDS_PN = "2";
BODY = "Q_RES","I215": #LOCATION = "R933" !CDS_LOCATION = "R933" &SEC = "1" #&CDS_SEC = "1";
"A":   PN = "1"  !CDS_PN = "1";
"B":   PN = "2"  !CDS_PN = "2";
BODY = "LCMXO3LF9400C5BG484C","I216": #LOCATION = "U18" !CDS_LOCATION = "U18" &SEC = "2" #&CDS_SEC = "2";
"PB5A":   PN = "AA2"  !CDS_PN = "AA2";
"PB5B":   PN = "AB2"  !CDS_PN = "AB2";
"PB5C":   PN = "V6"  !CDS_PN = "V6";
"PB5D":   PN = "U6"  !CDS_PN = "U6";
"PB7A||CSSPIN":   PN = "AA3"  !CDS_PN = "AA3";
"PB7B":   PN = "AB3"  !CDS_PN = "AB3";
"PB7C":   PN = "Y4"  !CDS_PN = "Y4";
"PB7D":   PN = "W5"  !CDS_PN = "W5";
"PB8A":   PN = "AA4"  !CDS_PN = "AA4";
"PB8B":   PN = "AB4"  !CDS_PN = "AB4";
"PB8C":   PN = "U7"  !CDS_PN = "U7";
"PB8D":   PN = "T8"  !CDS_PN = "T8";
"PB10A":   PN = "AA5"  !CDS_PN = "AA5";
"PB10B":   PN = "AB5"  !CDS_PN = "AB5";
"PB10C":   PN = "Y5"  !CDS_PN = "Y5";
"PB10D":   PN = "Y6"  !CDS_PN = "Y6";
"PB11A":   PN = "AA6"  !CDS_PN = "AA6";
"PB11B":   PN = "AB6"  !CDS_PN = "AB6";
"PB11C":   PN = "W6"  !CDS_PN = "W6";
"PB11D":   PN = "V7"  !CDS_PN = "V7";
"PB13A":   PN = "AA7"  !CDS_PN = "AA7";
"PB13B":   PN = "AB7"  !CDS_PN = "AB7";
"PB13C":   PN = "V8"  !CDS_PN = "V8";
"PB13D":   PN = "U8"  !CDS_PN = "U8";
"PB16A||MCLK||CCLK":   PN = "T9"  !CDS_PN = "T9";
"PB16B||SO||SPISO":   PN = "U9"  !CDS_PN = "U9";
"PB16C":   PN = "V9"  !CDS_PN = "V9";
"PB16D":   PN = "W8"  !CDS_PN = "W8";
"PB18A":   PN = "AA8"  !CDS_PN = "AA8";
"PB18B":   PN = "AB8"  !CDS_PN = "AB8";
"PB18C":   PN = "Y8"  !CDS_PN = "Y8";
"PB18D":   PN = "W9"  !CDS_PN = "W9";
"PB19A":   PN = "AA9"  !CDS_PN = "AA9";
"PB19B":   PN = "AB9"  !CDS_PN = "AB9";
"PB19C":   PN = "T10"  !CDS_PN = "T10";
"PB19D":   PN = "U10"  !CDS_PN = "U10";
"PB21A":   PN = "V10"  !CDS_PN = "V10";
"PB21B":   PN = "W10"  !CDS_PN = "W10";
"PB21C":   PN = "Y9"  !CDS_PN = "Y9";
"PB21D":   PN = "Y10"  !CDS_PN = "Y10";
"PB22A||PCLKT2_0":   PN = "AA10"  !CDS_PN = "AA10";
"PB22B||PCLKC2_0":   PN = "AB10"  !CDS_PN = "AB10";
"PB22C":   PN = "T11"  !CDS_PN = "T11";
"PB22D":   PN = "U11"  !CDS_PN = "U11";
"PB24A":   PN = "AA11"  !CDS_PN = "AA11";
"PB24B":   PN = "AB11"  !CDS_PN = "AB11";
"PB24C":   PN = "V11"  !CDS_PN = "V11";
"PB24D":   PN = "Y11"  !CDS_PN = "Y11";
"PB27A":   PN = "Y12"  !CDS_PN = "Y12";
"PB27B":   PN = "T12"  !CDS_PN = "T12";
"PB27C":   PN = "U12"  !CDS_PN = "U12";
"PB27D":   PN = "V12"  !CDS_PN = "V12";
"PB29A||PCLKT2_1":   PN = "AB12"  !CDS_PN = "AB12";
"PB29B||PCLKC2_1":   PN = "AA12"  !CDS_PN = "AA12";
"PB29C":   PN = "V13"  !CDS_PN = "V13";
"PB29D":   PN = "U13"  !CDS_PN = "U13";
"PB30A":   PN = "AB13"  !CDS_PN = "AB13";
"PB30B":   PN = "AA13"  !CDS_PN = "AA13";
"PB30C":   PN = "Y13"  !CDS_PN = "Y13";
"PB30D":   PN = "W13"  !CDS_PN = "W13";
"PB32A":   PN = "T13"  !CDS_PN = "T13";
"PB32B":   PN = "T14"  !CDS_PN = "T14";
"PB32C":   PN = "U14"  !CDS_PN = "U14";
"PB32D":   PN = "V14"  !CDS_PN = "V14";
"PB33A":   PN = "AB14"  !CDS_PN = "AB14";
"PB33B":   PN = "AA14"  !CDS_PN = "AA14";
"PB33C":   PN = "Y14"  !CDS_PN = "Y14";
"PB33D":   PN = "W14"  !CDS_PN = "W14";
"PB35A":   PN = "AB15"  !CDS_PN = "AB15";
"PB35B":   PN = "AA15"  !CDS_PN = "AA15";
"PB35C":   PN = "Y15"  !CDS_PN = "Y15";
"PB35D":   PN = "W15"  !CDS_PN = "W15";
"PB38A":   PN = "AB16"  !CDS_PN = "AB16";
"PB38B":   PN = "AA16"  !CDS_PN = "AA16";
"PB38C":   PN = "V15"  !CDS_PN = "V15";
"PB38D":   PN = "U15"  !CDS_PN = "U15";
"PB40A":   PN = "AB17"  !CDS_PN = "AB17";
"PB40B":   PN = "AA17"  !CDS_PN = "AA17";
"PB40C":   PN = "Y17"  !CDS_PN = "Y17";
"PB40D":   PN = "V16"  !CDS_PN = "V16";
"PB41A":   PN = "AB18"  !CDS_PN = "AB18";
"PB41B":   PN = "AA18"  !CDS_PN = "AA18";
"PB41C":   PN = "Y18"  !CDS_PN = "Y18";
"PB41D":   PN = "W17"  !CDS_PN = "W17";
"PB43A":   PN = "AB19"  !CDS_PN = "AB19";
"PB43B":   PN = "AA19"  !CDS_PN = "AA19";
"PB43C":   PN = "T15"  !CDS_PN = "T15";
"PB43D":   PN = "U16"  !CDS_PN = "U16";
"PB44A":   PN = "AB20"  !CDS_PN = "AB20";
"PB44B":   PN = "AA20"  !CDS_PN = "AA20";
"PB44C":   PN = "Y19"  !CDS_PN = "Y19";
"PB44D":   PN = "W18"  !CDS_PN = "W18";
"PB46A||SN":   PN = "AB21"  !CDS_PN = "AB21";
"PB46B||SI||SISPI":   PN = "AA21"  !CDS_PN = "AA21";
"PB46C":   PN = "V17"  !CDS_PN = "V17";
"PB46D":   PN = "T16"  !CDS_PN = "T16";
BODY = "LCMXO3LF9400C5BG484C","I217": #LOCATION = "U18" !CDS_LOCATION = "U18" &SEC = "7" #&CDS_SEC = "7";
"PR2A||R_GPLLT_FB":   PN = "C21"  !CDS_PN = "C21";
"PR2B||R_GPLLC_FB":   PN = "C22"  !CDS_PN = "C22";
"PR2C":   PN = "F17"  !CDS_PN = "F17";
"PR2D":   PN = "G16"  !CDS_PN = "G16";
"PR3A||R_GPLLT_IN":   PN = "D22"  !CDS_PN = "D22";
"PR3B||R_GPLLC_IN":   PN = "D21"  !CDS_PN = "D21";
"PR3C":   PN = "D19"  !CDS_PN = "D19";
"PR3D":   PN = "D20"  !CDS_PN = "D20";
"PR4A":   PN = "E22"  !CDS_PN = "E22";
"PR4B":   PN = "E21"  !CDS_PN = "E21";
"PR4C":   PN = "E19"  !CDS_PN = "E19";
"PR4D":   PN = "E20"  !CDS_PN = "E20";
"PR5A":   PN = "F22"  !CDS_PN = "F22";
"PR5B":   PN = "G22"  !CDS_PN = "G22";
"PR5C":   PN = "F18"  !CDS_PN = "F18";
"PR5D":   PN = "F19"  !CDS_PN = "F19";
"PR6A":   PN = "G21"  !CDS_PN = "G21";
"PR6B":   PN = "G20"  !CDS_PN = "G20";
"PR6C":   PN = "G19"  !CDS_PN = "G19";
"PR6D":   PN = "G18"  !CDS_PN = "G18";
"PR7A":   PN = "H22"  !CDS_PN = "H22";
"PR7B":   PN = "H21"  !CDS_PN = "H21";
"PR7C":   PN = "G17"  !CDS_PN = "G17";
"PR7D":   PN = "H20"  !CDS_PN = "H20";
"PR10A":   PN = "H19"  !CDS_PN = "H19";
"PR10B":   PN = "H18"  !CDS_PN = "H18";
"PR10C":   PN = "H17"  !CDS_PN = "H17";
"PR10D":   PN = "H16"  !CDS_PN = "H16";
"PR11A":   PN = "J16"  !CDS_PN = "J16";
"PR11B":   PN = "J17"  !CDS_PN = "J17";
"PR11C":   PN = "J18"  !CDS_PN = "J18";
"PR11D":   PN = "J19"  !CDS_PN = "J19";
"PR12A":   PN = "J21"  !CDS_PN = "J21";
"PR12B":   PN = "J22"  !CDS_PN = "J22";
"PR12C":   PN = "J20"  !CDS_PN = "J20";
"PR12D":   PN = "K20"  !CDS_PN = "K20";
"PR13A":   PN = "K19"  !CDS_PN = "K19";
"PR13B":   PN = "K18"  !CDS_PN = "K18";
"PR13C":   PN = "K17"  !CDS_PN = "K17";
"PR13D":   PN = "K16"  !CDS_PN = "K16";
"PR14A":   PN = "L17"  !CDS_PN = "L17";
"PR14B":   PN = "L16"  !CDS_PN = "L16";
"PR14C":   PN = "L19"  !CDS_PN = "L19";
"PR14D":   PN = "L20"  !CDS_PN = "L20";
"PR16A":   PN = "K22"  !CDS_PN = "K22";
"PR16B":   PN = "L21"  !CDS_PN = "L21";
"PR16C":   PN = "L22"  !CDS_PN = "L22";
"PR16D":   PN = "M17"  !CDS_PN = "M17";
"PR17A||PCLKT1_0":   PN = "M22"  !CDS_PN = "M22";
"PR17B||PCLKC1_0":   PN = "M21"  !CDS_PN = "M21";
"PR17C":   PN = "M20"  !CDS_PN = "M20";
"PR17D":   PN = "M19"  !CDS_PN = "M19";
"PR18A":   PN = "M16"  !CDS_PN = "M16";
"PR18B":   PN = "N16"  !CDS_PN = "N16";
"PR18C":   PN = "N17"  !CDS_PN = "N17";
"PR18D":   PN = "N18"  !CDS_PN = "N18";
"PR19A":   PN = "N22"  !CDS_PN = "N22";
"PR19B":   PN = "P21"  !CDS_PN = "P21";
"PR19C":   PN = "N20"  !CDS_PN = "N20";
"PR19D":   PN = "N19"  !CDS_PN = "N19";
"PR20A":   PN = "R22"  !CDS_PN = "R22";
"PR20B":   PN = "R21"  !CDS_PN = "R21";
"PR20C":   PN = "P22"  !CDS_PN = "P22";
"PR20D":   PN = "P20"  !CDS_PN = "P20";
"PR21A":   PN = "T22"  !CDS_PN = "T22";
"PR21B":   PN = "T21"  !CDS_PN = "T21";
"PR21C":   PN = "P19"  !CDS_PN = "P19";
"PR21D":   PN = "P18"  !CDS_PN = "P18";
"PR24A":   PN = "P17"  !CDS_PN = "P17";
"PR24B":   PN = "P16"  !CDS_PN = "P16";
"PR24C":   PN = "U22"  !CDS_PN = "U22";
"PR24D":   PN = "U21"  !CDS_PN = "U21";
"PR25A":   PN = "V22"  !CDS_PN = "V22";
"PR25B":   PN = "W22"  !CDS_PN = "W22";
"PR25C":   PN = "R20"  !CDS_PN = "R20";
"PR25D":   PN = "R19"  !CDS_PN = "R19";
"PR26A":   PN = "R18"  !CDS_PN = "R18";
"PR26B":   PN = "R17"  !CDS_PN = "R17";
"PR26C":   PN = "R16"  !CDS_PN = "R16";
"PR26D":   PN = "T20"  !CDS_PN = "T20";
"PR27A":   PN = "T19"  !CDS_PN = "T19";
"PR27B":   PN = "T18"  !CDS_PN = "T18";
"PR27C":   PN = "T17"  !CDS_PN = "T17";
"PR27D":   PN = "U20"  !CDS_PN = "U20";
"PR28A":   PN = "Y22"  !CDS_PN = "Y22";
"PR28B":   PN = "W21"  !CDS_PN = "W21";
"PR28C":   PN = "U19"  !CDS_PN = "U19";
"PR28D":   PN = "U18"  !CDS_PN = "U18";
"PR29A":   PN = "AA22"  !CDS_PN = "AA22";
"PR29B":   PN = "Y21"  !CDS_PN = "Y21";
"PR29C":   PN = "U17"  !CDS_PN = "U17";
"PR29D":   PN = "V19"  !CDS_PN = "V19";
"PR30A":   PN = "V18"  !CDS_PN = "V18";
"PR30B":   PN = "W20"  !CDS_PN = "W20";
"PR30C":   PN = "W19"  !CDS_PN = "W19";
"PR30D":   PN = "Y20"  !CDS_PN = "Y20";
BODY = "Q_RES","I220": #LOCATION = "R4170" !CDS_LOCATION = "R4170" &SEC = "1" #&CDS_SEC = "1";
"A":   PN = "1"  !CDS_PN = "1";
"B":   PN = "2"  !CDS_PN = "2";
BODY = "Q_RES","I223": #LOCATION = "R4171" !CDS_LOCATION = "R4171" &SEC = "1" #&CDS_SEC = "1";
"A":   PN = "1"  !CDS_PN = "1";
"B":   PN = "2"  !CDS_PN = "2";
BODY = "Q_RES","I224": #LOCATION = "R4172" !CDS_LOCATION = "R4172" &SEC = "1" #&CDS_SEC = "1";
"A":   PN = "1"  !CDS_PN = "1";
"B":   PN = "2"  !CDS_PN = "2";
BODY = "Q_RES","I226": #LOCATION = "R4556" !CDS_LOCATION = "R4556" &SEC = "1" #&CDS_SEC = "1";
"A":   PN = "1"  !CDS_PN = "1";
"B":   PN = "2"  !CDS_PN = "2";
BODY = "Q_RES","I228": #LOCATION = "R4558" !CDS_LOCATION = "R4558" &SEC = "1" #&CDS_SEC = "1";
"A":   PN = "1"  !CDS_PN = "1";
"B":   PN = "2"  !CDS_PN = "2";
BODY = "Q_RES","I231": #LOCATION = "R4143" !CDS_LOCATION = "R4143" &SEC = "1" #&CDS_SEC = "1";
"A":   PN = "1"  !CDS_PN = "1";
"B":   PN = "2"  !CDS_PN = "2";
BODY = "Q_RES","I233": #LOCATION = "R4144" !CDS_LOCATION = "R4144" &SEC = "1" #&CDS_SEC = "1";
"A":   PN = "1"  !CDS_PN = "1";
"B":   PN = "2"  !CDS_PN = "2";
BODY = "Q_RES","I240": #LOCATION = "R4147" !CDS_LOCATION = "R4147" &SEC = "1" #&CDS_SEC = "1";
"A":   PN = "1"  !CDS_PN = "1";
"B":   PN = "2"  !CDS_PN = "2";
BODY = "Q_RES","I242": #LOCATION = "R4148" !CDS_LOCATION = "R4148" &SEC = "1" #&CDS_SEC = "1";
"A":   PN = "1"  !CDS_PN = "1";
"B":   PN = "2"  !CDS_PN = "2";
BODY = "Q_RES","I243": #LOCATION = "R4563" !CDS_LOCATION = "R4563" &SEC = "1" #&CDS_SEC = "1";
"A":   PN = "1"  !CDS_PN = "1";
"B":   PN = "2"  !CDS_PN = "2";
BODY = "Q_RES","I246": #LOCATION = "R4157" !CDS_LOCATION = "R4157" &SEC = "1" #&CDS_SEC = "1";
"A":   PN = "1"  !CDS_PN = "1";
"B":   PN = "2"  !CDS_PN = "2";
BODY = "Q_RES","I247": #LOCATION = "R3480" !CDS_LOCATION = "R3480" &SEC = "1" #&CDS_SEC = "1";
"A":   PN = "1"  !CDS_PN = "1";
"B":   PN = "2"  !CDS_PN = "2";
BODY = "Q_RES","I250": #LOCATION = "R3476" !CDS_LOCATION = "R3476" &SEC = "1" #&CDS_SEC = "1";
"A":   PN = "1"  !CDS_PN = "1";
"B":   PN = "2"  !CDS_PN = "2";
BODY = "Q_RES","I251": #LOCATION = "R3481" !CDS_LOCATION = "R3481" &SEC = "1" #&CDS_SEC = "1";
"A":   PN = "1"  !CDS_PN = "1";
"B":   PN = "2"  !CDS_PN = "2";
BODY = "Q_RES","I254": #LOCATION = "R3484" !CDS_LOCATION = "R3484" &SEC = "1" #&CDS_SEC = "1";
"A":   PN = "1"  !CDS_PN = "1";
"B":   PN = "2"  !CDS_PN = "2";
BODY = "Q_RES","I255": #LOCATION = "R3485" !CDS_LOCATION = "R3485" &SEC = "1" #&CDS_SEC = "1";
"A":   PN = "1"  !CDS_PN = "1";
"B":   PN = "2"  !CDS_PN = "2";
BODY = "Q_RES","I258": #LOCATION = "R3486" !CDS_LOCATION = "R3486" &SEC = "1" #&CDS_SEC = "1";
"A":   PN = "1"  !CDS_PN = "1";
"B":   PN = "2"  !CDS_PN = "2";
BODY = "Q_RES","I259": #LOCATION = "R3505" !CDS_LOCATION = "R3505" &SEC = "1" #&CDS_SEC = "1";
"A":   PN = "1"  !CDS_PN = "1";
"B":   PN = "2"  !CDS_PN = "2";
BODY = "Q_RES","I262": #LOCATION = "R2846" !CDS_LOCATION = "R2846" &SEC = "1" #&CDS_SEC = "1";
"A":   PN = "1"  !CDS_PN = "1";
"B":   PN = "2"  !CDS_PN = "2";
BODY = "Q_RES","I263": #LOCATION = "R2844" !CDS_LOCATION = "R2844" &SEC = "1" #&CDS_SEC = "1";
"A":   PN = "1"  !CDS_PN = "1";
"B":   PN = "2"  !CDS_PN = "2";
BODY = "Q_RES","I266": #LOCATION = "R2847" !CDS_LOCATION = "R2847" &SEC = "1" #&CDS_SEC = "1";
"A":   PN = "1"  !CDS_PN = "1";
"B":   PN = "2"  !CDS_PN = "2";
BODY = "Q_RES","I268": #LOCATION = "R3066" !CDS_LOCATION = "R3066" &SEC = "1" #&CDS_SEC = "1";
"A":   PN = "1"  !CDS_PN = "1";
"B":   PN = "2"  !CDS_PN = "2";
BODY = "Q_RES","I271": #LOCATION = "R2663" !CDS_LOCATION = "R2663" &SEC = "1" #&CDS_SEC = "1";
"A":   PN = "1"  !CDS_PN = "1";
"B":   PN = "2"  !CDS_PN = "2";
BODY = "Q_RES","I272": #LOCATION = "R2664" !CDS_LOCATION = "R2664" &SEC = "1" #&CDS_SEC = "1";
"A":   PN = "1"  !CDS_PN = "1";
"B":   PN = "2"  !CDS_PN = "2";
BODY = "Q_RES","I274": #LOCATION = "R11667" !CDS_LOCATION = "R11667" &SEC = "1" #&CDS_SEC = "1";
"A":   PN = "1"  !CDS_PN = "1";
"B":   PN = "2"  !CDS_PN = "2";
BODY = "Q_RES","I276": #LOCATION = "R3324" !CDS_LOCATION = "R3324" &SEC = "1" #&CDS_SEC = "1";
"A":   PN = "1"  !CDS_PN = "1";
"B":   PN = "2"  !CDS_PN = "2";
BODY = "Q_RES","I278": #LOCATION = "R3482" !CDS_LOCATION = "R3482" &SEC = "1" #&CDS_SEC = "1";
"A":   PN = "1"  !CDS_PN = "1";
"B":   PN = "2"  !CDS_PN = "2";
BODY = "Q_RES","I281": #LOCATION = "R3479" !CDS_LOCATION = "R3479" &SEC = "1" #&CDS_SEC = "1";
"A":   PN = "1"  !CDS_PN = "1";
"B":   PN = "2"  !CDS_PN = "2";
BODY = "Q_RES","I284": #LOCATION = "R2261" !CDS_LOCATION = "R2261" &SEC = "1" #&CDS_SEC = "1";
"A":   PN = "1"  !CDS_PN = "1";
"B":   PN = "2"  !CDS_PN = "2";
BODY = "Q_RES","I286": #LOCATION = "R3477" !CDS_LOCATION = "R3477" &SEC = "1" #&CDS_SEC = "1";
"A":   PN = "1"  !CDS_PN = "1";
"B":   PN = "2"  !CDS_PN = "2";
BODY = "Q_RES","I288": #LOCATION = "R3478" !CDS_LOCATION = "R3478" &SEC = "1" #&CDS_SEC = "1";
"A":   PN = "1"  !CDS_PN = "1";
"B":   PN = "2"  !CDS_PN = "2";
BODY = "Q_RES","I290": #LOCATION = "R3483" !CDS_LOCATION = "R3483" &SEC = "1" #&CDS_SEC = "1";
"A":   PN = "1"  !CDS_PN = "1";
"B":   PN = "2"  !CDS_PN = "2";
BODY = "Q_RES","I293": #LOCATION = "R2845" !CDS_LOCATION = "R2845" &SEC = "1" #&CDS_SEC = "1";
"A":   PN = "1"  !CDS_PN = "1";
"B":   PN = "2"  !CDS_PN = "2";
BODY = "Q_RES","I294": #LOCATION = "R2262" !CDS_LOCATION = "R2262" &SEC = "1" #&CDS_SEC = "1";
"A":   PN = "1"  !CDS_PN = "1";
"B":   PN = "2"  !CDS_PN = "2";
BODY = "Q_RES","I295": #LOCATION = "R4608" !CDS_LOCATION = "R4608" &SEC = "1" #&CDS_SEC = "1";
"A":   PN = "1"  !CDS_PN = "1";
"B":   PN = "2"  !CDS_PN = "2";
BODY = "Q_RES","I298": #LOCATION = "R6085" !CDS_LOCATION = "R6085" &SEC = "1" #&CDS_SEC = "1";
"A":   PN = "1"  !CDS_PN = "1";
"B":   PN = "2"  !CDS_PN = "2";
BODY = "Q_RES","I301": #LOCATION = "R4557" !CDS_LOCATION = "R4557" &SEC = "1" #&CDS_SEC = "1";
"A":   PN = "1"  !CDS_PN = "1";
"B":   PN = "2"  !CDS_PN = "2";
BODY = "Q_RES","I303": #LOCATION = "R195" !CDS_LOCATION = "R195" &SEC = "1" #&CDS_SEC = "1";
"A":   PN = "1"  !CDS_PN = "1";
"B":   PN = "2"  !CDS_PN = "2";
BODY = "Q_RES","I311": #LOCATION = "R2939" !CDS_LOCATION = "R2939" &SEC = "1" #&CDS_SEC = "1";
"A":   PN = "1"  !CDS_PN = "1";
"B":   PN = "2"  !CDS_PN = "2";
BODY = "Q_RES","I315": #LOCATION = "R8000" !CDS_LOCATION = "R8000" &SEC = "1" #&CDS_SEC = "1";
"A":   PN = "1"  !CDS_PN = "1";
"B":   PN = "2"  !CDS_PN = "2";
BODY = "Q_RES","I318": #LOCATION = "R8021" !CDS_LOCATION = "R8021" #SEC = "1" !CDS_SEC = "1";
"A":   PN = "1"  !CDS_PN = "1";
"B":   PN = "2"  !CDS_PN = "2";
BODY = "Q_RES","I319": #LOCATION = "R8032" !CDS_LOCATION = "R8032" &SEC = "1" #&CDS_SEC = "1";
"A":   PN = "1"  !CDS_PN = "1";
"B":   PN = "2"  !CDS_PN = "2";
BODY = "Q_RES","I322": #LOCATION = "R6710" !CDS_LOCATION = "R6710" &SEC = "1" #&CDS_SEC = "1";
"A":   PN = "1"  !CDS_PN = "1";
"B":   PN = "2"  !CDS_PN = "2";
BODY = "Q_RES","I324": #LOCATION = "R6711" !CDS_LOCATION = "R6711" &SEC = "1" #&CDS_SEC = "1";
"A":   PN = "1"  !CDS_PN = "1";
"B":   PN = "2"  !CDS_PN = "2";
BODY = "Q_RES","I326": #LOCATION = "R6740" !CDS_LOCATION = "R6740" &SEC = "1" #&CDS_SEC = "1";
"A":   PN = "1"  !CDS_PN = "1";
"B":   PN = "2"  !CDS_PN = "2";
BODY = "Q_RES","I327": #LOCATION = "R6741" !CDS_LOCATION = "R6741" &SEC = "1" #&CDS_SEC = "1";
"A":   PN = "1"  !CDS_PN = "1";
"B":   PN = "2"  !CDS_PN = "2";
BODY = "Q_RES","I330": #LOCATION = "R6777" !CDS_LOCATION = "R6777" &SEC = "1" #&CDS_SEC = "1";
"A":   PN = "1"  !CDS_PN = "1";
"B":   PN = "2"  !CDS_PN = "2";
BODY = "Q_RES","I332": #LOCATION = "R6781" !CDS_LOCATION = "R6781" &SEC = "1" #&CDS_SEC = "1";
"A":   PN = "1"  !CDS_PN = "1";
"B":   PN = "2"  !CDS_PN = "2";
BODY = "Q_RES","I334": #LOCATION = "R6792" !CDS_LOCATION = "R6792" &SEC = "1" #&CDS_SEC = "1";
"A":   PN = "1"  !CDS_PN = "1";
"B":   PN = "2"  !CDS_PN = "2";
BODY = "Q_RES","I335": #LOCATION = "R6793" !CDS_LOCATION = "R6793" &SEC = "1" #&CDS_SEC = "1";
"A":   PN = "1"  !CDS_PN = "1";
"B":   PN = "2"  !CDS_PN = "2";
BODY = "Q_RES","I338": #LOCATION = "R6798" !CDS_LOCATION = "R6798" &SEC = "1" #&CDS_SEC = "1";
"A":   PN = "1"  !CDS_PN = "1";
"B":   PN = "2"  !CDS_PN = "2";
BODY = "Q_RES","I339": #LOCATION = "R6799" !CDS_LOCATION = "R6799" &SEC = "1" #&CDS_SEC = "1";
"A":   PN = "1"  !CDS_PN = "1";
"B":   PN = "2"  !CDS_PN = "2";
BODY = "Q_RES","I342": #LOCATION = "R6804" !CDS_LOCATION = "R6804" &SEC = "1" #&CDS_SEC = "1";
"A":   PN = "1"  !CDS_PN = "1";
"B":   PN = "2"  !CDS_PN = "2";
BODY = "Q_RES","I343": #LOCATION = "R6805" !CDS_LOCATION = "R6805" &SEC = "1" #&CDS_SEC = "1";
"A":   PN = "1"  !CDS_PN = "1";
"B":   PN = "2"  !CDS_PN = "2";
BODY = "Q_RES","I344": #LOCATION = "R6806" !CDS_LOCATION = "R6806" &SEC = "1" #&CDS_SEC = "1";
"A":   PN = "1"  !CDS_PN = "1";
"B":   PN = "2"  !CDS_PN = "2";
BODY = "Q_RES","I345": #LOCATION = "R6807" !CDS_LOCATION = "R6807" &SEC = "1" #&CDS_SEC = "1";
"A":   PN = "1"  !CDS_PN = "1";
"B":   PN = "2"  !CDS_PN = "2";
BODY = "Q_RES","I350": #LOCATION = "R6823" !CDS_LOCATION = "R6823" &SEC = "1" #&CDS_SEC = "1";
"A":   PN = "1"  !CDS_PN = "1";
"B":   PN = "2"  !CDS_PN = "2";
BODY = "Q_RES","I351": #LOCATION = "R6824" !CDS_LOCATION = "R6824" &SEC = "1" #&CDS_SEC = "1";
"A":   PN = "1"  !CDS_PN = "1";
"B":   PN = "2"  !CDS_PN = "2";
BODY = "Q_RES","I352": #LOCATION = "R6825" !CDS_LOCATION = "R6825" &SEC = "1" #&CDS_SEC = "1";
"A":   PN = "1"  !CDS_PN = "1";
"B":   PN = "2"  !CDS_PN = "2";
BODY = "Q_RES","I353": #LOCATION = "R6826" !CDS_LOCATION = "R6826" &SEC = "1" #&CDS_SEC = "1";
"A":   PN = "1"  !CDS_PN = "1";
"B":   PN = "2"  !CDS_PN = "2";
BODY = "Q_RES","I360": #LOCATION = "R6852" !CDS_LOCATION = "R6852" &SEC = "1" #&CDS_SEC = "1";
"A":   PN = "1"  !CDS_PN = "1";
"B":   PN = "2"  !CDS_PN = "2";
BODY = "Q_RES","I362": #LOCATION = "R6853" !CDS_LOCATION = "R6853" &SEC = "1" #&CDS_SEC = "1";
"A":   PN = "1"  !CDS_PN = "1";
"B":   PN = "2"  !CDS_PN = "2";
BODY = "Q_RES","I364": #LOCATION = "R6854" !CDS_LOCATION = "R6854" &SEC = "1" #&CDS_SEC = "1";
"A":   PN = "1"  !CDS_PN = "1";
"B":   PN = "2"  !CDS_PN = "2";
BODY = "Q_RES","I366": #LOCATION = "R6855" !CDS_LOCATION = "R6855" &SEC = "1" #&CDS_SEC = "1";
"A":   PN = "1"  !CDS_PN = "1";
"B":   PN = "2"  !CDS_PN = "2";
DRAWING = "@t6g_mb_lib.t6g(sch_1):page248";
BODY = "Q_CAP","I4": #LOCATION = "C1859" !CDS_LOCATION = "C1859" &SEC = "1" #&CDS_SEC = "1";
"A":   PN = "1"  !CDS_PN = "1";
"B":   PN = "2"  !CDS_PN = "2";
BODY = "PCA9617ADP","I6": #LOCATION = "U235" !CDS_LOCATION = "U235" &SEC = "1" #&CDS_SEC = "1";
"EN":   PN = "5"  !CDS_PN = "5";
"GND":   PN = "4"  !CDS_PN = "4";
"SCLA":   PN = "2"  !CDS_PN = "2";
"SCLB":   PN = "7"  !CDS_PN = "7";
"SDAA":   PN = "3"  !CDS_PN = "3";
"SDAB":   PN = "6"  !CDS_PN = "6";
"VCCA":   PN = "1"  !CDS_PN = "1";
"VCCB":   PN = "8"  !CDS_PN = "8";
BODY = "Q_CAP","I9": #LOCATION = "C1861" !CDS_LOCATION = "C1861" &SEC = "1" #&CDS_SEC = "1";
"A":   PN = "1"  !CDS_PN = "1";
"B":   PN = "2"  !CDS_PN = "2";
BODY = "PCA9617ADP","I14": #LOCATION = "U236" !CDS_LOCATION = "U236" &SEC = "1" #&CDS_SEC = "1";
"EN":   PN = "5"  !CDS_PN = "5";
"GND":   PN = "4"  !CDS_PN = "4";
"SCLA":   PN = "2"  !CDS_PN = "2";
"SCLB":   PN = "7"  !CDS_PN = "7";
"SDAA":   PN = "3"  !CDS_PN = "3";
"SDAB":   PN = "6"  !CDS_PN = "6";
"VCCA":   PN = "1"  !CDS_PN = "1";
"VCCB":   PN = "8"  !CDS_PN = "8";
BODY = "Q_CAP","I15": #LOCATION = "C1860" !CDS_LOCATION = "C1860" &SEC = "1" #&CDS_SEC = "1";
"A":   PN = "1"  !CDS_PN = "1";
"B":   PN = "2"  !CDS_PN = "2";
BODY = "Q_CAP","I19": #LOCATION = "C1862" !CDS_LOCATION = "C1862" &SEC = "1" #&CDS_SEC = "1";
"A":   PN = "1"  !CDS_PN = "1";
"B":   PN = "2"  !CDS_PN = "2";
BODY = "Q_RES","I23": #LOCATION = "R3520" !CDS_LOCATION = "R3520" &SEC = "1" #&CDS_SEC = "1";
"A":   PN = "1"  !CDS_PN = "1";
"B":   PN = "2"  !CDS_PN = "2";
BODY = "Q_RES","I27": #LOCATION = "R3500" !CDS_LOCATION = "R3500" &SEC = "1" #&CDS_SEC = "1";
"A":   PN = "1"  !CDS_PN = "1";
"B":   PN = "2"  !CDS_PN = "2";
BODY = "Q_RES","I31": #LOCATION = "R3501" !CDS_LOCATION = "R3501" &SEC = "1" #&CDS_SEC = "1";
"A":   PN = "1"  !CDS_PN = "1";
"B":   PN = "2"  !CDS_PN = "2";
BODY = "Q_RES","I34": #LOCATION = "R3519" !CDS_LOCATION = "R3519" &SEC = "1" #&CDS_SEC = "1";
"A":   PN = "1"  !CDS_PN = "1";
"B":   PN = "2"  !CDS_PN = "2";
BODY = "Q_RES","I35": #LOCATION = "R3263" !CDS_LOCATION = "R3263" &SEC = "1" #&CDS_SEC = "1";
"A":   PN = "1"  !CDS_PN = "1";
"B":   PN = "2"  !CDS_PN = "2";
BODY = "Q_RES","I38": #LOCATION = "R3264" !CDS_LOCATION = "R3264" &SEC = "1" #&CDS_SEC = "1";
"A":   PN = "1"  !CDS_PN = "1";
"B":   PN = "2"  !CDS_PN = "2";
BODY = "Q_RES","I41": #LOCATION = "R1135" !CDS_LOCATION = "R1135" &SEC = "1" #&CDS_SEC = "1";
"A":   PN = "1"  !CDS_PN = "1";
"B":   PN = "2"  !CDS_PN = "2";
BODY = "Q_RES","I43": #LOCATION = "R1500" !CDS_LOCATION = "R1500" &SEC = "1" #&CDS_SEC = "1";
"A":   PN = "1"  !CDS_PN = "1";
"B":   PN = "2"  !CDS_PN = "2";
BODY = "Q_RES","I44": #LOCATION = "R1522" !CDS_LOCATION = "R1522" &SEC = "1" #&CDS_SEC = "1";
"A":   PN = "1"  !CDS_PN = "1";
"B":   PN = "2"  !CDS_PN = "2";
BODY = "Q_RES","I45": #LOCATION = "R1180" !CDS_LOCATION = "R1180" &SEC = "1" #&CDS_SEC = "1";
"A":   PN = "1"  !CDS_PN = "1";
"B":   PN = "2"  !CDS_PN = "2";
DRAWING = "@t6g_mb_lib.t6g(sch_1):page249";
BODY = "Q_RES","I8": #LOCATION = "R2666" !CDS_LOCATION = "R2666" &SEC = "1" #&CDS_SEC = "1";
"A":   PN = "1"  !CDS_PN = "1";
"B":   PN = "2"  !CDS_PN = "2";
BODY = "Q_RES","I12": #LOCATION = "R2992" !CDS_LOCATION = "R2992" &SEC = "1" #&CDS_SEC = "1";
"A":   PN = "1"  !CDS_PN = "1";
"B":   PN = "2"  !CDS_PN = "2";
BODY = "Q_RES","I13": #LOCATION = "R3107" !CDS_LOCATION = "R3107" &SEC = "1" #&CDS_SEC = "1";
"A":   PN = "1"  !CDS_PN = "1";
"B":   PN = "2"  !CDS_PN = "2";
BODY = "Q_RES","I14": #LOCATION = "R3108" !CDS_LOCATION = "R3108" &SEC = "1" #&CDS_SEC = "1";
"A":   PN = "1"  !CDS_PN = "1";
"B":   PN = "2"  !CDS_PN = "2";
BODY = "LTC4307CMS8","I15": #LOCATION = "U200" !CDS_LOCATION = "U200" &SEC = "1" #&CDS_SEC = "1";
"ENABLE":   PN = "1"  !CDS_PN = "1";
"GND":   PN = "4"  !CDS_PN = "4";
"READY":   PN = "5"  !CDS_PN = "5";
"SCL_IN":   PN = "3"  !CDS_PN = "3";
"SCL_OUT":   PN = "2"  !CDS_PN = "2";
"SDA_IN":   PN = "6"  !CDS_PN = "6";
"SDA_OUT":   PN = "7"  !CDS_PN = "7";
"VCC":   PN = "8"  !CDS_PN = "8";
BODY = "Q_RES","I17": #LOCATION = "R2987" !CDS_LOCATION = "R2987" &SEC = "1" #&CDS_SEC = "1";
"A":   PN = "1"  !CDS_PN = "1";
"B":   PN = "2"  !CDS_PN = "2";
BODY = "Q_RES","I18": #LOCATION = "R2986" !CDS_LOCATION = "R2986" &SEC = "1" #&CDS_SEC = "1";
"A":   PN = "1"  !CDS_PN = "1";
"B":   PN = "2"  !CDS_PN = "2";
BODY = "Q_RES","I23": #LOCATION = "R4603" !CDS_LOCATION = "R4603" &SEC = "1" #&CDS_SEC = "1";
"A":   PN = "1"  !CDS_PN = "1";
"B":   PN = "2"  !CDS_PN = "2";
BODY = "Q_RES","I25": #LOCATION = "R3112" !CDS_LOCATION = "R3112" &SEC = "1" #&CDS_SEC = "1";
"A":   PN = "1"  !CDS_PN = "1";
"B":   PN = "2"  !CDS_PN = "2";
BODY = "Q_RES","I26": #LOCATION = "R2676" !CDS_LOCATION = "R2676" &SEC = "1" #&CDS_SEC = "1";
"A":   PN = "1"  !CDS_PN = "1";
"B":   PN = "2"  !CDS_PN = "2";
BODY = "Q_RES","I27": #LOCATION = "R2706" !CDS_LOCATION = "R2706" &SEC = "1" #&CDS_SEC = "1";
"A":   PN = "1"  !CDS_PN = "1";
"B":   PN = "2"  !CDS_PN = "2";
BODY = "Q_RES","I28": #LOCATION = "R2725" !CDS_LOCATION = "R2725" &SEC = "1" #&CDS_SEC = "1";
"A":   PN = "1"  !CDS_PN = "1";
"B":   PN = "2"  !CDS_PN = "2";
BODY = "LTC4307CMS8","I30": #LOCATION = "U176" !CDS_LOCATION = "U176" &SEC = "1" #&CDS_SEC = "1";
"ENABLE":   PN = "1"  !CDS_PN = "1";
"GND":   PN = "4"  !CDS_PN = "4";
"READY":   PN = "5"  !CDS_PN = "5";
"SCL_IN":   PN = "3"  !CDS_PN = "3";
"SCL_OUT":   PN = "2"  !CDS_PN = "2";
"SDA_IN":   PN = "6"  !CDS_PN = "6";
"SDA_OUT":   PN = "7"  !CDS_PN = "7";
"VCC":   PN = "8"  !CDS_PN = "8";
BODY = "Q_CAP","I32": #LOCATION = "C1796" !CDS_LOCATION = "C1796" &SEC = "1" #&CDS_SEC = "1";
"A":   PN = "1"  !CDS_PN = "1";
"B":   PN = "2"  !CDS_PN = "2";
BODY = "Q_RES","I34": #LOCATION = "R3110" !CDS_LOCATION = "R3110" &SEC = "1" #&CDS_SEC = "1";
"A":   PN = "1"  !CDS_PN = "1";
"B":   PN = "2"  !CDS_PN = "2";
BODY = "Q_RES","I35": #LOCATION = "R3109" !CDS_LOCATION = "R3109" &SEC = "1" #&CDS_SEC = "1";
"A":   PN = "1"  !CDS_PN = "1";
"B":   PN = "2"  !CDS_PN = "2";
BODY = "Q_RES","I36": #LOCATION = "R3521" !CDS_LOCATION = "R3521" &SEC = "1" #&CDS_SEC = "1";
"A":   PN = "1"  !CDS_PN = "1";
"B":   PN = "2"  !CDS_PN = "2";
BODY = "Q_RES","I37": #LOCATION = "R3522" !CDS_LOCATION = "R3522" &SEC = "1" #&CDS_SEC = "1";
"A":   PN = "1"  !CDS_PN = "1";
"B":   PN = "2"  !CDS_PN = "2";
BODY = "Q_RES","I38": #LOCATION = "R2990" !CDS_LOCATION = "R2990" &SEC = "1" #&CDS_SEC = "1";
"A":   PN = "1"  !CDS_PN = "1";
"B":   PN = "2"  !CDS_PN = "2";
BODY = "Q_RES","I39": #LOCATION = "R2991" !CDS_LOCATION = "R2991" &SEC = "1" #&CDS_SEC = "1";
"A":   PN = "1"  !CDS_PN = "1";
"B":   PN = "2"  !CDS_PN = "2";
BODY = "LTC4307CMS8","I42": #LOCATION = "U194" !CDS_LOCATION = "U194" &SEC = "1" #&CDS_SEC = "1";
"ENABLE":   PN = "1"  !CDS_PN = "1";
"GND":   PN = "4"  !CDS_PN = "4";
"READY":   PN = "5"  !CDS_PN = "5";
"SCL_IN":   PN = "3"  !CDS_PN = "3";
"SCL_OUT":   PN = "2"  !CDS_PN = "2";
"SDA_IN":   PN = "6"  !CDS_PN = "6";
"SDA_OUT":   PN = "7"  !CDS_PN = "7";
"VCC":   PN = "8"  !CDS_PN = "8";
BODY = "Q_RES","I43": #LOCATION = "R3106" !CDS_LOCATION = "R3106" &SEC = "1" #&CDS_SEC = "1";
"A":   PN = "1"  !CDS_PN = "1";
"B":   PN = "2"  !CDS_PN = "2";
BODY = "Q_RES","I44": #LOCATION = "R3105" !CDS_LOCATION = "R3105" &SEC = "1" #&CDS_SEC = "1";
"A":   PN = "1"  !CDS_PN = "1";
"B":   PN = "2"  !CDS_PN = "2";
BODY = "Q_RES","I45": #LOCATION = "R2707" !CDS_LOCATION = "R2707" &SEC = "1" #&CDS_SEC = "1";
"A":   PN = "1"  !CDS_PN = "1";
"B":   PN = "2"  !CDS_PN = "2";
BODY = "Q_RES","I47": #LOCATION = "R2705" !CDS_LOCATION = "R2705" &SEC = "1" #&CDS_SEC = "1";
"A":   PN = "1"  !CDS_PN = "1";
"B":   PN = "2"  !CDS_PN = "2";
BODY = "Q_RES","I48": #LOCATION = "R2724" !CDS_LOCATION = "R2724" &SEC = "1" #&CDS_SEC = "1";
"A":   PN = "1"  !CDS_PN = "1";
"B":   PN = "2"  !CDS_PN = "2";
BODY = "LTC4307CMS8","I49": #LOCATION = "U175" !CDS_LOCATION = "U175" &SEC = "1" #&CDS_SEC = "1";
"ENABLE":   PN = "1"  !CDS_PN = "1";
"GND":   PN = "4"  !CDS_PN = "4";
"READY":   PN = "5"  !CDS_PN = "5";
"SCL_IN":   PN = "3"  !CDS_PN = "3";
"SCL_OUT":   PN = "2"  !CDS_PN = "2";
"SDA_IN":   PN = "6"  !CDS_PN = "6";
"SDA_OUT":   PN = "7"  !CDS_PN = "7";
"VCC":   PN = "8"  !CDS_PN = "8";
BODY = "Q_RES","I50": #LOCATION = "R2899" !CDS_LOCATION = "R2899" &SEC = "1" #&CDS_SEC = "1";
"A":   PN = "1"  !CDS_PN = "1";
"B":   PN = "2"  !CDS_PN = "2";
BODY = "Q_CAP","I52": #LOCATION = "C1707" !CDS_LOCATION = "C1707" &SEC = "1" #&CDS_SEC = "1";
"A":   PN = "1"  !CDS_PN = "1";
"B":   PN = "2"  !CDS_PN = "2";
BODY = "Q_RES","I54": #LOCATION = "R2667" !CDS_LOCATION = "R2667" &SEC = "1" #&CDS_SEC = "1";
"A":   PN = "1"  !CDS_PN = "1";
"B":   PN = "2"  !CDS_PN = "2";
BODY = "Q_RES","I56": #LOCATION = "R2672" !CDS_LOCATION = "R2672" &SEC = "1" #&CDS_SEC = "1";
"A":   PN = "1"  !CDS_PN = "1";
"B":   PN = "2"  !CDS_PN = "2";
BODY = "Q_RES","I57": #LOCATION = "R2669" !CDS_LOCATION = "R2669" &SEC = "1" #&CDS_SEC = "1";
"A":   PN = "1"  !CDS_PN = "1";
"B":   PN = "2"  !CDS_PN = "2";
BODY = "Q_RES","I58": #LOCATION = "R2671" !CDS_LOCATION = "R2671" &SEC = "1" #&CDS_SEC = "1";
"A":   PN = "1"  !CDS_PN = "1";
"B":   PN = "2"  !CDS_PN = "2";
BODY = "Q_CAP","I61": #LOCATION = "C1708" !CDS_LOCATION = "C1708" &SEC = "1" #&CDS_SEC = "1";
"A":   PN = "1"  !CDS_PN = "1";
"B":   PN = "2"  !CDS_PN = "2";
BODY = "Q_RES","I62": #LOCATION = "R2668" !CDS_LOCATION = "R2668" &SEC = "1" #&CDS_SEC = "1";
"A":   PN = "1"  !CDS_PN = "1";
"B":   PN = "2"  !CDS_PN = "2";
BODY = "Q_RES","I63": #LOCATION = "R2670" !CDS_LOCATION = "R2670" &SEC = "1" #&CDS_SEC = "1";
"A":   PN = "1"  !CDS_PN = "1";
"B":   PN = "2"  !CDS_PN = "2";
BODY = "Q_RES","I67": #LOCATION = "R2894" !CDS_LOCATION = "R2894" &SEC = "1" #&CDS_SEC = "1";
"A":   PN = "1"  !CDS_PN = "1";
"B":   PN = "2"  !CDS_PN = "2";
BODY = "Q_RES","I68": #LOCATION = "R2893" !CDS_LOCATION = "R2893" &SEC = "1" #&CDS_SEC = "1";
"A":   PN = "1"  !CDS_PN = "1";
"B":   PN = "2"  !CDS_PN = "2";
BODY = "Q_RES","I69": #LOCATION = "R2675" !CDS_LOCATION = "R2675" &SEC = "1" #&CDS_SEC = "1";
"A":   PN = "1"  !CDS_PN = "1";
"B":   PN = "2"  !CDS_PN = "2";
BODY = "Q_RES","I73": #LOCATION = "R2898" !CDS_LOCATION = "R2898" &SEC = "1" #&CDS_SEC = "1";
"A":   PN = "1"  !CDS_PN = "1";
"B":   PN = "2"  !CDS_PN = "2";
BODY = "Q_RES","I74": #LOCATION = "R2897" !CDS_LOCATION = "R2897" &SEC = "1" #&CDS_SEC = "1";
"A":   PN = "1"  !CDS_PN = "1";
"B":   PN = "2"  !CDS_PN = "2";
BODY = "Q_CAP","I78": #LOCATION = "C1766" !CDS_LOCATION = "C1766" &SEC = "1" #&CDS_SEC = "1";
"A":   PN = "1"  !CDS_PN = "1";
"B":   PN = "2"  !CDS_PN = "2";
BODY = "Q_RES","I80": #LOCATION = "R3523" !CDS_LOCATION = "R3523" &SEC = "1" #&CDS_SEC = "1";
"A":   PN = "1"  !CDS_PN = "1";
"B":   PN = "2"  !CDS_PN = "2";
BODY = "Q_RES","I81": #LOCATION = "R3524" !CDS_LOCATION = "R3524" &SEC = "1" #&CDS_SEC = "1";
"A":   PN = "1"  !CDS_PN = "1";
"B":   PN = "2"  !CDS_PN = "2";
BODY = "Q_RES","I85": #LOCATION = "R3111" !CDS_LOCATION = "R3111" &SEC = "1" #&CDS_SEC = "1";
"A":   PN = "1"  !CDS_PN = "1";
"B":   PN = "2"  !CDS_PN = "2";
BODY = "Q_RES","I86": #LOCATION = "R2674" !CDS_LOCATION = "R2674" &SEC = "1" #&CDS_SEC = "1";
"A":   PN = "1"  !CDS_PN = "1";
"B":   PN = "2"  !CDS_PN = "2";
DRAWING = "@t6g_mb_lib.t6g(sch_1):page137";
BODY = "Q_CAP","I6": #LOCATION = "C611" !CDS_LOCATION = "C611" &SEC = "1" #&CDS_SEC = "1";
"A":   PN = "1"  !CDS_PN = "1";
"B":   PN = "2"  !CDS_PN = "2";
BODY = "Q_CAP","I8": #LOCATION = "C612" !CDS_LOCATION = "C612" &SEC = "1" #&CDS_SEC = "1";
"A":   PN = "1"  !CDS_PN = "1";
"B":   PN = "2"  !CDS_PN = "2";
BODY = "Q_RES","I13": #LOCATION = "R200" !CDS_LOCATION = "R200" &SEC = "1" #&CDS_SEC = "1";
"A":   PN = "1"  !CDS_PN = "1";
"B":   PN = "2"  !CDS_PN = "2";
BODY = "Q_RES","I15": #LOCATION = "R1154" !CDS_LOCATION = "R1154" &SEC = "1" #&CDS_SEC = "1";
"A":   PN = "1"  !CDS_PN = "1";
"B":   PN = "2"  !CDS_PN = "2";
BODY = "Q_RES","I16": #LOCATION = "R1153" !CDS_LOCATION = "R1153" &SEC = "1" #&CDS_SEC = "1";
"A":   PN = "1"  !CDS_PN = "1";
"B":   PN = "2"  !CDS_PN = "2";
BODY = "Q_CAP","I26": #LOCATION = "C23" !CDS_LOCATION = "C23" &SEC = "1" #&CDS_SEC = "1";
"A":   PN = "1"  !CDS_PN = "1";
"B":   PN = "2"  !CDS_PN = "2";
BODY = "Q_CAP","I29": #LOCATION = "C26" !CDS_LOCATION = "C26" &SEC = "1" #&CDS_SEC = "1";
"A":   PN = "1"  !CDS_PN = "1";
"B":   PN = "2"  !CDS_PN = "2";
BODY = "Q_RES","I31": #LOCATION = "R78" !CDS_LOCATION = "R78" &SEC = "1" #&CDS_SEC = "1";
"A":   PN = "1"  !CDS_PN = "1";
"B":   PN = "2"  !CDS_PN = "2";
BODY = "Q_RES","I40": #LOCATION = "R361" !CDS_LOCATION = "R361" &SEC = "1" #&CDS_SEC = "1";
"A":   PN = "1"  !CDS_PN = "1";
"B":   PN = "2"  !CDS_PN = "2";
BODY = "Q_RES","I41": #LOCATION = "R365" !CDS_LOCATION = "R365" &SEC = "1" #&CDS_SEC = "1";
"A":   PN = "1"  !CDS_PN = "1";
"B":   PN = "2"  !CDS_PN = "2";
BODY = "Q_RES","I44": #LOCATION = "R368" !CDS_LOCATION = "R368" &SEC = "1" #&CDS_SEC = "1";
"A":   PN = "1"  !CDS_PN = "1";
"B":   PN = "2"  !CDS_PN = "2";
BODY = "Q_RES","I46": #LOCATION = "R406" !CDS_LOCATION = "R406" &SEC = "1" #&CDS_SEC = "1";
"A":   PN = "1"  !CDS_PN = "1";
"B":   PN = "2"  !CDS_PN = "2";
BODY = "PCA9617ADP","I48": #LOCATION = "U5" !CDS_LOCATION = "U5" &SEC = "1" #&CDS_SEC = "1";
"EN":   PN = "5"  !CDS_PN = "5";
"GND":   PN = "4"  !CDS_PN = "4";
"SCLA":   PN = "2"  !CDS_PN = "2";
"SCLB":   PN = "7"  !CDS_PN = "7";
"SDAA":   PN = "3"  !CDS_PN = "3";
"SDAB":   PN = "6"  !CDS_PN = "6";
"VCCA":   PN = "1"  !CDS_PN = "1";
"VCCB":   PN = "8"  !CDS_PN = "8";
BODY = "PCA9617ADP","I51": #LOCATION = "U96" !CDS_LOCATION = "U96" #SEC = "1" !CDS_SEC = "1";
"EN":   PN = "5"  !CDS_PN = "5";
"GND":   PN = "4"  !CDS_PN = "4";
"SCLA":   PN = "2"  !CDS_PN = "2";
"SCLB":   PN = "7"  !CDS_PN = "7";
"SDAA":   PN = "3"  !CDS_PN = "3";
"SDAB":   PN = "6"  !CDS_PN = "6";
"VCCA":   PN = "1"  !CDS_PN = "1";
"VCCB":   PN = "8"  !CDS_PN = "8";
BODY = "Q_CAP","I56": #LOCATION = "C3" !CDS_LOCATION = "C3" &SEC = "1" #&CDS_SEC = "1";
"A":   PN = "1"  !CDS_PN = "1";
"B":   PN = "2"  !CDS_PN = "2";
BODY = "Q_CAP","I59": #LOCATION = "C2" !CDS_LOCATION = "C2" &SEC = "1" #&CDS_SEC = "1";
"A":   PN = "1"  !CDS_PN = "1";
"B":   PN = "2"  !CDS_PN = "2";
BODY = "Q_RES","I62": #LOCATION = "R201" !CDS_LOCATION = "R201" &SEC = "1" #&CDS_SEC = "1";
"A":   PN = "1"  !CDS_PN = "1";
"B":   PN = "2"  !CDS_PN = "2";
BODY = "Q_RES","I67": #LOCATION = "R202" !CDS_LOCATION = "R202" &SEC = "1" #&CDS_SEC = "1";
"A":   PN = "1"  !CDS_PN = "1";
"B":   PN = "2"  !CDS_PN = "2";
BODY = "Q_RES","I68": #LOCATION = "R206" !CDS_LOCATION = "R206" &SEC = "1" #&CDS_SEC = "1";
"A":   PN = "1"  !CDS_PN = "1";
"B":   PN = "2"  !CDS_PN = "2";
BODY = "Q_RES","I71": #LOCATION = "R274" !CDS_LOCATION = "R274" &SEC = "1" #&CDS_SEC = "1";
"A":   PN = "1"  !CDS_PN = "1";
"B":   PN = "2"  !CDS_PN = "2";
BODY = "Q_RES","I72": #LOCATION = "R281" !CDS_LOCATION = "R281" &SEC = "1" #&CDS_SEC = "1";
"A":   PN = "1"  !CDS_PN = "1";
"B":   PN = "2"  !CDS_PN = "2";
BODY = "Q_RES","I73": #LOCATION = "R322" !CDS_LOCATION = "R322" &SEC = "1" #&CDS_SEC = "1";
"A":   PN = "1"  !CDS_PN = "1";
"B":   PN = "2"  !CDS_PN = "2";
BODY = "Q_RES","I78": #LOCATION = "R290" !CDS_LOCATION = "R290" &SEC = "1" #&CDS_SEC = "1";
"A":   PN = "1"  !CDS_PN = "1";
"B":   PN = "2"  !CDS_PN = "2";
BODY = "Q_RES","I79": #LOCATION = "R151" !CDS_LOCATION = "R151" &SEC = "1" #&CDS_SEC = "1";
"A":   PN = "1"  !CDS_PN = "1";
"B":   PN = "2"  !CDS_PN = "2";
BODY = "Q_RES","I80": #LOCATION = "R162" !CDS_LOCATION = "R162" &SEC = "1" #&CDS_SEC = "1";
"A":   PN = "1"  !CDS_PN = "1";
"B":   PN = "2"  !CDS_PN = "2";
BODY = "Q_RES","I91": #LOCATION = "R257" !CDS_LOCATION = "R257" &SEC = "1" #&CDS_SEC = "1";
"A":   PN = "1"  !CDS_PN = "1";
"B":   PN = "2"  !CDS_PN = "2";
BODY = "Q_RES","I92": #LOCATION = "R256" !CDS_LOCATION = "R256" &SEC = "1" #&CDS_SEC = "1";
"A":   PN = "1"  !CDS_PN = "1";
"B":   PN = "2"  !CDS_PN = "2";
BODY = "Q_RES","I93": #LOCATION = "R1151" !CDS_LOCATION = "R1151" &SEC = "1" #&CDS_SEC = "1";
"A":   PN = "1"  !CDS_PN = "1";
"B":   PN = "2"  !CDS_PN = "2";
BODY = "Q_RES","I94": #LOCATION = "R1152" !CDS_LOCATION = "R1152" &SEC = "1" #&CDS_SEC = "1";
"A":   PN = "1"  !CDS_PN = "1";
"B":   PN = "2"  !CDS_PN = "2";
BODY = "Q_RES","I95": #LOCATION = "R790" !CDS_LOCATION = "R790" &SEC = "1" #&CDS_SEC = "1";
"A":   PN = "1"  !CDS_PN = "1";
"B":   PN = "2"  !CDS_PN = "2";
BODY = "Q_RES","I96": #LOCATION = "R789" !CDS_LOCATION = "R789" &SEC = "1" #&CDS_SEC = "1";
"A":   PN = "1"  !CDS_PN = "1";
"B":   PN = "2"  !CDS_PN = "2";
BODY = "Q_RES","I97": #LOCATION = "R150" !CDS_LOCATION = "R150" &SEC = "1" #&CDS_SEC = "1";
"A":   PN = "1"  !CDS_PN = "1";
"B":   PN = "2"  !CDS_PN = "2";
BODY = "Q_RES","I98": #LOCATION = "R140" !CDS_LOCATION = "R140" &SEC = "1" #&CDS_SEC = "1";
"A":   PN = "1"  !CDS_PN = "1";
"B":   PN = "2"  !CDS_PN = "2";
BODY = "PCA9617ADP","I99": #LOCATION = "U2" !CDS_LOCATION = "U2" #SEC = "1" !CDS_SEC = "1";
"EN":   PN = "5"  !CDS_PN = "5";
"GND":   PN = "4"  !CDS_PN = "4";
"SCLA":   PN = "2"  !CDS_PN = "2";
"SCLB":   PN = "7"  !CDS_PN = "7";
"SDAA":   PN = "3"  !CDS_PN = "3";
"SDAB":   PN = "6"  !CDS_PN = "6";
"VCCA":   PN = "1"  !CDS_PN = "1";
"VCCB":   PN = "8"  !CDS_PN = "8";
DRAWING = "@t6g_mb_lib.t6g(sch_1):page251";
BODY = "Q_RES","I1": #LOCATION = "R3704" !CDS_LOCATION = "R3704" &SEC = "1" #&CDS_SEC = "1";
"A":   PN = "1"  !CDS_PN = "1";
"B":   PN = "2"  !CDS_PN = "2";
BODY = "Q_RES","I4": #LOCATION = "R3707" !CDS_LOCATION = "R3707" &SEC = "1" #&CDS_SEC = "1";
"A":   PN = "1"  !CDS_PN = "1";
"B":   PN = "2"  !CDS_PN = "2";
BODY = "Q_RES","I6": #LOCATION = "R3709" !CDS_LOCATION = "R3709" &SEC = "1" #&CDS_SEC = "1";
"A":   PN = "1"  !CDS_PN = "1";
"B":   PN = "2"  !CDS_PN = "2";
BODY = "Q_RES","I7": #LOCATION = "R3703" !CDS_LOCATION = "R3703" &SEC = "1" #&CDS_SEC = "1";
"A":   PN = "1"  !CDS_PN = "1";
"B":   PN = "2"  !CDS_PN = "2";
BODY = "Q_RES","I8": #LOCATION = "R3706" !CDS_LOCATION = "R3706" &SEC = "1" #&CDS_SEC = "1";
"A":   PN = "1"  !CDS_PN = "1";
"B":   PN = "2"  !CDS_PN = "2";
BODY = "Q_RES","I10": #LOCATION = "R3708" !CDS_LOCATION = "R3708" &SEC = "1" #&CDS_SEC = "1";
"A":   PN = "1"  !CDS_PN = "1";
"B":   PN = "2"  !CDS_PN = "2";
BODY = "Q_RES","I18": #LOCATION = "R3719" !CDS_LOCATION = "R3719" &SEC = "1" #&CDS_SEC = "1";
"A":   PN = "1"  !CDS_PN = "1";
"B":   PN = "2"  !CDS_PN = "2";
BODY = "Q_RES","I19": #LOCATION = "R3720" !CDS_LOCATION = "R3720" &SEC = "1" #&CDS_SEC = "1";
"A":   PN = "1"  !CDS_PN = "1";
"B":   PN = "2"  !CDS_PN = "2";
BODY = "Q_RES","I20": #LOCATION = "R3717" !CDS_LOCATION = "R3717" &SEC = "1" #&CDS_SEC = "1";
"A":   PN = "1"  !CDS_PN = "1";
"B":   PN = "2"  !CDS_PN = "2";
BODY = "Q_RES","I21": #LOCATION = "R3718" !CDS_LOCATION = "R3718" &SEC = "1" #&CDS_SEC = "1";
"A":   PN = "1"  !CDS_PN = "1";
"B":   PN = "2"  !CDS_PN = "2";
BODY = "Q_RES","I27": #LOCATION = "R3705" !CDS_LOCATION = "R3705" &SEC = "1" #&CDS_SEC = "1";
"A":   PN = "1"  !CDS_PN = "1";
"B":   PN = "2"  !CDS_PN = "2";
BODY = "Q_RES","I29": #LOCATION = "R3710" !CDS_LOCATION = "R3710" &SEC = "1" #&CDS_SEC = "1";
"A":   PN = "1"  !CDS_PN = "1";
"B":   PN = "2"  !CDS_PN = "2";
BODY = "Q_RES","I30": #LOCATION = "R3716" !CDS_LOCATION = "R3716" &SEC = "1" #&CDS_SEC = "1";
"A":   PN = "1"  !CDS_PN = "1";
"B":   PN = "2"  !CDS_PN = "2";
BODY = "Q_RES","I31": #LOCATION = "R3715" !CDS_LOCATION = "R3715" &SEC = "1" #&CDS_SEC = "1";
"A":   PN = "1"  !CDS_PN = "1";
"B":   PN = "2"  !CDS_PN = "2";
BODY = "Q_RES","I32": #LOCATION = "R3714" !CDS_LOCATION = "R3714" &SEC = "1" #&CDS_SEC = "1";
"A":   PN = "1"  !CDS_PN = "1";
"B":   PN = "2"  !CDS_PN = "2";
BODY = "Q_RES","I33": #LOCATION = "R3713" !CDS_LOCATION = "R3713" &SEC = "1" #&CDS_SEC = "1";
"A":   PN = "1"  !CDS_PN = "1";
"B":   PN = "2"  !CDS_PN = "2";
BODY = "Q_CAP","I38": #LOCATION = "C2056" !CDS_LOCATION = "C2056" &SEC = "1" #&CDS_SEC = "1";
"A":   PN = "1"  !CDS_PN = "1";
"B":   PN = "2"  !CDS_PN = "2";
BODY = "Q_RES","I40": #LOCATION = "R4270" !CDS_LOCATION = "R4270" &SEC = "1" #&CDS_SEC = "1";
"A":   PN = "1"  !CDS_PN = "1";
"B":   PN = "2"  !CDS_PN = "2";
BODY = "Q_RES","I41": #LOCATION = "R4269" !CDS_LOCATION = "R4269" &SEC = "1" #&CDS_SEC = "1";
"A":   PN = "1"  !CDS_PN = "1";
"B":   PN = "2"  !CDS_PN = "2";
BODY = "Q_RES","I42": #LOCATION = "R3732" !CDS_LOCATION = "R3732" &SEC = "1" #&CDS_SEC = "1";
"A":   PN = "1"  !CDS_PN = "1";
"B":   PN = "2"  !CDS_PN = "2";
BODY = "Q_RES","I43": #LOCATION = "R3731" !CDS_LOCATION = "R3731" &SEC = "1" #&CDS_SEC = "1";
"A":   PN = "1"  !CDS_PN = "1";
"B":   PN = "2"  !CDS_PN = "2";
BODY = "Q_RES","I44": #LOCATION = "R3729" !CDS_LOCATION = "R3729" &SEC = "1" #&CDS_SEC = "1";
"A":   PN = "1"  !CDS_PN = "1";
"B":   PN = "2"  !CDS_PN = "2";
BODY = "Q_RES","I45": #LOCATION = "R3730" !CDS_LOCATION = "R3730" &SEC = "1" #&CDS_SEC = "1";
"A":   PN = "1"  !CDS_PN = "1";
"B":   PN = "2"  !CDS_PN = "2";
BODY = "Q_RES","I47": #LOCATION = "R3728" !CDS_LOCATION = "R3728" &SEC = "1" #&CDS_SEC = "1";
"A":   PN = "1"  !CDS_PN = "1";
"B":   PN = "2"  !CDS_PN = "2";
BODY = "Q_RES","I48": #LOCATION = "R3727" !CDS_LOCATION = "R3727" &SEC = "1" #&CDS_SEC = "1";
"A":   PN = "1"  !CDS_PN = "1";
"B":   PN = "2"  !CDS_PN = "2";
BODY = "Q_RES","I49": #LOCATION = "R3726" !CDS_LOCATION = "R3726" &SEC = "1" #&CDS_SEC = "1";
"A":   PN = "1"  !CDS_PN = "1";
"B":   PN = "2"  !CDS_PN = "2";
BODY = "Q_RES","I50": #LOCATION = "R3725" !CDS_LOCATION = "R3725" &SEC = "1" #&CDS_SEC = "1";
"A":   PN = "1"  !CDS_PN = "1";
"B":   PN = "2"  !CDS_PN = "2";
BODY = "Q_RES","I52": #LOCATION = "R3724" !CDS_LOCATION = "R3724" &SEC = "1" #&CDS_SEC = "1";
"A":   PN = "1"  !CDS_PN = "1";
"B":   PN = "2"  !CDS_PN = "2";
BODY = "Q_RES","I53": #LOCATION = "R3723" !CDS_LOCATION = "R3723" &SEC = "1" #&CDS_SEC = "1";
"A":   PN = "1"  !CDS_PN = "1";
"B":   PN = "2"  !CDS_PN = "2";
BODY = "Q_RES","I66": #LOCATION = "R3722" !CDS_LOCATION = "R3722" &SEC = "1" #&CDS_SEC = "1";
"A":   PN = "1"  !CDS_PN = "1";
"B":   PN = "2"  !CDS_PN = "2";
BODY = "Q_RES","I67": #LOCATION = "R3721" !CDS_LOCATION = "R3721" &SEC = "1" #&CDS_SEC = "1";
"A":   PN = "1"  !CDS_PN = "1";
"B":   PN = "2"  !CDS_PN = "2";
BODY = "Q_RES","I68": #LOCATION = "R3712" !CDS_LOCATION = "R3712" &SEC = "1" #&CDS_SEC = "1";
"A":   PN = "1"  !CDS_PN = "1";
"B":   PN = "2"  !CDS_PN = "2";
BODY = "Q_RES","I69": #LOCATION = "R3711" !CDS_LOCATION = "R3711" &SEC = "1" #&CDS_SEC = "1";
"A":   PN = "1"  !CDS_PN = "1";
"B":   PN = "2"  !CDS_PN = "2";
BODY = "TCA9548APWR","I74": #LOCATION = "U39" !CDS_LOCATION = "U39" #SEC = "1" !CDS_SEC = "1";
"A0":   PN = "1"  !CDS_PN = "1";
"A1":   PN = "2"  !CDS_PN = "2";
"A2":   PN = "21"  !CDS_PN = "21";
"GND":   PN = "12"  !CDS_PN = "12";
"RESET#":   PN = "3"  !CDS_PN = "3";
"SC0":   PN = "5"  !CDS_PN = "5";
"SC1":   PN = "7"  !CDS_PN = "7";
"SC2":   PN = "9"  !CDS_PN = "9";
"SC3":   PN = "11"  !CDS_PN = "11";
"SC4":   PN = "14"  !CDS_PN = "14";
"SC5":   PN = "16"  !CDS_PN = "16";
"SC6":   PN = "18"  !CDS_PN = "18";
"SC7":   PN = "20"  !CDS_PN = "20";
"SCL":   PN = "22"  !CDS_PN = "22";
"SD0":   PN = "4"  !CDS_PN = "4";
"SD1":   PN = "6"  !CDS_PN = "6";
"SD2":   PN = "8"  !CDS_PN = "8";
"SD3":   PN = "10"  !CDS_PN = "10";
"SD4":   PN = "13"  !CDS_PN = "13";
"SD5":   PN = "15"  !CDS_PN = "15";
"SD6":   PN = "17"  !CDS_PN = "17";
"SD7":   PN = "19"  !CDS_PN = "19";
"SDA":   PN = "23"  !CDS_PN = "23";
"VCC":   PN = "24"  !CDS_PN = "24";
BODY = "Q_RES","I75": #LOCATION = "R6228" !CDS_LOCATION = "R6228" &SEC = "1" #&CDS_SEC = "1";
"A":   PN = "1"  !CDS_PN = "1";
"B":   PN = "2"  !CDS_PN = "2";
BODY = "Q_RES","I76": #LOCATION = "R6229" !CDS_LOCATION = "R6229" &SEC = "1" #&CDS_SEC = "1";
"A":   PN = "1"  !CDS_PN = "1";
"B":   PN = "2"  !CDS_PN = "2";
BODY = "Q_RES","I79": #LOCATION = "R1312" !CDS_LOCATION = "R1312" &SEC = "1" #&CDS_SEC = "1";
"A":   PN = "1"  !CDS_PN = "1";
"B":   PN = "2"  !CDS_PN = "2";
BODY = "Q_RES","I80": #LOCATION = "R1315" !CDS_LOCATION = "R1315" &SEC = "1" #&CDS_SEC = "1";
"A":   PN = "1"  !CDS_PN = "1";
"B":   PN = "2"  !CDS_PN = "2";
BODY = "Q_RES","I83": #LOCATION = "R1316" !CDS_LOCATION = "R1316" &SEC = "1" #&CDS_SEC = "1";
"A":   PN = "1"  !CDS_PN = "1";
"B":   PN = "2"  !CDS_PN = "2";
BODY = "Q_RES","I84": #LOCATION = "R1341" !CDS_LOCATION = "R1341" &SEC = "1" #&CDS_SEC = "1";
"A":   PN = "1"  !CDS_PN = "1";
"B":   PN = "2"  !CDS_PN = "2";
DRAWING = "@t6g_mb_lib.t6g(sch_1):page252";
BODY = "Q_RES","I2": #LOCATION = "R317" !CDS_LOCATION = "R317" &SEC = "1" #&CDS_SEC = "1";
"A":   PN = "1"  !CDS_PN = "1";
"B":   PN = "2"  !CDS_PN = "2";
BODY = "Q_RES","I4": #LOCATION = "R319" !CDS_LOCATION = "R319" &SEC = "1" #&CDS_SEC = "1";
"A":   PN = "1"  !CDS_PN = "1";
"B":   PN = "2"  !CDS_PN = "2";
BODY = "Q_RES","I6": #LOCATION = "R587" !CDS_LOCATION = "R587" &SEC = "1" #&CDS_SEC = "1";
"A":   PN = "1"  !CDS_PN = "1";
"B":   PN = "2"  !CDS_PN = "2";
BODY = "Q_RES","I7": #LOCATION = "R316" !CDS_LOCATION = "R316" &SEC = "1" #&CDS_SEC = "1";
"A":   PN = "1"  !CDS_PN = "1";
"B":   PN = "2"  !CDS_PN = "2";
BODY = "Q_RES","I8": #LOCATION = "R318" !CDS_LOCATION = "R318" &SEC = "1" #&CDS_SEC = "1";
"A":   PN = "1"  !CDS_PN = "1";
"B":   PN = "2"  !CDS_PN = "2";
BODY = "Q_RES","I10": #LOCATION = "R320" !CDS_LOCATION = "R320" &SEC = "1" #&CDS_SEC = "1";
"A":   PN = "1"  !CDS_PN = "1";
"B":   PN = "2"  !CDS_PN = "2";
BODY = "Q_RES","I21": #LOCATION = "R1822" !CDS_LOCATION = "R1822" &SEC = "1" #&CDS_SEC = "1";
"A":   PN = "1"  !CDS_PN = "1";
"B":   PN = "2"  !CDS_PN = "2";
BODY = "Q_RES","I23": #LOCATION = "R3526" !CDS_LOCATION = "R3526" &SEC = "1" #&CDS_SEC = "1";
"A":   PN = "1"  !CDS_PN = "1";
"B":   PN = "2"  !CDS_PN = "2";
BODY = "Q_RES","I24": #LOCATION = "R3527" !CDS_LOCATION = "R3527" &SEC = "1" #&CDS_SEC = "1";
"A":   PN = "1"  !CDS_PN = "1";
"B":   PN = "2"  !CDS_PN = "2";
BODY = "Q_RES","I25": #LOCATION = "R2967" !CDS_LOCATION = "R2967" &SEC = "1" #&CDS_SEC = "1";
"A":   PN = "1"  !CDS_PN = "1";
"B":   PN = "2"  !CDS_PN = "2";
BODY = "Q_RES","I26": #LOCATION = "R2968" !CDS_LOCATION = "R2968" &SEC = "1" #&CDS_SEC = "1";
"A":   PN = "1"  !CDS_PN = "1";
"B":   PN = "2"  !CDS_PN = "2";
BODY = "Q_RES","I27": #LOCATION = "R3393" !CDS_LOCATION = "R3393" #SEC = "1" !CDS_SEC = "1";
"A":   PN = "1"  !CDS_PN = "1";
"B":   PN = "2"  !CDS_PN = "2";
BODY = "Q_RES","I28": #LOCATION = "R2268" !CDS_LOCATION = "R2268" &SEC = "1" #&CDS_SEC = "1";
"A":   PN = "1"  !CDS_PN = "1";
"B":   PN = "2"  !CDS_PN = "2";
BODY = "Q_RES","I29": #LOCATION = "R3394" !CDS_LOCATION = "R3394" &SEC = "1" #&CDS_SEC = "1";
"A":   PN = "1"  !CDS_PN = "1";
"B":   PN = "2"  !CDS_PN = "2";
BODY = "TCA9548APWR","I33": #LOCATION = "U36" !CDS_LOCATION = "U36" #SEC = "1" !CDS_SEC = "1";
"A0":   PN = "1"  !CDS_PN = "1";
"A1":   PN = "2"  !CDS_PN = "2";
"A2":   PN = "21"  !CDS_PN = "21";
"GND":   PN = "12"  !CDS_PN = "12";
"RESET#":   PN = "3"  !CDS_PN = "3";
"SC0":   PN = "5"  !CDS_PN = "5";
"SC1":   PN = "7"  !CDS_PN = "7";
"SC2":   PN = "9"  !CDS_PN = "9";
"SC3":   PN = "11"  !CDS_PN = "11";
"SC4":   PN = "14"  !CDS_PN = "14";
"SC5":   PN = "16"  !CDS_PN = "16";
"SC6":   PN = "18"  !CDS_PN = "18";
"SC7":   PN = "20"  !CDS_PN = "20";
"SCL":   PN = "22"  !CDS_PN = "22";
"SD0":   PN = "4"  !CDS_PN = "4";
"SD1":   PN = "6"  !CDS_PN = "6";
"SD2":   PN = "8"  !CDS_PN = "8";
"SD3":   PN = "10"  !CDS_PN = "10";
"SD4":   PN = "13"  !CDS_PN = "13";
"SD5":   PN = "15"  !CDS_PN = "15";
"SD6":   PN = "17"  !CDS_PN = "17";
"SD7":   PN = "19"  !CDS_PN = "19";
"SDA":   PN = "23"  !CDS_PN = "23";
"VCC":   PN = "24"  !CDS_PN = "24";
BODY = "Q_CAP","I34": #LOCATION = "C106" !CDS_LOCATION = "C106" &SEC = "1" #&CDS_SEC = "1";
"A":   PN = "1"  !CDS_PN = "1";
"B":   PN = "2"  !CDS_PN = "2";
BODY = "Q_RES","I37": #LOCATION = "R1089" !CDS_LOCATION = "R1089" &SEC = "1" #&CDS_SEC = "1";
"A":   PN = "1"  !CDS_PN = "1";
"B":   PN = "2"  !CDS_PN = "2";
BODY = "Q_RES","I38": #LOCATION = "R1090" !CDS_LOCATION = "R1090" &SEC = "1" #&CDS_SEC = "1";
"A":   PN = "1"  !CDS_PN = "1";
"B":   PN = "2"  !CDS_PN = "2";
BODY = "Q_RES","I39": #LOCATION = "R67" !CDS_LOCATION = "R67" &SEC = "1" #&CDS_SEC = "1";
"A":   PN = "1"  !CDS_PN = "1";
"B":   PN = "2"  !CDS_PN = "2";
BODY = "Q_RES","I40": #LOCATION = "R66" !CDS_LOCATION = "R66" &SEC = "1" #&CDS_SEC = "1";
"A":   PN = "1"  !CDS_PN = "1";
"B":   PN = "2"  !CDS_PN = "2";
BODY = "Q_RES","I41": #LOCATION = "R2984" !CDS_LOCATION = "R2984" &SEC = "1" #&CDS_SEC = "1";
"A":   PN = "1"  !CDS_PN = "1";
"B":   PN = "2"  !CDS_PN = "2";
BODY = "Q_RES","I42": #LOCATION = "R2985" !CDS_LOCATION = "R2985" &SEC = "1" #&CDS_SEC = "1";
"A":   PN = "1"  !CDS_PN = "1";
"B":   PN = "2"  !CDS_PN = "2";
BODY = "Q_RES","I43": #LOCATION = "R3536" !CDS_LOCATION = "R3536" &SEC = "1" #&CDS_SEC = "1";
"A":   PN = "1"  !CDS_PN = "1";
"B":   PN = "2"  !CDS_PN = "2";
BODY = "Q_RES","I44": #LOCATION = "R3535" !CDS_LOCATION = "R3535" &SEC = "1" #&CDS_SEC = "1";
"A":   PN = "1"  !CDS_PN = "1";
"B":   PN = "2"  !CDS_PN = "2";
BODY = "Q_RES","I45": #LOCATION = "R3583" !CDS_LOCATION = "R3583" &SEC = "1" #&CDS_SEC = "1";
"A":   PN = "1"  !CDS_PN = "1";
"B":   PN = "2"  !CDS_PN = "2";
BODY = "Q_RES","I46": #LOCATION = "R3582" !CDS_LOCATION = "R3582" &SEC = "1" #&CDS_SEC = "1";
"A":   PN = "1"  !CDS_PN = "1";
"B":   PN = "2"  !CDS_PN = "2";
BODY = "Q_RES","I47": #LOCATION = "R3395" !CDS_LOCATION = "R3395" &SEC = "1" #&CDS_SEC = "1";
"A":   PN = "1"  !CDS_PN = "1";
"B":   PN = "2"  !CDS_PN = "2";
BODY = "Q_RES","I48": #LOCATION = "R3396" !CDS_LOCATION = "R3396" &SEC = "1" #&CDS_SEC = "1";
"A":   PN = "1"  !CDS_PN = "1";
"B":   PN = "2"  !CDS_PN = "2";
BODY = "Q_RES","I49": #LOCATION = "R2205" !CDS_LOCATION = "R2205" &SEC = "1" #&CDS_SEC = "1";
"A":   PN = "1"  !CDS_PN = "1";
"B":   PN = "2"  !CDS_PN = "2";
BODY = "Q_RES","I50": #LOCATION = "R2204" !CDS_LOCATION = "R2204" &SEC = "1" #&CDS_SEC = "1";
"A":   PN = "1"  !CDS_PN = "1";
"B":   PN = "2"  !CDS_PN = "2";
BODY = "Q_RES","I67": #LOCATION = "R2565" !CDS_LOCATION = "R2565" &SEC = "1" #&CDS_SEC = "1";
"A":   PN = "1"  !CDS_PN = "1";
"B":   PN = "2"  !CDS_PN = "2";
BODY = "Q_RES","I68": #LOCATION = "R3581" !CDS_LOCATION = "R3581" &SEC = "1" #&CDS_SEC = "1";
"A":   PN = "1"  !CDS_PN = "1";
"B":   PN = "2"  !CDS_PN = "2";
BODY = "Q_RES","I69": #LOCATION = "R3580" !CDS_LOCATION = "R3580" &SEC = "1" #&CDS_SEC = "1";
"A":   PN = "1"  !CDS_PN = "1";
"B":   PN = "2"  !CDS_PN = "2";
BODY = "Q_RES","I70": #LOCATION = "R2704" !CDS_LOCATION = "R2704" &SEC = "1" #&CDS_SEC = "1";
"A":   PN = "1"  !CDS_PN = "1";
"B":   PN = "2"  !CDS_PN = "2";
BODY = "Q_RES","I71": #LOCATION = "R2703" !CDS_LOCATION = "R2703" &SEC = "1" #&CDS_SEC = "1";
"A":   PN = "1"  !CDS_PN = "1";
"B":   PN = "2"  !CDS_PN = "2";
BODY = "Q_RES","I72": #LOCATION = "R2566" !CDS_LOCATION = "R2566" &SEC = "1" #&CDS_SEC = "1";
"A":   PN = "1"  !CDS_PN = "1";
"B":   PN = "2"  !CDS_PN = "2";
BODY = "Q_RES","I73": #LOCATION = "R55" !CDS_LOCATION = "R55" &SEC = "1" #&CDS_SEC = "1";
"A":   PN = "1"  !CDS_PN = "1";
"B":   PN = "2"  !CDS_PN = "2";
BODY = "Q_RES","I74": #LOCATION = "R65" !CDS_LOCATION = "R65" &SEC = "1" #&CDS_SEC = "1";
"A":   PN = "1"  !CDS_PN = "1";
"B":   PN = "2"  !CDS_PN = "2";
BODY = "Q_RES","I83": #LOCATION = "R6200" !CDS_LOCATION = "R6200" &SEC = "1" #&CDS_SEC = "1";
"A":   PN = "1"  !CDS_PN = "1";
"B":   PN = "2"  !CDS_PN = "2";
BODY = "Q_RES","I84": #LOCATION = "R6201" !CDS_LOCATION = "R6201" &SEC = "1" #&CDS_SEC = "1";
"A":   PN = "1"  !CDS_PN = "1";
"B":   PN = "2"  !CDS_PN = "2";
BODY = "Q_RES","I89": #LOCATION = "R6211" !CDS_LOCATION = "R6211" &SEC = "1" #&CDS_SEC = "1";
"A":   PN = "1"  !CDS_PN = "1";
"B":   PN = "2"  !CDS_PN = "2";
BODY = "Q_RES","I90": #LOCATION = "R6212" !CDS_LOCATION = "R6212" &SEC = "1" #&CDS_SEC = "1";
"A":   PN = "1"  !CDS_PN = "1";
"B":   PN = "2"  !CDS_PN = "2";
DRAWING = "@t6g_mb_lib.t6g(sch_1):page253";
BODY = "Q_RES","I3": #LOCATION = "R3593" !CDS_LOCATION = "R3593" &SEC = "1" #&CDS_SEC = "1";
"A":   PN = "1"  !CDS_PN = "1";
"B":   PN = "2"  !CDS_PN = "2";
BODY = "Q_RES","I4": #LOCATION = "R3592" !CDS_LOCATION = "R3592" &SEC = "1" #&CDS_SEC = "1";
"A":   PN = "1"  !CDS_PN = "1";
"B":   PN = "2"  !CDS_PN = "2";
BODY = "Q_RES","I5": #LOCATION = "R3595" !CDS_LOCATION = "R3595" &SEC = "1" #&CDS_SEC = "1";
"A":   PN = "1"  !CDS_PN = "1";
"B":   PN = "2"  !CDS_PN = "2";
BODY = "Q_RES","I6": #LOCATION = "R3594" !CDS_LOCATION = "R3594" &SEC = "1" #&CDS_SEC = "1";
"A":   PN = "1"  !CDS_PN = "1";
"B":   PN = "2"  !CDS_PN = "2";
BODY = "Q_RES","I7": #LOCATION = "R3591" !CDS_LOCATION = "R3591" &SEC = "1" #&CDS_SEC = "1";
"A":   PN = "1"  !CDS_PN = "1";
"B":   PN = "2"  !CDS_PN = "2";
BODY = "Q_RES","I8": #LOCATION = "R3590" !CDS_LOCATION = "R3590" &SEC = "1" #&CDS_SEC = "1";
"A":   PN = "1"  !CDS_PN = "1";
"B":   PN = "2"  !CDS_PN = "2";
BODY = "Q_RES","I9": #LOCATION = "R3589" !CDS_LOCATION = "R3589" &SEC = "1" #&CDS_SEC = "1";
"A":   PN = "1"  !CDS_PN = "1";
"B":   PN = "2"  !CDS_PN = "2";
BODY = "Q_RES","I10": #LOCATION = "R3588" !CDS_LOCATION = "R3588" &SEC = "1" #&CDS_SEC = "1";
"A":   PN = "1"  !CDS_PN = "1";
"B":   PN = "2"  !CDS_PN = "2";
BODY = "Q_RES","I11": #LOCATION = "R3587" !CDS_LOCATION = "R3587" &SEC = "1" #&CDS_SEC = "1";
"A":   PN = "1"  !CDS_PN = "1";
"B":   PN = "2"  !CDS_PN = "2";
BODY = "Q_RES","I12": #LOCATION = "R3586" !CDS_LOCATION = "R3586" &SEC = "1" #&CDS_SEC = "1";
"A":   PN = "1"  !CDS_PN = "1";
"B":   PN = "2"  !CDS_PN = "2";
BODY = "Q_RES","I23": #LOCATION = "R1344" !CDS_LOCATION = "R1344" &SEC = "1" #&CDS_SEC = "1";
"A":   PN = "1"  !CDS_PN = "1";
"B":   PN = "2"  !CDS_PN = "2";
BODY = "Q_RES","I24": #LOCATION = "R1345" !CDS_LOCATION = "R1345" &SEC = "1" #&CDS_SEC = "1";
"A":   PN = "1"  !CDS_PN = "1";
"B":   PN = "2"  !CDS_PN = "2";
BODY = "Q_RES","I25": #LOCATION = "R1346" !CDS_LOCATION = "R1346" &SEC = "1" #&CDS_SEC = "1";
"A":   PN = "1"  !CDS_PN = "1";
"B":   PN = "2"  !CDS_PN = "2";
BODY = "Q_RES","I26": #LOCATION = "R1347" !CDS_LOCATION = "R1347" &SEC = "1" #&CDS_SEC = "1";
"A":   PN = "1"  !CDS_PN = "1";
"B":   PN = "2"  !CDS_PN = "2";
BODY = "Q_RES","I27": #LOCATION = "R1348" !CDS_LOCATION = "R1348" &SEC = "1" #&CDS_SEC = "1";
"A":   PN = "1"  !CDS_PN = "1";
"B":   PN = "2"  !CDS_PN = "2";
BODY = "Q_RES","I28": #LOCATION = "R1349" !CDS_LOCATION = "R1349" &SEC = "1" #&CDS_SEC = "1";
"A":   PN = "1"  !CDS_PN = "1";
"B":   PN = "2"  !CDS_PN = "2";
DRAWING = "@t6g_mb_lib.t6g(sch_1):page355";
BODY = "Q_CAP_DIFFBUS","I7": #LOCATION = "C1990" !CDS_LOCATION = "C1990" &SEC = "1" #&CDS_SEC = "1";
"1":   PN = "1"  !CDS_PN = "1";
"2":   PN = "2"  !CDS_PN = "2";
BODY = "Q_CAP_DIFFBUS","I8": #LOCATION = "C1989" !CDS_LOCATION = "C1989" &SEC = "1" #&CDS_SEC = "1";
"1":   PN = "1"  !CDS_PN = "1";
"2":   PN = "2"  !CDS_PN = "2";
BODY = "Q_CAP_DIFFBUS","I9": #LOCATION = "C1992" !CDS_LOCATION = "C1992" &SEC = "1" #&CDS_SEC = "1";
"1":   PN = "1"  !CDS_PN = "1";
"2":   PN = "2"  !CDS_PN = "2";
BODY = "Q_CAP_DIFFBUS","I10": #LOCATION = "C1991" !CDS_LOCATION = "C1991" &SEC = "1" #&CDS_SEC = "1";
"1":   PN = "1"  !CDS_PN = "1";
"2":   PN = "2"  !CDS_PN = "2";
BODY = "Q_CAP_DIFFBUS","I11": #LOCATION = "C1994" !CDS_LOCATION = "C1994" &SEC = "1" #&CDS_SEC = "1";
"1":   PN = "1"  !CDS_PN = "1";
"2":   PN = "2"  !CDS_PN = "2";
BODY = "Q_CAP_DIFFBUS","I12": #LOCATION = "C1993" !CDS_LOCATION = "C1993" &SEC = "1" #&CDS_SEC = "1";
"1":   PN = "1"  !CDS_PN = "1";
"2":   PN = "2"  !CDS_PN = "2";
BODY = "Q_CAP_DIFFBUS","I51": #LOCATION = "C1996" !CDS_LOCATION = "C1996" &SEC = "1" #&CDS_SEC = "1";
"1":   PN = "1"  !CDS_PN = "1";
"2":   PN = "2"  !CDS_PN = "2";
BODY = "Q_CAP_DIFFBUS","I52": #LOCATION = "C1995" !CDS_LOCATION = "C1995" &SEC = "1" #&CDS_SEC = "1";
"1":   PN = "1"  !CDS_PN = "1";
"2":   PN = "2"  !CDS_PN = "2";
BODY = "Q_CAP_DIFFBUS","I53": #LOCATION = "C1547" !CDS_LOCATION = "C1547" &SEC = "1" #&CDS_SEC = "1";
"1":   PN = "1"  !CDS_PN = "1";
"2":   PN = "2"  !CDS_PN = "2";
BODY = "Q_CAP_DIFFBUS","I54": #LOCATION = "C1546" !CDS_LOCATION = "C1546" &SEC = "1" #&CDS_SEC = "1";
"1":   PN = "1"  !CDS_PN = "1";
"2":   PN = "2"  !CDS_PN = "2";
BODY = "Q_CAP_DIFFBUS","I55": #LOCATION = "C1544" !CDS_LOCATION = "C1544" &SEC = "1" #&CDS_SEC = "1";
"1":   PN = "1"  !CDS_PN = "1";
"2":   PN = "2"  !CDS_PN = "2";
BODY = "Q_CAP_DIFFBUS","I56": #LOCATION = "C1545" !CDS_LOCATION = "C1545" &SEC = "1" #&CDS_SEC = "1";
"1":   PN = "1"  !CDS_PN = "1";
"2":   PN = "2"  !CDS_PN = "2";
BODY = "Q_CAP_DIFFBUS","I57": #LOCATION = "C1543" !CDS_LOCATION = "C1543" &SEC = "1" #&CDS_SEC = "1";
"1":   PN = "1"  !CDS_PN = "1";
"2":   PN = "2"  !CDS_PN = "2";
BODY = "Q_CAP_DIFFBUS","I58": #LOCATION = "C1542" !CDS_LOCATION = "C1542" &SEC = "1" #&CDS_SEC = "1";
"1":   PN = "1"  !CDS_PN = "1";
"2":   PN = "2"  !CDS_PN = "2";
BODY = "Q_CAP_DIFFBUS","I67": #LOCATION = "C1541" !CDS_LOCATION = "C1541" &SEC = "1" #&CDS_SEC = "1";
"1":   PN = "1"  !CDS_PN = "1";
"2":   PN = "2"  !CDS_PN = "2";
BODY = "Q_CAP_DIFFBUS","I68": #LOCATION = "C1540" !CDS_LOCATION = "C1540" &SEC = "1" #&CDS_SEC = "1";
"1":   PN = "1"  !CDS_PN = "1";
"2":   PN = "2"  !CDS_PN = "2";
BODY = "Q_CAP_DIFFBUS","I69": #LOCATION = "C1539" !CDS_LOCATION = "C1539" &SEC = "1" #&CDS_SEC = "1";
"1":   PN = "1"  !CDS_PN = "1";
"2":   PN = "2"  !CDS_PN = "2";
BODY = "Q_CAP_DIFFBUS","I70": #LOCATION = "C1538" !CDS_LOCATION = "C1538" &SEC = "1" #&CDS_SEC = "1";
"1":   PN = "1"  !CDS_PN = "1";
"2":   PN = "2"  !CDS_PN = "2";
BODY = "Q_CAP_DIFFBUS","I71": #LOCATION = "C1537" !CDS_LOCATION = "C1537" &SEC = "1" #&CDS_SEC = "1";
"1":   PN = "1"  !CDS_PN = "1";
"2":   PN = "2"  !CDS_PN = "2";
BODY = "Q_CAP_DIFFBUS","I72": #LOCATION = "C1536" !CDS_LOCATION = "C1536" &SEC = "1" #&CDS_SEC = "1";
"1":   PN = "1"  !CDS_PN = "1";
"2":   PN = "2"  !CDS_PN = "2";
BODY = "Q_CAP_DIFFBUS","I73": #LOCATION = "C1535" !CDS_LOCATION = "C1535" &SEC = "1" #&CDS_SEC = "1";
"1":   PN = "1"  !CDS_PN = "1";
"2":   PN = "2"  !CDS_PN = "2";
BODY = "Q_CAP_DIFFBUS","I74": #LOCATION = "C1534" !CDS_LOCATION = "C1534" &SEC = "1" #&CDS_SEC = "1";
"1":   PN = "1"  !CDS_PN = "1";
"2":   PN = "2"  !CDS_PN = "2";
BODY = "Q_CAP_DIFFBUS","I75": #LOCATION = "C1533" !CDS_LOCATION = "C1533" &SEC = "1" #&CDS_SEC = "1";
"1":   PN = "1"  !CDS_PN = "1";
"2":   PN = "2"  !CDS_PN = "2";
BODY = "Q_CAP_DIFFBUS","I76": #LOCATION = "C1532" !CDS_LOCATION = "C1532" &SEC = "1" #&CDS_SEC = "1";
"1":   PN = "1"  !CDS_PN = "1";
"2":   PN = "2"  !CDS_PN = "2";
BODY = "Q_CAP_DIFFBUS","I77": #LOCATION = "C1531" !CDS_LOCATION = "C1531" &SEC = "1" #&CDS_SEC = "1";
"1":   PN = "1"  !CDS_PN = "1";
"2":   PN = "2"  !CDS_PN = "2";
BODY = "Q_CAP_DIFFBUS","I78": #LOCATION = "C1530" !CDS_LOCATION = "C1530" &SEC = "1" #&CDS_SEC = "1";
"1":   PN = "1"  !CDS_PN = "1";
"2":   PN = "2"  !CDS_PN = "2";
BODY = "Q_CAP_DIFFBUS","I79": #LOCATION = "C1529" !CDS_LOCATION = "C1529" &SEC = "1" #&CDS_SEC = "1";
"1":   PN = "1"  !CDS_PN = "1";
"2":   PN = "2"  !CDS_PN = "2";
BODY = "Q_CAP_DIFFBUS","I80": #LOCATION = "C1528" !CDS_LOCATION = "C1528" &SEC = "1" #&CDS_SEC = "1";
"1":   PN = "1"  !CDS_PN = "1";
"2":   PN = "2"  !CDS_PN = "2";
BODY = "Q_CAP_DIFFBUS","I81": #LOCATION = "C1526" !CDS_LOCATION = "C1526" &SEC = "1" #&CDS_SEC = "1";
"1":   PN = "1"  !CDS_PN = "1";
"2":   PN = "2"  !CDS_PN = "2";
BODY = "Q_CAP_DIFFBUS","I82": #LOCATION = "C1527" !CDS_LOCATION = "C1527" &SEC = "1" #&CDS_SEC = "1";
"1":   PN = "1"  !CDS_PN = "1";
"2":   PN = "2"  !CDS_PN = "2";
BODY = "Q_CAP_DIFFBUS","I83": #LOCATION = "C1525" !CDS_LOCATION = "C1525" &SEC = "1" #&CDS_SEC = "1";
"1":   PN = "1"  !CDS_PN = "1";
"2":   PN = "2"  !CDS_PN = "2";
BODY = "Q_CAP_DIFFBUS","I84": #LOCATION = "C1524" !CDS_LOCATION = "C1524" &SEC = "1" #&CDS_SEC = "1";
"1":   PN = "1"  !CDS_PN = "1";
"2":   PN = "2"  !CDS_PN = "2";
BODY = "Q_CAP_DIFFBUS","I85": #LOCATION = "C55" !CDS_LOCATION = "C55" &SEC = "1" #&CDS_SEC = "1";
"1":   PN = "1"  !CDS_PN = "1";
"2":   PN = "2"  !CDS_PN = "2";
BODY = "Q_CAP_DIFFBUS","I86": #LOCATION = "C54" !CDS_LOCATION = "C54" &SEC = "1" #&CDS_SEC = "1";
"1":   PN = "1"  !CDS_PN = "1";
"2":   PN = "2"  !CDS_PN = "2";
BODY = "Q_CAP_DIFFBUS","I107": #LOCATION = "C53" !CDS_LOCATION = "C53" &SEC = "1" #&CDS_SEC = "1";
"1":   PN = "1"  !CDS_PN = "1";
"2":   PN = "2"  !CDS_PN = "2";
BODY = "Q_CAP_DIFFBUS","I116": #LOCATION = "C52" !CDS_LOCATION = "C52" &SEC = "1" #&CDS_SEC = "1";
"1":   PN = "1"  !CDS_PN = "1";
"2":   PN = "2"  !CDS_PN = "2";
BODY = "Q_CAP_DIFFBUS","I117": #LOCATION = "C51" !CDS_LOCATION = "C51" &SEC = "1" #&CDS_SEC = "1";
"1":   PN = "1"  !CDS_PN = "1";
"2":   PN = "2"  !CDS_PN = "2";
BODY = "Q_CAP_DIFFBUS","I118": #LOCATION = "C50" !CDS_LOCATION = "C50" &SEC = "1" #&CDS_SEC = "1";
"1":   PN = "1"  !CDS_PN = "1";
"2":   PN = "2"  !CDS_PN = "2";
BODY = "Q_CAP_DIFFBUS","I119": #LOCATION = "C48" !CDS_LOCATION = "C48" &SEC = "1" #&CDS_SEC = "1";
"1":   PN = "1"  !CDS_PN = "1";
"2":   PN = "2"  !CDS_PN = "2";
BODY = "Q_CAP_DIFFBUS","I120": #LOCATION = "C49" !CDS_LOCATION = "C49" &SEC = "1" #&CDS_SEC = "1";
"1":   PN = "1"  !CDS_PN = "1";
"2":   PN = "2"  !CDS_PN = "2";
BODY = "Q_CAP_DIFFBUS","I133": #LOCATION = "C1099" !CDS_LOCATION = "C1099" &SEC = "1" #&CDS_SEC = "1";
"1":   PN = "1"  !CDS_PN = "1";
"2":   PN = "2"  !CDS_PN = "2";
BODY = "Q_CAP_DIFFBUS","I134": #LOCATION = "C1098" !CDS_LOCATION = "C1098" &SEC = "1" #&CDS_SEC = "1";
"1":   PN = "1"  !CDS_PN = "1";
"2":   PN = "2"  !CDS_PN = "2";
BODY = "Q_CAP_DIFFBUS","I135": #LOCATION = "C1101" !CDS_LOCATION = "C1101" &SEC = "1" #&CDS_SEC = "1";
"1":   PN = "1"  !CDS_PN = "1";
"2":   PN = "2"  !CDS_PN = "2";
BODY = "Q_CAP_DIFFBUS","I136": #LOCATION = "C1100" !CDS_LOCATION = "C1100" &SEC = "1" #&CDS_SEC = "1";
"1":   PN = "1"  !CDS_PN = "1";
"2":   PN = "2"  !CDS_PN = "2";
BODY = "Q_CAP_DIFFBUS","I137": #LOCATION = "C9103" !CDS_LOCATION = "C9103" &SEC = "1" #&CDS_SEC = "1";
"1":   PN = "1"  !CDS_PN = "1";
"2":   PN = "2"  !CDS_PN = "2";
BODY = "Q_CAP_DIFFBUS","I138": #LOCATION = "C9102" !CDS_LOCATION = "C9102" &SEC = "1" #&CDS_SEC = "1";
"1":   PN = "1"  !CDS_PN = "1";
"2":   PN = "2"  !CDS_PN = "2";
BODY = "Q_CAP_DIFFBUS","I161": #LOCATION = "C9105" !CDS_LOCATION = "C9105" &SEC = "1" #&CDS_SEC = "1";
"1":   PN = "1"  !CDS_PN = "1";
"2":   PN = "2"  !CDS_PN = "2";
BODY = "Q_CAP_DIFFBUS","I162": #LOCATION = "C9104" !CDS_LOCATION = "C9104" &SEC = "1" #&CDS_SEC = "1";
"1":   PN = "1"  !CDS_PN = "1";
"2":   PN = "2"  !CDS_PN = "2";
BODY = "Q_CAP_DIFFBUS","I165": #LOCATION = "C709" !CDS_LOCATION = "C709" &SEC = "1" #&CDS_SEC = "1";
"1":   PN = "1"  !CDS_PN = "1";
"2":   PN = "2"  !CDS_PN = "2";
BODY = "Q_CAP_DIFFBUS","I166": #LOCATION = "C708" !CDS_LOCATION = "C708" &SEC = "1" #&CDS_SEC = "1";
"1":   PN = "1"  !CDS_PN = "1";
"2":   PN = "2"  !CDS_PN = "2";
BODY = "Q_CAP_DIFFBUS","I167": #LOCATION = "C706" !CDS_LOCATION = "C706" &SEC = "1" #&CDS_SEC = "1";
"1":   PN = "1"  !CDS_PN = "1";
"2":   PN = "2"  !CDS_PN = "2";
BODY = "Q_CAP_DIFFBUS","I168": #LOCATION = "C707" !CDS_LOCATION = "C707" &SEC = "1" #&CDS_SEC = "1";
"1":   PN = "1"  !CDS_PN = "1";
"2":   PN = "2"  !CDS_PN = "2";
BODY = "Q_CAP_DIFFBUS","I169": #LOCATION = "C705" !CDS_LOCATION = "C705" &SEC = "1" #&CDS_SEC = "1";
"1":   PN = "1"  !CDS_PN = "1";
"2":   PN = "2"  !CDS_PN = "2";
BODY = "Q_CAP_DIFFBUS","I170": #LOCATION = "C704" !CDS_LOCATION = "C704" &SEC = "1" #&CDS_SEC = "1";
"1":   PN = "1"  !CDS_PN = "1";
"2":   PN = "2"  !CDS_PN = "2";
BODY = "Q_CAP_DIFFBUS","I197": #LOCATION = "C702" !CDS_LOCATION = "C702" &SEC = "1" #&CDS_SEC = "1";
"1":   PN = "1"  !CDS_PN = "1";
"2":   PN = "2"  !CDS_PN = "2";
BODY = "Q_CAP_DIFFBUS","I198": #LOCATION = "C703" !CDS_LOCATION = "C703" &SEC = "1" #&CDS_SEC = "1";
"1":   PN = "1"  !CDS_PN = "1";
"2":   PN = "2"  !CDS_PN = "2";
BODY = "Q_CAP_DIFFBUS","I199": #LOCATION = "C701" !CDS_LOCATION = "C701" &SEC = "1" #&CDS_SEC = "1";
"1":   PN = "1"  !CDS_PN = "1";
"2":   PN = "2"  !CDS_PN = "2";
BODY = "Q_CAP_DIFFBUS","I200": #LOCATION = "C700" !CDS_LOCATION = "C700" &SEC = "1" #&CDS_SEC = "1";
"1":   PN = "1"  !CDS_PN = "1";
"2":   PN = "2"  !CDS_PN = "2";
BODY = "Q_CAP_DIFFBUS","I201": #LOCATION = "C698" !CDS_LOCATION = "C698" &SEC = "1" #&CDS_SEC = "1";
"1":   PN = "1"  !CDS_PN = "1";
"2":   PN = "2"  !CDS_PN = "2";
BODY = "Q_CAP_DIFFBUS","I202": #LOCATION = "C699" !CDS_LOCATION = "C699" &SEC = "1" #&CDS_SEC = "1";
"1":   PN = "1"  !CDS_PN = "1";
"2":   PN = "2"  !CDS_PN = "2";
BODY = "Q_CAP_DIFFBUS","I203": #LOCATION = "C697" !CDS_LOCATION = "C697" &SEC = "1" #&CDS_SEC = "1";
"1":   PN = "1"  !CDS_PN = "1";
"2":   PN = "2"  !CDS_PN = "2";
BODY = "Q_CAP_DIFFBUS","I204": #LOCATION = "C696" !CDS_LOCATION = "C696" &SEC = "1" #&CDS_SEC = "1";
"1":   PN = "1"  !CDS_PN = "1";
"2":   PN = "2"  !CDS_PN = "2";
BODY = "Q_CAP_DIFFBUS","I205": #LOCATION = "C695" !CDS_LOCATION = "C695" &SEC = "1" #&CDS_SEC = "1";
"1":   PN = "1"  !CDS_PN = "1";
"2":   PN = "2"  !CDS_PN = "2";
BODY = "Q_CAP_DIFFBUS","I206": #LOCATION = "C694" !CDS_LOCATION = "C694" &SEC = "1" #&CDS_SEC = "1";
"1":   PN = "1"  !CDS_PN = "1";
"2":   PN = "2"  !CDS_PN = "2";
BODY = "Q_CAP_DIFFBUS","I216": #LOCATION = "C56" !CDS_LOCATION = "C56" &SEC = "1" #&CDS_SEC = "1";
"1":   PN = "1"  !CDS_PN = "1";
"2":   PN = "2"  !CDS_PN = "2";
BODY = "Q_CAP_DIFFBUS","I217": #LOCATION = "C692" !CDS_LOCATION = "C692" &SEC = "1" #&CDS_SEC = "1";
"1":   PN = "1"  !CDS_PN = "1";
"2":   PN = "2"  !CDS_PN = "2";
BODY = "Q_CAP_DIFFBUS","I218": #LOCATION = "C691" !CDS_LOCATION = "C691" &SEC = "1" #&CDS_SEC = "1";
"1":   PN = "1"  !CDS_PN = "1";
"2":   PN = "2"  !CDS_PN = "2";
BODY = "Q_CAP_DIFFBUS","I219": #LOCATION = "C690" !CDS_LOCATION = "C690" &SEC = "1" #&CDS_SEC = "1";
"1":   PN = "1"  !CDS_PN = "1";
"2":   PN = "2"  !CDS_PN = "2";
BODY = "Q_CAP_DIFFBUS","I220": #LOCATION = "C688" !CDS_LOCATION = "C688" &SEC = "1" #&CDS_SEC = "1";
"1":   PN = "1"  !CDS_PN = "1";
"2":   PN = "2"  !CDS_PN = "2";
BODY = "Q_CAP_DIFFBUS","I221": #LOCATION = "C689" !CDS_LOCATION = "C689" &SEC = "1" #&CDS_SEC = "1";
"1":   PN = "1"  !CDS_PN = "1";
"2":   PN = "2"  !CDS_PN = "2";
BODY = "Q_CAP_DIFFBUS","I222": #LOCATION = "C687" !CDS_LOCATION = "C687" &SEC = "1" #&CDS_SEC = "1";
"1":   PN = "1"  !CDS_PN = "1";
"2":   PN = "2"  !CDS_PN = "2";
BODY = "Q_CAP_DIFFBUS","I223": #LOCATION = "C686" !CDS_LOCATION = "C686" &SEC = "1" #&CDS_SEC = "1";
"1":   PN = "1"  !CDS_PN = "1";
"2":   PN = "2"  !CDS_PN = "2";
BODY = "Q_CAP_DIFFBUS","I224": #LOCATION = "C685" !CDS_LOCATION = "C685" &SEC = "1" #&CDS_SEC = "1";
"1":   PN = "1"  !CDS_PN = "1";
"2":   PN = "2"  !CDS_PN = "2";
BODY = "Q_CAP_DIFFBUS","I225": #LOCATION = "C684" !CDS_LOCATION = "C684" &SEC = "1" #&CDS_SEC = "1";
"1":   PN = "1"  !CDS_PN = "1";
"2":   PN = "2"  !CDS_PN = "2";
BODY = "Q_CAP_DIFFBUS","I236": #LOCATION = "C683" !CDS_LOCATION = "C683" &SEC = "1" #&CDS_SEC = "1";
"1":   PN = "1"  !CDS_PN = "1";
"2":   PN = "2"  !CDS_PN = "2";
BODY = "Q_CAP_DIFFBUS","I247": #LOCATION = "C682" !CDS_LOCATION = "C682" &SEC = "1" #&CDS_SEC = "1";
"1":   PN = "1"  !CDS_PN = "1";
"2":   PN = "2"  !CDS_PN = "2";
BODY = "Q_CAP_DIFFBUS","I248": #LOCATION = "C681" !CDS_LOCATION = "C681" &SEC = "1" #&CDS_SEC = "1";
"1":   PN = "1"  !CDS_PN = "1";
"2":   PN = "2"  !CDS_PN = "2";
BODY = "Q_CAP_DIFFBUS","I249": #LOCATION = "C680" !CDS_LOCATION = "C680" &SEC = "1" #&CDS_SEC = "1";
"1":   PN = "1"  !CDS_PN = "1";
"2":   PN = "2"  !CDS_PN = "2";
BODY = "Q_CAP_DIFFBUS","I250": #LOCATION = "C679" !CDS_LOCATION = "C679" &SEC = "1" #&CDS_SEC = "1";
"1":   PN = "1"  !CDS_PN = "1";
"2":   PN = "2"  !CDS_PN = "2";
BODY = "Q_CAP_DIFFBUS","I251": #LOCATION = "C678" !CDS_LOCATION = "C678" &SEC = "1" #&CDS_SEC = "1";
"1":   PN = "1"  !CDS_PN = "1";
"2":   PN = "2"  !CDS_PN = "2";
DRAWING = "@t6g_mb_lib.t6g(sch_1):page297";
BODY = "Q_RES","I2": #LOCATION = "R3775" !CDS_LOCATION = "R3775" &SEC = "1" #&CDS_SEC = "1";
"A":   PN = "1"  !CDS_PN = "1";
"B":   PN = "2"  !CDS_PN = "2";
BODY = "74LVC2G07DW7","I4": #LOCATION = "U134" !CDS_LOCATION = "U134" &SEC = "1" #&CDS_SEC = "1";
"1A":   PN = "1"  !CDS_PN = "1";
"1Y":   PN = "6"  !CDS_PN = "6";
"2A":   PN = "3"  !CDS_PN = "3";
"2Y":   PN = "4"  !CDS_PN = "4";
"GND":   PN = "2"  !CDS_PN = "2";
"VCC":   PN = "5"  !CDS_PN = "5";
BODY = "Q_RES","I6": #LOCATION = "R10296" !CDS_LOCATION = "R10296" &SEC = "1" #&CDS_SEC = "1";
"A":   PN = "1"  !CDS_PN = "1";
"B":   PN = "2"  !CDS_PN = "2";
BODY = "Q_RES","I7": #LOCATION = "R3771" !CDS_LOCATION = "R3771" &SEC = "1" #&CDS_SEC = "1";
"A":   PN = "1"  !CDS_PN = "1";
"B":   PN = "2"  !CDS_PN = "2";
BODY = "Q_RES","I30": #LOCATION = "R3779" !CDS_LOCATION = "R3779" &SEC = "1" #&CDS_SEC = "1";
"A":   PN = "1"  !CDS_PN = "1";
"B":   PN = "2"  !CDS_PN = "2";
BODY = "Q_RES","I31": #LOCATION = "R2317" !CDS_LOCATION = "R2317" &SEC = "1" #&CDS_SEC = "1";
"A":   PN = "1"  !CDS_PN = "1";
"B":   PN = "2"  !CDS_PN = "2";
BODY = "Q_CAP","I36": #LOCATION = "C1592" !CDS_LOCATION = "C1592" &SEC = "1" #&CDS_SEC = "1";
"A":   PN = "1"  !CDS_PN = "1";
"B":   PN = "2"  !CDS_PN = "2";
BODY = "Q_RES","I37": #LOCATION = "R2114" !CDS_LOCATION = "R2114" &SEC = "1" #&CDS_SEC = "1";
"A":   PN = "1"  !CDS_PN = "1";
"B":   PN = "2"  !CDS_PN = "2";
BODY = "Q_RES","I38": #LOCATION = "R3772" !CDS_LOCATION = "R3772" &SEC = "1" #&CDS_SEC = "1";
"A":   PN = "1"  !CDS_PN = "1";
"B":   PN = "2"  !CDS_PN = "2";
BODY = "Q_RES","I40": #LOCATION = "R2125" !CDS_LOCATION = "R2125" &SEC = "1" #&CDS_SEC = "1";
"A":   PN = "1"  !CDS_PN = "1";
"B":   PN = "2"  !CDS_PN = "2";
BODY = "Q_CAP","I66": #LOCATION = "C1276" !CDS_LOCATION = "C1276" &SEC = "1" #&CDS_SEC = "1";
"A":   PN = "1"  !CDS_PN = "1";
"B":   PN = "2"  !CDS_PN = "2";
BODY = "Q_CAP","I67": #LOCATION = "C1277" !CDS_LOCATION = "C1277" &SEC = "1" #&CDS_SEC = "1";
"A":   PN = "1"  !CDS_PN = "1";
"B":   PN = "2"  !CDS_PN = "2";
BODY = "Q_CAP","I68": #LOCATION = "C1278" !CDS_LOCATION = "C1278" &SEC = "1" #&CDS_SEC = "1";
"A":   PN = "1"  !CDS_PN = "1";
"B":   PN = "2"  !CDS_PN = "2";
BODY = "Q_CAP","I74": #LOCATION = "C1279" !CDS_LOCATION = "C1279" &SEC = "1" #&CDS_SEC = "1";
"A":   PN = "1"  !CDS_PN = "1";
"B":   PN = "2"  !CDS_PN = "2";
BODY = "Q_RES","I75": #LOCATION = "R2426" !CDS_LOCATION = "R2426" &SEC = "1" #&CDS_SEC = "1";
"A":   PN = "1"  !CDS_PN = "1";
"B":   PN = "2"  !CDS_PN = "2";
BODY = "Q_RES","I79": #LOCATION = "R10287" !CDS_LOCATION = "R10287" &SEC = "1" #&CDS_SEC = "1";
"A":   PN = "1"  !CDS_PN = "1";
"B":   PN = "2"  !CDS_PN = "2";
BODY = "Q_CAP","I87": #LOCATION = "C1282" !CDS_LOCATION = "C1282" &SEC = "1" #&CDS_SEC = "1";
"A":   PN = "1"  !CDS_PN = "1";
"B":   PN = "2"  !CDS_PN = "2";
BODY = "Q_CAP","I88": #LOCATION = "C1283" !CDS_LOCATION = "C1283" &SEC = "1" #&CDS_SEC = "1";
"A":   PN = "1"  !CDS_PN = "1";
"B":   PN = "2"  !CDS_PN = "2";
BODY = "SCONN56_123276793","I90": #LOCATION = "J90" !CDS_LOCATION = "J90" &SEC = "1" #&CDS_SEC = "1";
"DUALPORTEN#":   PN = "B9"  !CDS_PN = "B9";
"G1":   PN = "G1"  !CDS_PN = "G1";
"G2":   PN = "G2"  !CDS_PN = "G2";
"GND_A1":   PN = "A1"  !CDS_PN = "A1";
"GND_A2":   PN = "A2"  !CDS_PN = "A2";
"GND_A3":   PN = "A3"  !CDS_PN = "A3";
"GND_A4":   PN = "A4"  !CDS_PN = "A4";
"GND_A5":   PN = "A5"  !CDS_PN = "A5";
"GND_A6":   PN = "A6"  !CDS_PN = "A6";
"GND_A13":   PN = "A13"  !CDS_PN = "A13";
"GND_A16":   PN = "A16"  !CDS_PN = "A16";
"GND_A19":   PN = "A19"  !CDS_PN = "A19";
"GND_A22":   PN = "A22"  !CDS_PN = "A22";
"GND_A25":   PN = "A25"  !CDS_PN = "A25";
"GND_A28":   PN = "A28"  !CDS_PN = "A28";
"GND_B13":   PN = "B13"  !CDS_PN = "B13";
"GND_B16":   PN = "B16"  !CDS_PN = "B16";
"GND_B19":   PN = "B19"  !CDS_PN = "B19";
"GND_B22":   PN = "B22"  !CDS_PN = "B22";
"GND_B25":   PN = "B25"  !CDS_PN = "B25";
"GND_B28":   PN = "B28"  !CDS_PN = "B28";
"LED#_ACTIVITY":   PN = "A10"  !CDS_PN = "A10";
"MFG":   PN = "B7"  !CDS_PN = "B7";
"P3V3_AUX":   PN = "B11"  !CDS_PN = "B11";
"P12V_B1":   PN = "B1"  !CDS_PN = "B1";
"P12V_B2":   PN = "B2"  !CDS_PN = "B2";
"P12V_B3":   PN = "B3"  !CDS_PN = "B3";
"P12V_B4":   PN = "B4"  !CDS_PN = "B4";
"P12V_B5":   PN = "B5"  !CDS_PN = "B5";
"P12V_B6":   PN = "B6"  !CDS_PN = "B6";
"PER_N0":   PN = "A17"  !CDS_PN = "A17";
"PER_N1":   PN = "A20"  !CDS_PN = "A20";
"PER_N2":   PN = "A23"  !CDS_PN = "A23";
"PER_N3":   PN = "A26"  !CDS_PN = "A26";
"PER_P0":   PN = "A18"  !CDS_PN = "A18";
"PER_P1":   PN = "A21"  !CDS_PN = "A21";
"PER_P2":   PN = "A24"  !CDS_PN = "A24";
"PER_P3":   PN = "A27"  !CDS_PN = "A27";
"PERST0#":   PN = "B10"  !CDS_PN = "B10";
"PERST1#_CLKREQ#":   PN = "A11"  !CDS_PN = "A11";
"PET_N0":   PN = "B17"  !CDS_PN = "B17";
"PET_N1":   PN = "B20"  !CDS_PN = "B20";
"PET_N2":   PN = "B23"  !CDS_PN = "B23";
"PET_N3":   PN = "B26"  !CDS_PN = "B26";
"PET_P0":   PN = "B18"  !CDS_PN = "B18";
"PET_P1":   PN = "B21"  !CDS_PN = "B21";
"PET_P2":   PN = "B24"  !CDS_PN = "B24";
"PET_P3":   PN = "B27"  !CDS_PN = "B27";
"PRSNT0#":   PN = "A12"  !CDS_PN = "A12";
"PWRDIS":   PN = "B12"  !CDS_PN = "B12";
"REFCLK_N0":   PN = "B14"  !CDS_PN = "B14";
"REFCLK_N1":   PN = "A14"  !CDS_PN = "A14";
"REFCLK_P0":   PN = "B15"  !CDS_PN = "B15";
"REFCLK_P1":   PN = "A15"  !CDS_PN = "A15";
"RFU":   PN = "B8"  !CDS_PN = "B8";
"SMBCLK":   PN = "A7"  !CDS_PN = "A7";
"SMBDAT":   PN = "A8"  !CDS_PN = "A8";
"SMBRST#":   PN = "A9"  !CDS_PN = "A9";
BODY = "Q_RES","I94": #LOCATION = "R955" !CDS_LOCATION = "R955" &SEC = "1" #&CDS_SEC = "1";
"A":   PN = "1"  !CDS_PN = "1";
"B":   PN = "2"  !CDS_PN = "2";
BODY = "Q_RES","I95": #LOCATION = "R999" !CDS_LOCATION = "R999" &SEC = "1" #&CDS_SEC = "1";
"A":   PN = "1"  !CDS_PN = "1";
"B":   PN = "2"  !CDS_PN = "2";
BODY = "74LVC1G17GW","I97": #LOCATION = "U44" !CDS_LOCATION = "U44" &SEC = "1" #&CDS_SEC = "1";
"A":   PN = "2"  !CDS_PN = "2";
"GND":   PN = "3"  !CDS_PN = "3";
"NC":   PN = "1"  !CDS_PN = "1";
"VCC":   PN = "5"  !CDS_PN = "5";
"Y":   PN = "4"  !CDS_PN = "4";
BODY = "Q_CAP","I99": #LOCATION = "C508" !CDS_LOCATION = "C508" &SEC = "1" #&CDS_SEC = "1";
"A":   PN = "1"  !CDS_PN = "1";
"B":   PN = "2"  !CDS_PN = "2";
BODY = "Q_RES","I101": #LOCATION = "R1038" !CDS_LOCATION = "R1038" &SEC = "1" #&CDS_SEC = "1";
"A":   PN = "1"  !CDS_PN = "1";
"B":   PN = "2"  !CDS_PN = "2";
BODY = "Q_RES","I102": #LOCATION = "R1000" !CDS_LOCATION = "R1000" &SEC = "1" #&CDS_SEC = "1";
"A":   PN = "1"  !CDS_PN = "1";
"B":   PN = "2"  !CDS_PN = "2";
BODY = "Q_RES","I105": #LOCATION = "R1673" !CDS_LOCATION = "R1673" &SEC = "1" #&CDS_SEC = "1";
"A":   PN = "1"  !CDS_PN = "1";
"B":   PN = "2"  !CDS_PN = "2";
BODY = "Q_RES","I106": #LOCATION = "R3773" !CDS_LOCATION = "R3773" &SEC = "1" #&CDS_SEC = "1";
"A":   PN = "1"  !CDS_PN = "1";
"B":   PN = "2"  !CDS_PN = "2";
DRAWING = "@t6g_mb_lib.t6g(sch_1):page110";
BODY = "Q_RES","I2": #LOCATION = "R3268" !CDS_LOCATION = "R3268" &SEC = "1" #&CDS_SEC = "1";
"A":   PN = "1"  !CDS_PN = "1";
"B":   PN = "2"  !CDS_PN = "2";
BODY = "Q_RES","I4": #LOCATION = "R3272" !CDS_LOCATION = "R3272" &SEC = "1" #&CDS_SEC = "1";
"A":   PN = "1"  !CDS_PN = "1";
"B":   PN = "2"  !CDS_PN = "2";
BODY = "Q_RES","I5": #LOCATION = "R3271" !CDS_LOCATION = "R3271" &SEC = "1" #&CDS_SEC = "1";
"A":   PN = "1"  !CDS_PN = "1";
"B":   PN = "2"  !CDS_PN = "2";
BODY = "Q_RES","I8": #LOCATION = "R3267" !CDS_LOCATION = "R3267" &SEC = "1" #&CDS_SEC = "1";
"A":   PN = "1"  !CDS_PN = "1";
"B":   PN = "2"  !CDS_PN = "2";
BODY = "Q_RES","I9": #LOCATION = "R3270" !CDS_LOCATION = "R3270" &SEC = "1" #&CDS_SEC = "1";
"A":   PN = "1"  !CDS_PN = "1";
"B":   PN = "2"  !CDS_PN = "2";
BODY = "Q_RES","I12": #LOCATION = "R3273" !CDS_LOCATION = "R3273" &SEC = "1" #&CDS_SEC = "1";
"A":   PN = "1"  !CDS_PN = "1";
"B":   PN = "2"  !CDS_PN = "2";
BODY = "Q_RES","I14": #LOCATION = "R3269" !CDS_LOCATION = "R3269" &SEC = "1" #&CDS_SEC = "1";
"A":   PN = "1"  !CDS_PN = "1";
"B":   PN = "2"  !CDS_PN = "2";
BODY = "Q_RES","I16": #LOCATION = "R3274" !CDS_LOCATION = "R3274" &SEC = "1" #&CDS_SEC = "1";
"A":   PN = "1"  !CDS_PN = "1";
"B":   PN = "2"  !CDS_PN = "2";
BODY = "Q_RES","I18": #LOCATION = "R3278" !CDS_LOCATION = "R3278" &SEC = "1" #&CDS_SEC = "1";
"A":   PN = "1"  !CDS_PN = "1";
"B":   PN = "2"  !CDS_PN = "2";
BODY = "Q_RES","I19": #LOCATION = "R3277" !CDS_LOCATION = "R3277" &SEC = "1" #&CDS_SEC = "1";
"A":   PN = "1"  !CDS_PN = "1";
"B":   PN = "2"  !CDS_PN = "2";
BODY = "Q_RES","I22": #LOCATION = "R3279" !CDS_LOCATION = "R3279" &SEC = "1" #&CDS_SEC = "1";
"A":   PN = "1"  !CDS_PN = "1";
"B":   PN = "2"  !CDS_PN = "2";
BODY = "Q_RES","I25": #LOCATION = "R3281" !CDS_LOCATION = "R3281" &SEC = "1" #&CDS_SEC = "1";
"A":   PN = "1"  !CDS_PN = "1";
"B":   PN = "2"  !CDS_PN = "2";
BODY = "Q_RES","I26": #LOCATION = "R3280" !CDS_LOCATION = "R3280" &SEC = "1" #&CDS_SEC = "1";
"A":   PN = "1"  !CDS_PN = "1";
"B":   PN = "2"  !CDS_PN = "2";
BODY = "Q_RES","I29": #LOCATION = "R3276" !CDS_LOCATION = "R3276" &SEC = "1" #&CDS_SEC = "1";
"A":   PN = "1"  !CDS_PN = "1";
"B":   PN = "2"  !CDS_PN = "2";
BODY = "Q_RES","I32": #LOCATION = "R3275" !CDS_LOCATION = "R3275" &SEC = "1" #&CDS_SEC = "1";
"A":   PN = "1"  !CDS_PN = "1";
"B":   PN = "2"  !CDS_PN = "2";
BODY = "Q_RES","I34": #LOCATION = "R3282" !CDS_LOCATION = "R3282" &SEC = "1" #&CDS_SEC = "1";
"A":   PN = "1"  !CDS_PN = "1";
"B":   PN = "2"  !CDS_PN = "2";
BODY = "Q_RES","I36": #LOCATION = "R3284" !CDS_LOCATION = "R3284" &SEC = "1" #&CDS_SEC = "1";
"A":   PN = "1"  !CDS_PN = "1";
"B":   PN = "2"  !CDS_PN = "2";
BODY = "Q_RES","I37": #LOCATION = "R3283" !CDS_LOCATION = "R3283" &SEC = "1" #&CDS_SEC = "1";
"A":   PN = "1"  !CDS_PN = "1";
"B":   PN = "2"  !CDS_PN = "2";
BODY = "Q_RES","I42": #LOCATION = "R3285" !CDS_LOCATION = "R3285" &SEC = "1" #&CDS_SEC = "1";
"A":   PN = "1"  !CDS_PN = "1";
"B":   PN = "2"  !CDS_PN = "2";
BODY = "Q_RES","I44": #LOCATION = "R3287" !CDS_LOCATION = "R3287" &SEC = "1" #&CDS_SEC = "1";
"A":   PN = "1"  !CDS_PN = "1";
"B":   PN = "2"  !CDS_PN = "2";
BODY = "Q_RES","I45": #LOCATION = "R3286" !CDS_LOCATION = "R3286" &SEC = "1" #&CDS_SEC = "1";
"A":   PN = "1"  !CDS_PN = "1";
"B":   PN = "2"  !CDS_PN = "2";
BODY = "Q_CAP","I60": #LOCATION = "C1867" !CDS_LOCATION = "C1867" &SEC = "1" #&CDS_SEC = "1";
"A":   PN = "1"  !CDS_PN = "1";
"B":   PN = "2"  !CDS_PN = "2";
BODY = "Q_CAP","I61": #LOCATION = "C1863" !CDS_LOCATION = "C1863" &SEC = "1" #&CDS_SEC = "1";
"A":   PN = "1"  !CDS_PN = "1";
"B":   PN = "2"  !CDS_PN = "2";
BODY = "Q_CAP","I62": #LOCATION = "C1864" !CDS_LOCATION = "C1864" &SEC = "1" #&CDS_SEC = "1";
"A":   PN = "1"  !CDS_PN = "1";
"B":   PN = "2"  !CDS_PN = "2";
BODY = "PI3EQX12902AZLEX","I63": #LOCATION = "U237" !CDS_LOCATION = "U237" &SEC = "1" #&CDS_SEC = "1";
"AIN":   PN = "3"  !CDS_PN = "3";
"AIP":   PN = "2"  !CDS_PN = "2";
"AON":   PN = "23"  !CDS_PN = "23";
"AOP":   PN = "24"  !CDS_PN = "24";
"BIN":   PN = "18"  !CDS_PN = "18";
"BIP":   PN = "17"  !CDS_PN = "17";
"BON":   PN = "8"  !CDS_PN = "8";
"BOP":   PN = "9"  !CDS_PN = "9";
"EN#":   PN = "11"  !CDS_PN = "11";
"EQA0":   PN = "21"  !CDS_PN = "21";
"EQA1":   PN = "26"  !CDS_PN = "26";
"EQB0":   PN = "20"  !CDS_PN = "20";
"EQB1":   PN = "15"  !CDS_PN = "15";
"FGA":   PN = "27"  !CDS_PN = "27";
"FGB":   PN = "14"  !CDS_PN = "14";
"GND1":   PN = "4"  !CDS_PN = "4";
"GND2":   PN = "6"  !CDS_PN = "6";
"GND3":   PN = "7"  !CDS_PN = "7";
"GND4":   PN = "13"  !CDS_PN = "13";
"GND5":   PN = "19"  !CDS_PN = "19";
"GND6":   PN = "22"  !CDS_PN = "22";
"GND7":   PN = "28"  !CDS_PN = "28";
"GND_TH":   PN = "TH"  !CDS_PN = "TH";
"MODE":   PN = "30"  !CDS_PN = "30";
"SWA":   PN = "29"  !CDS_PN = "29";
"SWB":   PN = "12"  !CDS_PN = "12";
"TEST#":   PN = "5"  !CDS_PN = "5";
"VDD1":   PN = "1"  !CDS_PN = "1";
"VDD2":   PN = "10"  !CDS_PN = "10";
"VDD3":   PN = "16"  !CDS_PN = "16";
"VDD4":   PN = "25"  !CDS_PN = "25";
BODY = "Q_CAP","I64": #LOCATION = "C1865" !CDS_LOCATION = "C1865" &SEC = "1" #&CDS_SEC = "1";
"A":   PN = "1"  !CDS_PN = "1";
"B":   PN = "2"  !CDS_PN = "2";
BODY = "Q_CAP","I65": #LOCATION = "C1866" !CDS_LOCATION = "C1866" &SEC = "1" #&CDS_SEC = "1";
"A":   PN = "1"  !CDS_PN = "1";
"B":   PN = "2"  !CDS_PN = "2";
BODY = "Q_RES","I67": #LOCATION = "R4537" !CDS_LOCATION = "R4537" &SEC = "1" #&CDS_SEC = "1";
"A":   PN = "1"  !CDS_PN = "1";
"B":   PN = "2"  !CDS_PN = "2";
BODY = "Q_RES","I74": #LOCATION = "R3288" !CDS_LOCATION = "R3288" &SEC = "1" #&CDS_SEC = "1";
"A":   PN = "1"  !CDS_PN = "1";
"B":   PN = "2"  !CDS_PN = "2";
BODY = "Q_RES","I76": #LOCATION = "R3290" !CDS_LOCATION = "R3290" &SEC = "1" #&CDS_SEC = "1";
"A":   PN = "1"  !CDS_PN = "1";
"B":   PN = "2"  !CDS_PN = "2";
BODY = "Q_RES","I77": #LOCATION = "R3289" !CDS_LOCATION = "R3289" &SEC = "1" #&CDS_SEC = "1";
"A":   PN = "1"  !CDS_PN = "1";
"B":   PN = "2"  !CDS_PN = "2";
BODY = "Q_RES","I81": #LOCATION = "R3265" !CDS_LOCATION = "R3265" &SEC = "1" #&CDS_SEC = "1";
"A":   PN = "1"  !CDS_PN = "1";
"B":   PN = "2"  !CDS_PN = "2";
BODY = "Q_RES","I88": #LOCATION = "R3291" !CDS_LOCATION = "R3291" &SEC = "1" #&CDS_SEC = "1";
"A":   PN = "1"  !CDS_PN = "1";
"B":   PN = "2"  !CDS_PN = "2";
BODY = "Q_RES","I89": #LOCATION = "R3292" !CDS_LOCATION = "R3292" &SEC = "1" #&CDS_SEC = "1";
"A":   PN = "1"  !CDS_PN = "1";
"B":   PN = "2"  !CDS_PN = "2";
BODY = "Q_RES","I92": #LOCATION = "R3293" !CDS_LOCATION = "R3293" &SEC = "1" #&CDS_SEC = "1";
"A":   PN = "1"  !CDS_PN = "1";
"B":   PN = "2"  !CDS_PN = "2";
BODY = "Q_RES","I93": #LOCATION = "R3266" !CDS_LOCATION = "R3266" &SEC = "1" #&CDS_SEC = "1";
"A":   PN = "1"  !CDS_PN = "1";
"B":   PN = "2"  !CDS_PN = "2";
DRAWING = "@t6g_mb_lib.t6g(sch_1):page53";
BODY = "Q_CAP_DIFFBUS","I132": #LOCATION = "C2073" !CDS_LOCATION = "C2073" &SEC = "1" #&CDS_SEC = "1";
"1":   PN = "1"  !CDS_PN = "1";
"2":   PN = "2"  !CDS_PN = "2";
BODY = "Q_CAP_DIFFBUS","I133": #LOCATION = "C2074" !CDS_LOCATION = "C2074" &SEC = "1" #&CDS_SEC = "1";
"1":   PN = "1"  !CDS_PN = "1";
"2":   PN = "2"  !CDS_PN = "2";
BODY = "Q_CAP_DIFFBUS","I134": #LOCATION = "C2076" !CDS_LOCATION = "C2076" &SEC = "1" #&CDS_SEC = "1";
"1":   PN = "1"  !CDS_PN = "1";
"2":   PN = "2"  !CDS_PN = "2";
BODY = "Q_CAP_DIFFBUS","I135": #LOCATION = "C2075" !CDS_LOCATION = "C2075" &SEC = "1" #&CDS_SEC = "1";
"1":   PN = "1"  !CDS_PN = "1";
"2":   PN = "2"  !CDS_PN = "2";
BODY = "GENOA_SP5","I145": #LOCATION = "U26" !CDS_LOCATION = "U26" &SEC = "19" #&CDS_SEC = "19";
"P4_RXN0":   PN = "DG53"  !CDS_PN = "DG53";
"P4_RXN1":   PN = "DG50"  !CDS_PN = "DG50";
"P4_RXN2":   PN = "DG47"  !CDS_PN = "DG47";
"P4_RXN3":   PN = "DG44"  !CDS_PN = "DG44";
"P4_RXP0":   PN = "DG54"  !CDS_PN = "DG54";
"P4_RXP1":   PN = "DG51"  !CDS_PN = "DG51";
"P4_RXP2":   PN = "DG48"  !CDS_PN = "DG48";
"P4_RXP3":   PN = "DG45"  !CDS_PN = "DG45";
"P4_TXN0":   PN = "DE52"  !CDS_PN = "DE52";
"P4_TXN1":   PN = "DE49"  !CDS_PN = "DE49";
"P4_TXN2":   PN = "DE46"  !CDS_PN = "DE46";
"P4_TXN3":   PN = "DE43"  !CDS_PN = "DE43";
"P4_TXP0":   PN = "DE53"  !CDS_PN = "DE53";
"P4_TXP1":   PN = "DE50"  !CDS_PN = "DE50";
"P4_TXP2":   PN = "DE47"  !CDS_PN = "DE47";
"P4_TXP3":   PN = "DE44"  !CDS_PN = "DE44";
"P5_RXN2":   PN = "E44"  !CDS_PN = "E44";
"P5_RXN3":   PN = "E41"  !CDS_PN = "E41";
"P5_RXP2":   PN = "E43"  !CDS_PN = "E43";
"P5_RXP3":   PN = "E40"  !CDS_PN = "E40";
"P5_TXN2":   PN = "C45"  !CDS_PN = "C45";
"P5_TXN3":   PN = "C42"  !CDS_PN = "C42";
"P5_TXP2":   PN = "C44"  !CDS_PN = "C44";
"P5_TXP3":   PN = "C41"  !CDS_PN = "C41";
"WAFL_RXN0||P5_RXN0":   PN = "E50"  !CDS_PN = "E50";
"WAFL_RXN1||P5_RXN1":   PN = "E47"  !CDS_PN = "E47";
"WAFL_RXP0||P5_RXP0":   PN = "E49"  !CDS_PN = "E49";
"WAFL_RXP1||P5_RXP1":   PN = "E46"  !CDS_PN = "E46";
"WAFL_TXN0||P5_TXN0":   PN = "C51"  !CDS_PN = "C51";
"WAFL_TXN1||P5_TXN1":   PN = "C48"  !CDS_PN = "C48";
"WAFL_TXP0||P5_TXP0":   PN = "C50"  !CDS_PN = "C50";
"WAFL_TXP1||P5_TXP1":   PN = "C47"  !CDS_PN = "C47";
DRAWING = "@t6g_mb_lib.t6g(sch_1):page28";
BODY = "Q_RES","I22": #LOCATION = "R420" !CDS_LOCATION = "R420" &SEC = "1" #&CDS_SEC = "1";
"A":   PN = "1"  !CDS_PN = "1";
"B":   PN = "2"  !CDS_PN = "2";
BODY = "Q_RES","I25": #LOCATION = "R425" !CDS_LOCATION = "R425" &SEC = "1" #&CDS_SEC = "1";
"A":   PN = "1"  !CDS_PN = "1";
"B":   PN = "2"  !CDS_PN = "2";
BODY = "Q_RES","I53": #LOCATION = "R443" !CDS_LOCATION = "R443" &SEC = "1" #&CDS_SEC = "1";
"A":   PN = "1"  !CDS_PN = "1";
"B":   PN = "2"  !CDS_PN = "2";
BODY = "Q_RES","I96": #LOCATION = "R212" !CDS_LOCATION = "R212" &SEC = "1" #&CDS_SEC = "1";
"A":   PN = "1"  !CDS_PN = "1";
"B":   PN = "2"  !CDS_PN = "2";
BODY = "Q_RES","I136": #LOCATION = "R248" !CDS_LOCATION = "R248" &SEC = "1" #&CDS_SEC = "1";
"A":   PN = "1"  !CDS_PN = "1";
"B":   PN = "2"  !CDS_PN = "2";
BODY = "Q_CRYSTAL","I140": #LOCATION = "Y3" !CDS_LOCATION = "Y3" &SEC = "1" #&CDS_SEC = "1";
"1":   PN = "1"  !CDS_PN = "1";
"2":   PN = "2"  !CDS_PN = "2";
BODY = "Q_RES","I151": #LOCATION = "R2660" !CDS_LOCATION = "R2660" &SEC = "1" #&CDS_SEC = "1";
"A":   PN = "1"  !CDS_PN = "1";
"B":   PN = "2"  !CDS_PN = "2";
BODY = "Q_RES","I155": #LOCATION = "R8566" !CDS_LOCATION = "R8566" &SEC = "1" #&CDS_SEC = "1";
"A":   PN = "1"  !CDS_PN = "1";
"B":   PN = "2"  !CDS_PN = "2";
BODY = "Q_RES","I156": #LOCATION = "R8564" !CDS_LOCATION = "R8564" &SEC = "1" #&CDS_SEC = "1";
"A":   PN = "1"  !CDS_PN = "1";
"B":   PN = "2"  !CDS_PN = "2";
BODY = "Q_RES","I171": #LOCATION = "R435" !CDS_LOCATION = "R435" &SEC = "1" #&CDS_SEC = "1";
"A":   PN = "1"  !CDS_PN = "1";
"B":   PN = "2"  !CDS_PN = "2";
BODY = "Q_RES","I172": #LOCATION = "R436" !CDS_LOCATION = "R436" &SEC = "1" #&CDS_SEC = "1";
"A":   PN = "1"  !CDS_PN = "1";
"B":   PN = "2"  !CDS_PN = "2";
BODY = "Q_RES","I23": #LOCATION = "R421" !CDS_LOCATION = "R421" &SEC = "1" #&CDS_SEC = "1";
"A":   PN = "1"  !CDS_PN = "1";
"B":   PN = "2"  !CDS_PN = "2";
BODY = "Q_RES","I24": #LOCATION = "R423" !CDS_LOCATION = "R423" &SEC = "1" #&CDS_SEC = "1";
"A":   PN = "1"  !CDS_PN = "1";
"B":   PN = "2"  !CDS_PN = "2";
BODY = "CONN6_HBC1031L200D8H","I28": #LOCATION = "J6" !CDS_LOCATION = "J6" &SEC = "1" #&CDS_SEC = "1";
"1":   PN = "1"  !CDS_PN = "1";
"2":   PN = "2"  !CDS_PN = "2";
"3":   PN = "3"  !CDS_PN = "3";
"4":   PN = "4"  !CDS_PN = "4";
"5":   PN = "5"  !CDS_PN = "5";
"6":   PN = "6"  !CDS_PN = "6";
BODY = "Q_RES","I29": #LOCATION = "R422" !CDS_LOCATION = "R422" &SEC = "1" #&CDS_SEC = "1";
"A":   PN = "1"  !CDS_PN = "1";
"B":   PN = "2"  !CDS_PN = "2";
BODY = "Q_RES","I30": #LOCATION = "R424" !CDS_LOCATION = "R424" &SEC = "1" #&CDS_SEC = "1";
"A":   PN = "1"  !CDS_PN = "1";
"B":   PN = "2"  !CDS_PN = "2";
BODY = "Q_RES","I33": #LOCATION = "R582" !CDS_LOCATION = "R582" &SEC = "1" #&CDS_SEC = "1";
"A":   PN = "1"  !CDS_PN = "1";
"B":   PN = "2"  !CDS_PN = "2";
BODY = "Q_RES","I34": #LOCATION = "R581" !CDS_LOCATION = "R581" &SEC = "1" #&CDS_SEC = "1";
"A":   PN = "1"  !CDS_PN = "1";
"B":   PN = "2"  !CDS_PN = "2";
BODY = "Q_RES","I36": #LOCATION = "R287" !CDS_LOCATION = "R287" &SEC = "1" #&CDS_SEC = "1";
"A":   PN = "1"  !CDS_PN = "1";
"B":   PN = "2"  !CDS_PN = "2";
BODY = "Q_RES","I37": #LOCATION = "R440" !CDS_LOCATION = "R440" &SEC = "1" #&CDS_SEC = "1";
"A":   PN = "1"  !CDS_PN = "1";
"B":   PN = "2"  !CDS_PN = "2";
BODY = "Q_RES","I40": #LOCATION = "R5026" !CDS_LOCATION = "R5026" &SEC = "1" #&CDS_SEC = "1";
"A":   PN = "1"  !CDS_PN = "1";
"B":   PN = "2"  !CDS_PN = "2";
BODY = "Q_RES","I41": #LOCATION = "R276" !CDS_LOCATION = "R276" &SEC = "1" #&CDS_SEC = "1";
"A":   PN = "1"  !CDS_PN = "1";
"B":   PN = "2"  !CDS_PN = "2";
BODY = "Q_RES","I42": #LOCATION = "R288" !CDS_LOCATION = "R288" &SEC = "1" #&CDS_SEC = "1";
"A":   PN = "1"  !CDS_PN = "1";
"B":   PN = "2"  !CDS_PN = "2";
BODY = "Q_RES","I43": #LOCATION = "R444" !CDS_LOCATION = "R444" &SEC = "1" #&CDS_SEC = "1";
"A":   PN = "1"  !CDS_PN = "1";
"B":   PN = "2"  !CDS_PN = "2";
BODY = "Q_RES","I44": #LOCATION = "R207" !CDS_LOCATION = "R207" &SEC = "1" #&CDS_SEC = "1";
"A":   PN = "1"  !CDS_PN = "1";
"B":   PN = "2"  !CDS_PN = "2";
BODY = "Q_RES","I45": #LOCATION = "R452" !CDS_LOCATION = "R452" &SEC = "1" #&CDS_SEC = "1";
"A":   PN = "1"  !CDS_PN = "1";
"B":   PN = "2"  !CDS_PN = "2";
BODY = "Q_RES","I46": #LOCATION = "R451" !CDS_LOCATION = "R451" &SEC = "1" #&CDS_SEC = "1";
"A":   PN = "1"  !CDS_PN = "1";
"B":   PN = "2"  !CDS_PN = "2";
BODY = "Q_RES","I47": #LOCATION = "R450" !CDS_LOCATION = "R450" &SEC = "1" #&CDS_SEC = "1";
"A":   PN = "1"  !CDS_PN = "1";
"B":   PN = "2"  !CDS_PN = "2";
BODY = "Q_RES","I48": #LOCATION = "R449" !CDS_LOCATION = "R449" &SEC = "1" #&CDS_SEC = "1";
"A":   PN = "1"  !CDS_PN = "1";
"B":   PN = "2"  !CDS_PN = "2";
BODY = "Q_RES","I49": #LOCATION = "R448" !CDS_LOCATION = "R448" &SEC = "1" #&CDS_SEC = "1";
"A":   PN = "1"  !CDS_PN = "1";
"B":   PN = "2"  !CDS_PN = "2";
BODY = "Q_RES","I55": #LOCATION = "R441" !CDS_LOCATION = "R441" &SEC = "1" #&CDS_SEC = "1";
"A":   PN = "1"  !CDS_PN = "1";
"B":   PN = "2"  !CDS_PN = "2";
BODY = "Q_RES","I56": #LOCATION = "R442" !CDS_LOCATION = "R442" &SEC = "1" #&CDS_SEC = "1";
"A":   PN = "1"  !CDS_PN = "1";
"B":   PN = "2"  !CDS_PN = "2";
BODY = "Q_RES","I59": #LOCATION = "R5027" !CDS_LOCATION = "R5027" &SEC = "1" #&CDS_SEC = "1";
"A":   PN = "1"  !CDS_PN = "1";
"B":   PN = "2"  !CDS_PN = "2";
BODY = "Q_RES","I60": #LOCATION = "R5028" !CDS_LOCATION = "R5028" &SEC = "1" #&CDS_SEC = "1";
"A":   PN = "1"  !CDS_PN = "1";
"B":   PN = "2"  !CDS_PN = "2";
BODY = "Q_RES","I62": #LOCATION = "R5029" !CDS_LOCATION = "R5029" &SEC = "1" #&CDS_SEC = "1";
"A":   PN = "1"  !CDS_PN = "1";
"B":   PN = "2"  !CDS_PN = "2";
BODY = "Q_RES","I64": #LOCATION = "R446" !CDS_LOCATION = "R446" &SEC = "1" #&CDS_SEC = "1";
"A":   PN = "1"  !CDS_PN = "1";
"B":   PN = "2"  !CDS_PN = "2";
BODY = "Q_RES","I65": #LOCATION = "R447" !CDS_LOCATION = "R447" &SEC = "1" #&CDS_SEC = "1";
"A":   PN = "1"  !CDS_PN = "1";
"B":   PN = "2"  !CDS_PN = "2";
BODY = "Q_RES","I66": #LOCATION = "R445" !CDS_LOCATION = "R445" &SEC = "1" #&CDS_SEC = "1";
"A":   PN = "1"  !CDS_PN = "1";
"B":   PN = "2"  !CDS_PN = "2";
BODY = "Q_RES","I69": #LOCATION = "R938" !CDS_LOCATION = "R938" &SEC = "1" #&CDS_SEC = "1";
"A":   PN = "1"  !CDS_PN = "1";
"B":   PN = "2"  !CDS_PN = "2";
BODY = "Q_RES","I93": #LOCATION = "R939" !CDS_LOCATION = "R939" &SEC = "1" #&CDS_SEC = "1";
"A":   PN = "1"  !CDS_PN = "1";
"B":   PN = "2"  !CDS_PN = "2";
BODY = "Q_RES","I94": #LOCATION = "R940" !CDS_LOCATION = "R940" &SEC = "1" #&CDS_SEC = "1";
"A":   PN = "1"  !CDS_PN = "1";
"B":   PN = "2"  !CDS_PN = "2";
BODY = "Q_RES","I95": #LOCATION = "R213" !CDS_LOCATION = "R213" &SEC = "1" #&CDS_SEC = "1";
"A":   PN = "1"  !CDS_PN = "1";
"B":   PN = "2"  !CDS_PN = "2";
BODY = "Q_RES","I97": #LOCATION = "R431" !CDS_LOCATION = "R431" &SEC = "1" #&CDS_SEC = "1";
"A":   PN = "1"  !CDS_PN = "1";
"B":   PN = "2"  !CDS_PN = "2";
BODY = "Q_RES","I98": #LOCATION = "R430" !CDS_LOCATION = "R430" &SEC = "1" #&CDS_SEC = "1";
"A":   PN = "1"  !CDS_PN = "1";
"B":   PN = "2"  !CDS_PN = "2";
BODY = "Q_RES","I100": #LOCATION = "R1205" !CDS_LOCATION = "R1205" &SEC = "1" #&CDS_SEC = "1";
"A":   PN = "1"  !CDS_PN = "1";
"B":   PN = "2"  !CDS_PN = "2";
BODY = "Q_XTAL_4P_13BI_24GND","I103": #LOCATION = "Y2" !CDS_LOCATION = "Y2" &SEC = "1" #&CDS_SEC = "1";
"G1":   PN = "2"  !CDS_PN = "2";
"G2":   PN = "4"  !CDS_PN = "4";
"X1":   PN = "1"  !CDS_PN = "1";
"X2":   PN = "3"  !CDS_PN = "3";
BODY = "Q_RES","I104": #LOCATION = "R432" !CDS_LOCATION = "R432" &SEC = "1" #&CDS_SEC = "1";
"A":   PN = "1"  !CDS_PN = "1";
"B":   PN = "2"  !CDS_PN = "2";
BODY = "Q_RES","I135": #LOCATION = "R249" !CDS_LOCATION = "R249" &SEC = "1" #&CDS_SEC = "1";
"A":   PN = "1"  !CDS_PN = "1";
"B":   PN = "2"  !CDS_PN = "2";
BODY = "Q_RES","I152": #LOCATION = "R2659" !CDS_LOCATION = "R2659" &SEC = "1" #&CDS_SEC = "1";
"A":   PN = "1"  !CDS_PN = "1";
"B":   PN = "2"  !CDS_PN = "2";
BODY = "Q_RES","I153": #LOCATION = "R9273" !CDS_LOCATION = "R9273" &SEC = "1" #&CDS_SEC = "1";
"A":   PN = "1"  !CDS_PN = "1";
"B":   PN = "2"  !CDS_PN = "2";
BODY = "Q_RES","I154": #LOCATION = "R9274" !CDS_LOCATION = "R9274" &SEC = "1" #&CDS_SEC = "1";
"A":   PN = "1"  !CDS_PN = "1";
"B":   PN = "2"  !CDS_PN = "2";
BODY = "Q_RES","I157": #LOCATION = "R8563" !CDS_LOCATION = "R8563" &SEC = "1" #&CDS_SEC = "1";
"A":   PN = "1"  !CDS_PN = "1";
"B":   PN = "2"  !CDS_PN = "2";
BODY = "Q_RES","I158": #LOCATION = "R8565" !CDS_LOCATION = "R8565" &SEC = "1" #&CDS_SEC = "1";
"A":   PN = "1"  !CDS_PN = "1";
"B":   PN = "2"  !CDS_PN = "2";
BODY = "Q_RES","I160": #LOCATION = "R4535" !CDS_LOCATION = "R4535" &SEC = "1" #&CDS_SEC = "1";
"A":   PN = "1"  !CDS_PN = "1";
"B":   PN = "2"  !CDS_PN = "2";
BODY = "Q_RES","I161": #LOCATION = "R4536" !CDS_LOCATION = "R4536" &SEC = "1" #&CDS_SEC = "1";
"A":   PN = "1"  !CDS_PN = "1";
"B":   PN = "2"  !CDS_PN = "2";
BODY = "Q_RES","I165": #LOCATION = "R434" !CDS_LOCATION = "R434" &SEC = "1" #&CDS_SEC = "1";
"A":   PN = "1"  !CDS_PN = "1";
"B":   PN = "2"  !CDS_PN = "2";
BODY = "Q_RES","I167": #LOCATION = "R9275" !CDS_LOCATION = "R9275" &SEC = "1" #&CDS_SEC = "1";
"A":   PN = "1"  !CDS_PN = "1";
"B":   PN = "2"  !CDS_PN = "2";
BODY = "Q_RES","I168": #LOCATION = "R9276" !CDS_LOCATION = "R9276" &SEC = "1" #&CDS_SEC = "1";
"A":   PN = "1"  !CDS_PN = "1";
"B":   PN = "2"  !CDS_PN = "2";
BODY = "GENOA_SP5","I188": #LOCATION = "U25" !CDS_LOCATION = "U25" &SEC = "21" #&CDS_SEC = "21";
"AGPIO3||SPD_HOST_CTRL_L":   PN = "DE36"  !CDS_PN = "DE36";
"AGPIO4||SATA_ACT_L":   PN = "DF36"  !CDS_PN = "DF36";
"AGPIO5||DEVSLP0||SATA_ZP0_L":   PN = "DF40"  !CDS_PN = "DF40";
"AGPIO6||DEVSLP1||SATA_ZP1_L":   PN = "DE40"  !CDS_PN = "DE40";
"AGPIO7":   PN = "DH4"  !CDS_PN = "DH4";
"AGPIO21":   PN = "DF33"  !CDS_PN = "DF33";
"AGPIO22":   PN = "DE32"  !CDS_PN = "DE32";
"AGPIO87":   PN = "DG11"  !CDS_PN = "DG11";
"AGPIO88":   PN = "DJ29"  !CDS_PN = "DJ29";
"AGPIO104":   PN = "DH30"  !CDS_PN = "DH30";
"AGPIO105":   PN = "DE30"  !CDS_PN = "DE30";
"AGPIO106":   PN = "DF31"  !CDS_PN = "DF31";
"AGPIO107":   PN = "DG31"  !CDS_PN = "DG31";
"AGPIO109":   PN = "DG32"  !CDS_PN = "DG32";
"AGPIO115||CLK_REQ11_L":   PN = "DH16"  !CDS_PN = "DH16";
"AGPIO116||CLK_REQ12_L":   PN = "DH15"  !CDS_PN = "DH15";
"AGPIO256||SGPIO0_CLK":   PN = "A14"  !CDS_PN = "A14";
"AGPIO257||SGPIO1_CLK||CLK_REQ01_L":   PN = "C14"  !CDS_PN = "C14";
"AGPIO258||SGPIO2_CLK||CLK_REQ02_L":   PN = "A13"  !CDS_PN = "A13";
"AGPIO259||SGPIO3_CLK":   PN = "B16"  !CDS_PN = "B16";
"FORCE_SELFREFRESH":   PN = "B63"  !CDS_PN = "B63";
"GENINT_L||PM_INTR_L||UBM_CPRSNT_CHANGE_DET_L||AGPIO89":   PN = "DJ35"  !CDS_PN = "DJ35";
"GPP_CLK01N":   PN = "A7"  !CDS_PN = "A7";
"GPP_CLK01P":   PN = "A8"  !CDS_PN = "A8";
"GPP_CLK02N":   PN = "C6"  !CDS_PN = "C6";
"GPP_CLK02P":   PN = "B6"  !CDS_PN = "B6";
"GPP_CLK03N":   PN = "A11"  !CDS_PN = "A11";
"GPP_CLK03P":   PN = "A10"  !CDS_PN = "A10";
"GPP_CLK04N":   PN = "C12"  !CDS_PN = "C12";
"GPP_CLK04P":   PN = "B12"  !CDS_PN = "B12";
"GPP_CLK05N":   PN = "C9"  !CDS_PN = "C9";
"GPP_CLK05P":   PN = "B9"  !CDS_PN = "B9";
"GPP_CLK11N":   PN = "DJ42"  !CDS_PN = "DJ42";
"GPP_CLK11P":   PN = "DJ41"  !CDS_PN = "DJ41";
"GPP_CLK12N":   PN = "DJ44"  !CDS_PN = "DJ44";
"GPP_CLK12P":   PN = "DJ45"  !CDS_PN = "DJ45";
"GPP_CLK13N":   PN = "DJ54"  !CDS_PN = "DJ54";
"GPP_CLK13P":   PN = "DJ53"  !CDS_PN = "DJ53";
"GPP_CLK14N":   PN = "DJ47"  !CDS_PN = "DJ47";
"GPP_CLK14P":   PN = "DJ48"  !CDS_PN = "DJ48";
"GPP_CLK15N":   PN = "DJ50"  !CDS_PN = "DJ50";
"GPP_CLK15P":   PN = "DJ51"  !CDS_PN = "DJ51";
"I2C4_SCL||HP_SCL||UBM_SCL||AGPIO13":   PN = "DG12"  !CDS_PN = "DG12";
"I2C4_SDA||HP_SDA||UBM_SDA||AGPIO14":   PN = "DH12"  !CDS_PN = "DH12";
"I2C5_SCL||BMC_SCL||SMBUS1_SCL||AGPIO19":   PN = "DJ21"  !CDS_PN = "DJ21";
"I2C5_SDA||BMC_SDA||SMBUS1_SDA||AGPIO20":   PN = "DJ20"  !CDS_PN = "DJ20";
"I3C0_SCL||I2C0_SCL||SPD0_SCL||SMBUS0_SCL||AGPIO145":   PN = "A71"  !CDS_PN = "A71";
"I3C0_SDA||I2C0_SDA||SPD0_SDA||SMBUS0_SDA||AGPIO146":   PN = "B71"  !CDS_PN = "B71";
"I3C1_SCL||I2C1_SCL||SPD1_SCL||AGPIO147":   PN = "C7"  !CDS_PN = "C7";
"I3C1_SDA||I2C1_SDA||SPD1_SDA||AGPIO148":   PN = "A5"  !CDS_PN = "A5";
"I3C2_SCL||I2C2_SCL||SPD2_SCL||AGPIO149":   PN = "C72"  !CDS_PN = "C72";
"I3C2_SDA||I2C2_SDA||SPD2_SDA||AGPIO150":   PN = "B72"  !CDS_PN = "B72";
"I3C3_SCL||I2C3_SCL||SPD3_SCL||AGPIO151":   PN = "A4"  !CDS_PN = "A4";
"I3C3_SDA||I2C3_SDA||SPD3_SDA||AGPIO152":   PN = "B4"  !CDS_PN = "B4";
"NMI_SYNC_FLOOD_L":   PN = "DJ31"  !CDS_PN = "DJ31";
"NV_SAVE_L":   PN = "B64"  !CDS_PN = "B64";
"PCIE_RST0_L||AGPIO266":   PN = "D18"  !CDS_PN = "D18";
"PCIE_RST1_L||AGPIO26":   PN = "DG36"  !CDS_PN = "DG36";
"PWR_BTN_L||AGPIO0":   PN = "DH7"  !CDS_PN = "DH7";
"PWR_GOOD":   PN = "DJ8"  !CDS_PN = "DJ8";
"PWRGD_OUT||AGPIO12":   PN = "DH36"  !CDS_PN = "DH36";
"PWROK||SVI_RST_L":   PN = "D69"  !CDS_PN = "D69";
"REFCLK100SSC_N||GPP_CLK10N":   PN = "A20"  !CDS_PN = "A20";
"REFCLK100SSC_P||GPP_CLK10P":   PN = "A19"  !CDS_PN = "A19";
"RESET_L":   PN = "B67"  !CDS_PN = "B67";
"RSMRST_L":   PN = "DG10"  !CDS_PN = "DG10";
"RTCCLK":   PN = "DH9"  !CDS_PN = "DH9";
"SEC_SCL||AGPIO262":   PN = "B14"  !CDS_PN = "B14";
"SEC_SDA||AGPIO263":   PN = "D14"  !CDS_PN = "D14";
"SGPIO_DATAOUT||AGPIO260":   PN = "D15"  !CDS_PN = "D15";
"SGPIO_LOAD||AGPIO261":   PN = "B15"  !CDS_PN = "B15";
"SLP_S3_L":   PN = "DJ5"  !CDS_PN = "DJ5";
"SLP_S5_L":   PN = "DG4"  !CDS_PN = "DG4";
"SMERR_L||AGPIO24":   PN = "DJ11"  !CDS_PN = "DJ11";
"SYS_RESET_L||AGPIO1":   PN = "DH6"  !CDS_PN = "DH6";
"WAKE_L||AGPIO2":   PN = "DJ10"  !CDS_PN = "DJ10";
"X32K_X1":   PN = "DJ14"  !CDS_PN = "DJ14";
"X32K_X2":   PN = "DJ13"  !CDS_PN = "DJ13";
"X48M_X1":   PN = "DJ17"  !CDS_PN = "DJ17";
"X48M_X2":   PN = "DJ16"  !CDS_PN = "DJ16";
BODY = "Q_RES","I191": #LOCATION = "R4303" !CDS_LOCATION = "R4303" &SEC = "1" #&CDS_SEC = "1";
"A":   PN = "1"  !CDS_PN = "1";
"B":   PN = "2"  !CDS_PN = "2";
BODY = "Q_RES","I192": #LOCATION = "R4304" !CDS_LOCATION = "R4304" &SEC = "1" #&CDS_SEC = "1";
"A":   PN = "1"  !CDS_PN = "1";
"B":   PN = "2"  !CDS_PN = "2";
BODY = "Q_CAP","I194": #LOCATION = "C5023" !CDS_LOCATION = "C5023" &SEC = "1" #&CDS_SEC = "1";
"A":   PN = "1"  !CDS_PN = "1";
"B":   PN = "2"  !CDS_PN = "2";
BODY = "Q_RES","I195": #LOCATION = "R5102" !CDS_LOCATION = "R5102" &SEC = "1" #&CDS_SEC = "1";
"A":   PN = "1"  !CDS_PN = "1";
"B":   PN = "2"  !CDS_PN = "2";
BODY = "Q_RES","I206": #LOCATION = "R27" !CDS_LOCATION = "R27" &SEC = "1" #&CDS_SEC = "1";
"A":   PN = "1"  !CDS_PN = "1";
"B":   PN = "2"  !CDS_PN = "2";
BODY = "Q_RES","I207": #LOCATION = "R28" !CDS_LOCATION = "R28" &SEC = "1" #&CDS_SEC = "1";
"A":   PN = "1"  !CDS_PN = "1";
"B":   PN = "2"  !CDS_PN = "2";
BODY = "Q_RES","I208": #LOCATION = "R29" !CDS_LOCATION = "R29" &SEC = "1" #&CDS_SEC = "1";
"A":   PN = "1"  !CDS_PN = "1";
"B":   PN = "2"  !CDS_PN = "2";
BODY = "Q_RES","I209": #LOCATION = "R30" !CDS_LOCATION = "R30" &SEC = "1" #&CDS_SEC = "1";
"A":   PN = "1"  !CDS_PN = "1";
"B":   PN = "2"  !CDS_PN = "2";
BODY = "Q_RES","I210": #LOCATION = "R6081" !CDS_LOCATION = "R6081" &SEC = "1" #&CDS_SEC = "1";
"A":   PN = "1"  !CDS_PN = "1";
"B":   PN = "2"  !CDS_PN = "2";
BODY = "Q_RES","I212": #LOCATION = "R6082" !CDS_LOCATION = "R6082" &SEC = "1" #&CDS_SEC = "1";
"A":   PN = "1"  !CDS_PN = "1";
"B":   PN = "2"  !CDS_PN = "2";
BODY = "Q_RES","I213": #LOCATION = "R6083" !CDS_LOCATION = "R6083" &SEC = "1" #&CDS_SEC = "1";
"A":   PN = "1"  !CDS_PN = "1";
"B":   PN = "2"  !CDS_PN = "2";
BODY = "Q_RES","I214": #LOCATION = "R6084" !CDS_LOCATION = "R6084" &SEC = "1" #&CDS_SEC = "1";
"A":   PN = "1"  !CDS_PN = "1";
"B":   PN = "2"  !CDS_PN = "2";
BODY = "Q_RES","I221": #LOCATION = "R433" !CDS_LOCATION = "R433" #SEC = "1" !CDS_SEC = "1";
"A":   PN = "1"  !CDS_PN = "1";
"B":   PN = "2"  !CDS_PN = "2";
BODY = "Q_RES","I222": #LOCATION = "R438" !CDS_LOCATION = "R438" #SEC = "1" !CDS_SEC = "1";
"A":   PN = "1"  !CDS_PN = "1";
"B":   PN = "2"  !CDS_PN = "2";
BODY = "Q_RES","I224": #LOCATION = "R6502" !CDS_LOCATION = "R6502" &SEC = "1" #&CDS_SEC = "1";
"A":   PN = "1"  !CDS_PN = "1";
"B":   PN = "2"  !CDS_PN = "2";
BODY = "Q_RES","I228": #LOCATION = "R8306" !CDS_LOCATION = "R8306" #SEC = "1" !CDS_SEC = "1";
"A":   PN = "1"  !CDS_PN = "1";
"B":   PN = "2"  !CDS_PN = "2";
BODY = "Q_RES","I229": #LOCATION = "R8305" !CDS_LOCATION = "R8305" #SEC = "1" !CDS_SEC = "1";
"A":   PN = "1"  !CDS_PN = "1";
"B":   PN = "2"  !CDS_PN = "2";
BODY = "Q_CAP","I230": #LOCATION = "C215" !CDS_LOCATION = "C215" &SEC = "1" #&CDS_SEC = "1";
"A":   PN = "1"  !CDS_PN = "1";
"B":   PN = "2"  !CDS_PN = "2";
BODY = "Q_CAP","I231": #LOCATION = "C216" !CDS_LOCATION = "C216" &SEC = "1" #&CDS_SEC = "1";
"A":   PN = "1"  !CDS_PN = "1";
"B":   PN = "2"  !CDS_PN = "2";
BODY = "Q_CAP","I232": #LOCATION = "C213" !CDS_LOCATION = "C213" &SEC = "1" #&CDS_SEC = "1";
"A":   PN = "1"  !CDS_PN = "1";
"B":   PN = "2"  !CDS_PN = "2";
BODY = "Q_CAP","I233": #LOCATION = "C214" !CDS_LOCATION = "C214" &SEC = "1" #&CDS_SEC = "1";
"A":   PN = "1"  !CDS_PN = "1";
"B":   PN = "2"  !CDS_PN = "2";
DRAWING = "@t6g_mb_lib.t6g(sch_1):page368";
BODY = "MOSFET_NCH_DUAL","I3": #LOCATION = "Q144" !CDS_LOCATION = "Q144" &SEC = "1" #&CDS_SEC = "1";
"D1":   PN = "6"  !CDS_PN = "6";
"G1":   PN = "2"  !CDS_PN = "2";
"S1":   PN = "1"  !CDS_PN = "1";
BODY = "Q_RES","I5": #LOCATION = "R4604" !CDS_LOCATION = "R4604" &SEC = "1" #&CDS_SEC = "1";
"A":   PN = "1"  !CDS_PN = "1";
"B":   PN = "2"  !CDS_PN = "2";
BODY = "Q_RES","I7": #LOCATION = "R3048" !CDS_LOCATION = "R3048" &SEC = "1" #&CDS_SEC = "1";
"A":   PN = "1"  !CDS_PN = "1";
"B":   PN = "2"  !CDS_PN = "2";
BODY = "Q_RES","I8": #LOCATION = "R3047" !CDS_LOCATION = "R3047" &SEC = "1" #&CDS_SEC = "1";
"A":   PN = "1"  !CDS_PN = "1";
"B":   PN = "2"  !CDS_PN = "2";
BODY = "MOSFET_NCH_DUAL","I10": #LOCATION = "Q144" !CDS_LOCATION = "Q144" &SEC = "2" #&CDS_SEC = "2";
"D2":   PN = "3"  !CDS_PN = "3";
"G2":   PN = "5"  !CDS_PN = "5";
"S2":   PN = "4"  !CDS_PN = "4";
BODY = "Q_RES","I11": #LOCATION = "R4605" !CDS_LOCATION = "R4605" &SEC = "1" #&CDS_SEC = "1";
"A":   PN = "1"  !CDS_PN = "1";
"B":   PN = "2"  !CDS_PN = "2";
BODY = "Q_RES","I13": #LOCATION = "R9446" !CDS_LOCATION = "R9446" &SEC = "1" #&CDS_SEC = "1";
"A":   PN = "1"  !CDS_PN = "1";
"B":   PN = "2"  !CDS_PN = "2";
DRAWING = "@t6g_mb_lib.t6g(sch_1):page254";
BODY = "Q_LED","I3": #LOCATION = "D99" !CDS_LOCATION = "D99" &SEC = "1" #&CDS_SEC = "1";
"A":   PN = "A"  !CDS_PN = "A";
"C":   PN = "C"  !CDS_PN = "C";
BODY = "Q_RES","I8": #LOCATION = "R3100" !CDS_LOCATION = "R3100" &SEC = "1" #&CDS_SEC = "1";
"A":   PN = "1"  !CDS_PN = "1";
"B":   PN = "2"  !CDS_PN = "2";
BODY = "Q_RES","I9": #LOCATION = "R3102" !CDS_LOCATION = "R3102" &SEC = "1" #&CDS_SEC = "1";
"A":   PN = "1"  !CDS_PN = "1";
"B":   PN = "2"  !CDS_PN = "2";
BODY = "Q_LED","I14": #LOCATION = "D96" !CDS_LOCATION = "D96" &SEC = "1" #&CDS_SEC = "1";
"A":   PN = "A"  !CDS_PN = "A";
"C":   PN = "C"  !CDS_PN = "C";
BODY = "Q_RES","I15": #LOCATION = "R3075" !CDS_LOCATION = "R3075" &SEC = "1" #&CDS_SEC = "1";
"A":   PN = "1"  !CDS_PN = "1";
"B":   PN = "2"  !CDS_PN = "2";
BODY = "Q_LED","I17": #LOCATION = "D98" !CDS_LOCATION = "D98" &SEC = "1" #&CDS_SEC = "1";
"A":   PN = "A"  !CDS_PN = "A";
"C":   PN = "C"  !CDS_PN = "C";
BODY = "MOSFET_NCH_DUAL","I18": #LOCATION = "Q78" !CDS_LOCATION = "Q78" #SEC = "2" !CDS_SEC = "2";
"D2":   PN = "3"  !CDS_PN = "3";
"G2":   PN = "5"  !CDS_PN = "5";
"S2":   PN = "4"  !CDS_PN = "4";
BODY = "Q_RES","I21": #LOCATION = "R3071" !CDS_LOCATION = "R3071" &SEC = "1" #&CDS_SEC = "1";
"A":   PN = "1"  !CDS_PN = "1";
"B":   PN = "2"  !CDS_PN = "2";
BODY = "Q_LED","I23": #LOCATION = "D91" !CDS_LOCATION = "D91" &SEC = "1" #&CDS_SEC = "1";
"A":   PN = "A"  !CDS_PN = "A";
"C":   PN = "C"  !CDS_PN = "C";
BODY = "MOSFET_NCH_DUAL","I24": #LOCATION = "Q78" !CDS_LOCATION = "Q78" &SEC = "1" #&CDS_SEC = "1";
"D1":   PN = "6"  !CDS_PN = "6";
"G1":   PN = "2"  !CDS_PN = "2";
"S1":   PN = "1"  !CDS_PN = "1";
BODY = "Q_RES","I32": #LOCATION = "R3069" !CDS_LOCATION = "R3069" &SEC = "1" #&CDS_SEC = "1";
"A":   PN = "1"  !CDS_PN = "1";
"B":   PN = "2"  !CDS_PN = "2";
BODY = "Q_LED","I33": #LOCATION = "D88" !CDS_LOCATION = "D88" &SEC = "1" #&CDS_SEC = "1";
"A":   PN = "A"  !CDS_PN = "A";
"C":   PN = "C"  !CDS_PN = "C";
BODY = "MOSFET_NCH_DUAL","I35": #LOCATION = "Q87" !CDS_LOCATION = "Q87" #SEC = "2" !CDS_SEC = "2";
"D2":   PN = "3"  !CDS_PN = "3";
"G2":   PN = "5"  !CDS_PN = "5";
"S2":   PN = "4"  !CDS_PN = "4";
BODY = "MOSFET_NCH_DUAL","I38": #LOCATION = "Q87" !CDS_LOCATION = "Q87" &SEC = "1" #&CDS_SEC = "1";
"D1":   PN = "6"  !CDS_PN = "6";
"G1":   PN = "2"  !CDS_PN = "2";
"S1":   PN = "1"  !CDS_PN = "1";
BODY = "Q_LED","I40": #LOCATION = "D93" !CDS_LOCATION = "D93" &SEC = "1" #&CDS_SEC = "1";
"A":   PN = "A"  !CDS_PN = "A";
"C":   PN = "C"  !CDS_PN = "C";
BODY = "Q_RES","I41": #LOCATION = "R3074" !CDS_LOCATION = "R3074" &SEC = "1" #&CDS_SEC = "1";
"A":   PN = "1"  !CDS_PN = "1";
"B":   PN = "2"  !CDS_PN = "2";
BODY = "Q_LED","I43": #LOCATION = "D6000" !CDS_LOCATION = "D6000" &SEC = "1" #&CDS_SEC = "1";
"A":   PN = "A"  !CDS_PN = "A";
"C":   PN = "C"  !CDS_PN = "C";
BODY = "Q_RES","I45": #LOCATION = "R6246" !CDS_LOCATION = "R6246" &SEC = "1" #&CDS_SEC = "1";
"A":   PN = "1"  !CDS_PN = "1";
"B":   PN = "2"  !CDS_PN = "2";
BODY = "MOSFET_NCH_DUAL","I47": #LOCATION = "Q6000" !CDS_LOCATION = "Q6000" &SEC = "1" #&CDS_SEC = "1";
"D1":   PN = "6"  !CDS_PN = "6";
"G1":   PN = "2"  !CDS_PN = "2";
"S1":   PN = "1"  !CDS_PN = "1";
DRAWING = "@t6g_mb_lib.t6g(sch_1):page79";
BODY = "Q_RES","I16": #LOCATION = "R160" !CDS_LOCATION = "R160" &SEC = "1" #&CDS_SEC = "1";
"A":   PN = "1"  !CDS_PN = "1";
"B":   PN = "2"  !CDS_PN = "2";
BODY = "Q_RES","I17": #LOCATION = "R992" !CDS_LOCATION = "R992" &SEC = "1" #&CDS_SEC = "1";
"A":   PN = "1"  !CDS_PN = "1";
"B":   PN = "2"  !CDS_PN = "2";
BODY = "Q_RES","I18": #LOCATION = "R493" !CDS_LOCATION = "R493" &SEC = "1" #&CDS_SEC = "1";
"A":   PN = "1"  !CDS_PN = "1";
"B":   PN = "2"  !CDS_PN = "2";
BODY = "Q_RES","I19": #LOCATION = "R70" !CDS_LOCATION = "R70" &SEC = "1" #&CDS_SEC = "1";
"A":   PN = "1"  !CDS_PN = "1";
"B":   PN = "2"  !CDS_PN = "2";
BODY = "Q_RES","I20": #LOCATION = "R6039" !CDS_LOCATION = "R6039" &SEC = "1" #&CDS_SEC = "1";
"A":   PN = "1"  !CDS_PN = "1";
"B":   PN = "2"  !CDS_PN = "2";
BODY = "Q_RES","I21": #LOCATION = "R6038" !CDS_LOCATION = "R6038" &SEC = "1" #&CDS_SEC = "1";
"A":   PN = "1"  !CDS_PN = "1";
"B":   PN = "2"  !CDS_PN = "2";
BODY = "Q_RES","I23": #LOCATION = "R23" !CDS_LOCATION = "R23" &SEC = "1" #&CDS_SEC = "1";
"A":   PN = "1"  !CDS_PN = "1";
"B":   PN = "2"  !CDS_PN = "2";
BODY = "Q_RES","I24": #LOCATION = "R168" !CDS_LOCATION = "R168" &SEC = "1" #&CDS_SEC = "1";
"A":   PN = "1"  !CDS_PN = "1";
"B":   PN = "2"  !CDS_PN = "2";
BODY = "Q_RES","I43": #LOCATION = "R172" !CDS_LOCATION = "R172" &SEC = "1" #&CDS_SEC = "1";
"A":   PN = "1"  !CDS_PN = "1";
"B":   PN = "2"  !CDS_PN = "2";
BODY = "Q_RES","I44": #LOCATION = "R58" !CDS_LOCATION = "R58" &SEC = "1" #&CDS_SEC = "1";
"A":   PN = "1"  !CDS_PN = "1";
"B":   PN = "2"  !CDS_PN = "2";
BODY = "Q_RES","I45": #LOCATION = "R167" !CDS_LOCATION = "R167" &SEC = "1" #&CDS_SEC = "1";
"A":   PN = "1"  !CDS_PN = "1";
"B":   PN = "2"  !CDS_PN = "2";
BODY = "Q_RES","I46": #LOCATION = "R49" !CDS_LOCATION = "R49" &SEC = "1" #&CDS_SEC = "1";
"A":   PN = "1"  !CDS_PN = "1";
"B":   PN = "2"  !CDS_PN = "2";
BODY = "Q_RES","I47": #LOCATION = "R165" !CDS_LOCATION = "R165" &SEC = "1" #&CDS_SEC = "1";
"A":   PN = "1"  !CDS_PN = "1";
"B":   PN = "2"  !CDS_PN = "2";
BODY = "Q_RES","I48": #LOCATION = "R169" !CDS_LOCATION = "R169" &SEC = "1" #&CDS_SEC = "1";
"A":   PN = "1"  !CDS_PN = "1";
"B":   PN = "2"  !CDS_PN = "2";
BODY = "Q_RES","I49": #LOCATION = "R50" !CDS_LOCATION = "R50" &SEC = "1" #&CDS_SEC = "1";
"A":   PN = "1"  !CDS_PN = "1";
"B":   PN = "2"  !CDS_PN = "2";
BODY = "Q_RES","I50": #LOCATION = "R164" !CDS_LOCATION = "R164" &SEC = "1" #&CDS_SEC = "1";
"A":   PN = "1"  !CDS_PN = "1";
"B":   PN = "2"  !CDS_PN = "2";
BODY = "Q_RES","I51": #LOCATION = "R166" !CDS_LOCATION = "R166" &SEC = "1" #&CDS_SEC = "1";
"A":   PN = "1"  !CDS_PN = "1";
"B":   PN = "2"  !CDS_PN = "2";
BODY = "Q_RES","I52": #LOCATION = "R171" !CDS_LOCATION = "R171" &SEC = "1" #&CDS_SEC = "1";
"A":   PN = "1"  !CDS_PN = "1";
"B":   PN = "2"  !CDS_PN = "2";
BODY = "Q_RES","I53": #LOCATION = "R170" !CDS_LOCATION = "R170" &SEC = "1" #&CDS_SEC = "1";
"A":   PN = "1"  !CDS_PN = "1";
"B":   PN = "2"  !CDS_PN = "2";
BODY = "Q_RES","I54": #LOCATION = "R163" !CDS_LOCATION = "R163" &SEC = "1" #&CDS_SEC = "1";
"A":   PN = "1"  !CDS_PN = "1";
"B":   PN = "2"  !CDS_PN = "2";
BODY = "Q_RES","I64": #LOCATION = "R6030" !CDS_LOCATION = "R6030" &SEC = "1" #&CDS_SEC = "1";
"A":   PN = "1"  !CDS_PN = "1";
"B":   PN = "2"  !CDS_PN = "2";
BODY = "Q_RES","I79": #LOCATION = "R63" !CDS_LOCATION = "R63" &SEC = "1" #&CDS_SEC = "1";
"A":   PN = "1"  !CDS_PN = "1";
"B":   PN = "2"  !CDS_PN = "2";
BODY = "Q_RES","I80": #LOCATION = "R211" !CDS_LOCATION = "R211" &SEC = "1" #&CDS_SEC = "1";
"A":   PN = "1"  !CDS_PN = "1";
"B":   PN = "2"  !CDS_PN = "2";
BODY = "Q_RES","I81": #LOCATION = "R210" !CDS_LOCATION = "R210" &SEC = "1" #&CDS_SEC = "1";
"A":   PN = "1"  !CDS_PN = "1";
"B":   PN = "2"  !CDS_PN = "2";
BODY = "Q_RES","I82": #LOCATION = "R56" !CDS_LOCATION = "R56" &SEC = "1" #&CDS_SEC = "1";
"A":   PN = "1"  !CDS_PN = "1";
"B":   PN = "2"  !CDS_PN = "2";
BODY = "LCMXO3LF9400C5BG484C","I25": #LOCATION = "U18" !CDS_LOCATION = "U18" &SEC = "4" #&CDS_SEC = "4";
"PT15C||TDO":   PN = "E8"  !CDS_PN = "E8";
"PT15D||TDI":   PN = "E9"  !CDS_PN = "E9";
"PT22C||TCK":   PN = "D10"  !CDS_PN = "D10";
"PT22D||TMS":   PN = "C10"  !CDS_PN = "C10";
"PT31C||JTAGENB":   PN = "E14"  !CDS_PN = "E14";
"PT31D||PROGRAMN":   PN = "E15"  !CDS_PN = "E15";
"PT44C||INITN":   PN = "F16"  !CDS_PN = "F16";
"PT44D||DONE":   PN = "E17"  !CDS_PN = "E17";
BODY = "Q_RES","I55": #LOCATION = "R6031" !CDS_LOCATION = "R6031" &SEC = "1" #&CDS_SEC = "1";
"A":   PN = "1"  !CDS_PN = "1";
"B":   PN = "2"  !CDS_PN = "2";
BODY = "Q_RES","I65": #LOCATION = "R6029" !CDS_LOCATION = "R6029" &SEC = "1" #&CDS_SEC = "1";
"A":   PN = "1"  !CDS_PN = "1";
"B":   PN = "2"  !CDS_PN = "2";
BODY = "Q_RES","I83": #LOCATION = "R51" !CDS_LOCATION = "R51" &SEC = "1" #&CDS_SEC = "1";
"A":   PN = "1"  !CDS_PN = "1";
"B":   PN = "2"  !CDS_PN = "2";
BODY = "LCMXO3LF9400C5BG484C","I94": #LOCATION = "U18" !CDS_LOCATION = "U18" &SEC = "3" #&CDS_SEC = "3";
"PT9A||L_GPLLT":   PN = "B1"  !CDS_PN = "B1";
"PT9B||L_GPLLC":   PN = "A2"  !CDS_PN = "A2";
"PT9C":   PN = "E6"  !CDS_PN = "E6";
"PT9D":   PN = "F7"  !CDS_PN = "F7";
"PT10A":   PN = "B2"  !CDS_PN = "B2";
"PT10B":   PN = "A3"  !CDS_PN = "A3";
"PT10C":   PN = "C3"  !CDS_PN = "C3";
"PT10D":   PN = "C4"  !CDS_PN = "C4";
"PT11A":   PN = "B3"  !CDS_PN = "B3";
"PT11B":   PN = "A4"  !CDS_PN = "A4";
"PT11C":   PN = "F8"  !CDS_PN = "F8";
"PT11D":   PN = "G8"  !CDS_PN = "G8";
"PT12A":   PN = "B4"  !CDS_PN = "B4";
"PT12B":   PN = "A5"  !CDS_PN = "A5";
"PT12C":   PN = "D5"  !CDS_PN = "D5";
"PT12D":   PN = "C5"  !CDS_PN = "C5";
"PT13A":   PN = "B5"  !CDS_PN = "B5";
"PT13B":   PN = "A6"  !CDS_PN = "A6";
"PT13C":   PN = "D6"  !CDS_PN = "D6";
"PT13D":   PN = "E7"  !CDS_PN = "E7";
"PT14A":   PN = "B6"  !CDS_PN = "B6";
"PT14B":   PN = "A7"  !CDS_PN = "A7";
"PT14C":   PN = "C6"  !CDS_PN = "C6";
"PT14D":   PN = "D7"  !CDS_PN = "D7";
"PT15A":   PN = "C8"  !CDS_PN = "C8";
"PT15B":   PN = "D8"  !CDS_PN = "D8";
"PT20A":   PN = "B8"  !CDS_PN = "B8";
"PT20B":   PN = "A8"  !CDS_PN = "A8";
"PT20C":   PN = "C9"  !CDS_PN = "C9";
"PT20D":   PN = "D9"  !CDS_PN = "D9";
"PT21A":   PN = "B9"  !CDS_PN = "B9";
"PT21B":   PN = "A9"  !CDS_PN = "A9";
"PT21C":   PN = "F9"  !CDS_PN = "F9";
"PT21D":   PN = "G9"  !CDS_PN = "G9";
"PT22A":   PN = "F10"  !CDS_PN = "F10";
"PT22B":   PN = "E10"  !CDS_PN = "E10";
"PT23A||PCLKT0_1":   PN = "B10"  !CDS_PN = "B10";
"PT23B||PCLKC0_1":   PN = "A10"  !CDS_PN = "A10";
"PT23C":   PN = "G11"  !CDS_PN = "G11";
"PT23D":   PN = "F11"  !CDS_PN = "F11";
"PT24A":   PN = "B11"  !CDS_PN = "B11";
"PT24B":   PN = "A11"  !CDS_PN = "A11";
"PT24C":   PN = "E11"  !CDS_PN = "E11";
"PT24D":   PN = "D11"  !CDS_PN = "D11";
"PT27A":   PN = "D12"  !CDS_PN = "D12";
"PT27B":   PN = "E12"  !CDS_PN = "E12";
"PT27C||SCL||PCLKT0_0":   PN = "B12"  !CDS_PN = "B12";
"PT27D||SDA||PCLKC0_0":   PN = "A12"  !CDS_PN = "A12";
"PT28A":   PN = "G12"  !CDS_PN = "G12";
"PT28B":   PN = "F12"  !CDS_PN = "F12";
"PT28C":   PN = "E13"  !CDS_PN = "E13";
"PT28D":   PN = "F13"  !CDS_PN = "F13";
"PT29A":   PN = "A13"  !CDS_PN = "A13";
"PT29B":   PN = "B13"  !CDS_PN = "B13";
"PT29C":   PN = "C13"  !CDS_PN = "C13";
"PT29D":   PN = "D13"  !CDS_PN = "D13";
"PT30A":   PN = "A14"  !CDS_PN = "A14";
"PT30B":   PN = "B14"  !CDS_PN = "B14";
"PT30C":   PN = "C14"  !CDS_PN = "C14";
"PT30D":   PN = "D14"  !CDS_PN = "D14";
"PT31A":   PN = "G14"  !CDS_PN = "G14";
"PT31B":   PN = "F14"  !CDS_PN = "F14";
"PT38A":   PN = "A15"  !CDS_PN = "A15";
"PT38B":   PN = "B15"  !CDS_PN = "B15";
"PT38C":   PN = "C15"  !CDS_PN = "C15";
"PT38D":   PN = "D15"  !CDS_PN = "D15";
"PT39A":   PN = "A16"  !CDS_PN = "A16";
"PT39B":   PN = "B17"  !CDS_PN = "B17";
"PT39C":   PN = "C17"  !CDS_PN = "C17";
"PT39D":   PN = "D16"  !CDS_PN = "D16";
"PT40A":   PN = "A17"  !CDS_PN = "A17";
"PT40B":   PN = "B18"  !CDS_PN = "B18";
"PT40C":   PN = "E16"  !CDS_PN = "E16";
"PT40D":   PN = "D17"  !CDS_PN = "D17";
"PT41A":   PN = "A18"  !CDS_PN = "A18";
"PT41B":   PN = "B19"  !CDS_PN = "B19";
"PT41C":   PN = "C18"  !CDS_PN = "C18";
"PT41D":   PN = "D18"  !CDS_PN = "D18";
"PT42A":   PN = "A19"  !CDS_PN = "A19";
"PT42B":   PN = "B20"  !CDS_PN = "B20";
"PT42C":   PN = "F15"  !CDS_PN = "F15";
"PT42D":   PN = "G15"  !CDS_PN = "G15";
"PT43A||R_GPLLT":   PN = "A20"  !CDS_PN = "A20";
"PT43B||R_GPLLC":   PN = "B21"  !CDS_PN = "B21";
"PT43C":   PN = "C19"  !CDS_PN = "C19";
"PT43D":   PN = "C20"  !CDS_PN = "C20";
"PT44A||R_GPLLT":   PN = "A21"  !CDS_PN = "A21";
"PT44B||R_GPLLC":   PN = "B22"  !CDS_PN = "B22";
BODY = "Q_RES","I112": #LOCATION = "R6095" !CDS_LOCATION = "R6095" &SEC = "1" #&CDS_SEC = "1";
"A":   PN = "1"  !CDS_PN = "1";
"B":   PN = "2"  !CDS_PN = "2";
BODY = "Q_RES","I115": #LOCATION = "R6096" !CDS_LOCATION = "R6096" &SEC = "1" #&CDS_SEC = "1";
"A":   PN = "1"  !CDS_PN = "1";
"B":   PN = "2"  !CDS_PN = "2";
BODY = "Q_RES","I121": #LOCATION = "R4145" !CDS_LOCATION = "R4145" &SEC = "1" #&CDS_SEC = "1";
"A":   PN = "1"  !CDS_PN = "1";
"B":   PN = "2"  !CDS_PN = "2";
BODY = "Q_RES","I122": #LOCATION = "R4146" !CDS_LOCATION = "R4146" &SEC = "1" #&CDS_SEC = "1";
"A":   PN = "1"  !CDS_PN = "1";
"B":   PN = "2"  !CDS_PN = "2";
BODY = "Q_RES","I128": #LOCATION = "R6094" !CDS_LOCATION = "R6094" &SEC = "1" #&CDS_SEC = "1";
"A":   PN = "1"  !CDS_PN = "1";
"B":   PN = "2"  !CDS_PN = "2";
BODY = "Q_RES","I129": #LOCATION = "R6116" !CDS_LOCATION = "R6116" &SEC = "1" #&CDS_SEC = "1";
"A":   PN = "1"  !CDS_PN = "1";
"B":   PN = "2"  !CDS_PN = "2";
BODY = "Q_RES","I131": #LOCATION = "R6117" !CDS_LOCATION = "R6117" &SEC = "1" #&CDS_SEC = "1";
"A":   PN = "1"  !CDS_PN = "1";
"B":   PN = "2"  !CDS_PN = "2";
BODY = "Q_RES","I139": #LOCATION = "R407" !CDS_LOCATION = "R407" &SEC = "1" #&CDS_SEC = "1";
"A":   PN = "1"  !CDS_PN = "1";
"B":   PN = "2"  !CDS_PN = "2";
BODY = "Q_RES","I141": #LOCATION = "R419" !CDS_LOCATION = "R419" &SEC = "1" #&CDS_SEC = "1";
"A":   PN = "1"  !CDS_PN = "1";
"B":   PN = "2"  !CDS_PN = "2";
BODY = "Q_RES","I144": #LOCATION = "R439" !CDS_LOCATION = "R439" #SEC = "1" !CDS_SEC = "1";
"A":   PN = "1"  !CDS_PN = "1";
"B":   PN = "2"  !CDS_PN = "2";
BODY = "Q_RES","I146": #LOCATION = "R6850" !CDS_LOCATION = "R6850" &SEC = "1" #&CDS_SEC = "1";
"A":   PN = "1"  !CDS_PN = "1";
"B":   PN = "2"  !CDS_PN = "2";
BODY = "Q_RES","I147": #LOCATION = "R6851" !CDS_LOCATION = "R6851" &SEC = "1" #&CDS_SEC = "1";
"A":   PN = "1"  !CDS_PN = "1";
"B":   PN = "2"  !CDS_PN = "2";
BODY = "Q_RES","I153": #LOCATION = "R152" !CDS_LOCATION = "R152" &SEC = "1" #&CDS_SEC = "1";
"A":   PN = "1"  !CDS_PN = "1";
"B":   PN = "2"  !CDS_PN = "2";
BODY = "Q_RES","I155": #LOCATION = "R1179" !CDS_LOCATION = "R1179" &SEC = "1" #&CDS_SEC = "1";
"A":   PN = "1"  !CDS_PN = "1";
"B":   PN = "2"  !CDS_PN = "2";
DRAWING = "@t6g_mb_lib.t6g(sch_1):page82";
BODY = "Q_RES","I35": #LOCATION = "R638" !CDS_LOCATION = "R638" &SEC = "1" #&CDS_SEC = "1";
"A":   PN = "1"  !CDS_PN = "1";
"B":   PN = "2"  !CDS_PN = "2";
BODY = "Q_RES","I36": #LOCATION = "R1195" !CDS_LOCATION = "R1195" &SEC = "1" #&CDS_SEC = "1";
"A":   PN = "1"  !CDS_PN = "1";
"B":   PN = "2"  !CDS_PN = "2";
BODY = "Q_RES","I39": #LOCATION = "R6061" !CDS_LOCATION = "R6061" &SEC = "1" #&CDS_SEC = "1";
"A":   PN = "1"  !CDS_PN = "1";
"B":   PN = "2"  !CDS_PN = "2";
BODY = "Q_RES","I40": #LOCATION = "R6062" !CDS_LOCATION = "R6062" &SEC = "1" #&CDS_SEC = "1";
"A":   PN = "1"  !CDS_PN = "1";
"B":   PN = "2"  !CDS_PN = "2";
BODY = "Q_RES","I53": #LOCATION = "R993" !CDS_LOCATION = "R993" &SEC = "1" #&CDS_SEC = "1";
"A":   PN = "1"  !CDS_PN = "1";
"B":   PN = "2"  !CDS_PN = "2";
BODY = "Q_RES","I54": #LOCATION = "R1314" !CDS_LOCATION = "R1314" &SEC = "1" #&CDS_SEC = "1";
"A":   PN = "1"  !CDS_PN = "1";
"B":   PN = "2"  !CDS_PN = "2";
BODY = "Q_RES","I56": #LOCATION = "R1527" !CDS_LOCATION = "R1527" &SEC = "1" #&CDS_SEC = "1";
"A":   PN = "1"  !CDS_PN = "1";
"B":   PN = "2"  !CDS_PN = "2";
BODY = "Q_RES","I57": #LOCATION = "R1189" !CDS_LOCATION = "R1189" &SEC = "1" #&CDS_SEC = "1";
"A":   PN = "1"  !CDS_PN = "1";
"B":   PN = "2"  !CDS_PN = "2";
BODY = "Q_RES","I58": #LOCATION = "R1190" !CDS_LOCATION = "R1190" &SEC = "1" #&CDS_SEC = "1";
"A":   PN = "1"  !CDS_PN = "1";
"B":   PN = "2"  !CDS_PN = "2";
BODY = "Q_RES","I59": #LOCATION = "R1187" !CDS_LOCATION = "R1187" &SEC = "1" #&CDS_SEC = "1";
"A":   PN = "1"  !CDS_PN = "1";
"B":   PN = "2"  !CDS_PN = "2";
BODY = "Q_RES","I60": #LOCATION = "R1186" !CDS_LOCATION = "R1186" &SEC = "1" #&CDS_SEC = "1";
"A":   PN = "1"  !CDS_PN = "1";
"B":   PN = "2"  !CDS_PN = "2";
BODY = "Q_RES","I61": #LOCATION = "R1188" !CDS_LOCATION = "R1188" &SEC = "1" #&CDS_SEC = "1";
"A":   PN = "1"  !CDS_PN = "1";
"B":   PN = "2"  !CDS_PN = "2";
BODY = "Q_RES","I62": #LOCATION = "R1185" !CDS_LOCATION = "R1185" &SEC = "1" #&CDS_SEC = "1";
"A":   PN = "1"  !CDS_PN = "1";
"B":   PN = "2"  !CDS_PN = "2";
BODY = "Q_RES","I76": #LOCATION = "R1286" !CDS_LOCATION = "R1286" &SEC = "1" #&CDS_SEC = "1";
"A":   PN = "1"  !CDS_PN = "1";
"B":   PN = "2"  !CDS_PN = "2";
BODY = "Q_RES","I77": #LOCATION = "R1285" !CDS_LOCATION = "R1285" &SEC = "1" #&CDS_SEC = "1";
"A":   PN = "1"  !CDS_PN = "1";
"B":   PN = "2"  !CDS_PN = "2";
BODY = "Q_CAP","I79": #LOCATION = "C1134" !CDS_LOCATION = "C1134" &SEC = "1" #&CDS_SEC = "1";
"A":   PN = "1"  !CDS_PN = "1";
"B":   PN = "2"  !CDS_PN = "2";
BODY = "Q_CAP","I80": #LOCATION = "C1132" !CDS_LOCATION = "C1132" &SEC = "1" #&CDS_SEC = "1";
"A":   PN = "1"  !CDS_PN = "1";
"B":   PN = "2"  !CDS_PN = "2";
BODY = "Q_CAP","I82": #LOCATION = "C1131" !CDS_LOCATION = "C1131" &SEC = "1" #&CDS_SEC = "1";
"A":   PN = "1"  !CDS_PN = "1";
"B":   PN = "2"  !CDS_PN = "2";
BODY = "Q_CAP","I83": #LOCATION = "C352" !CDS_LOCATION = "C352" &SEC = "1" #&CDS_SEC = "1";
"A":   PN = "1"  !CDS_PN = "1";
"B":   PN = "2"  !CDS_PN = "2";
BODY = "Q_CAP","I84": #LOCATION = "C1128" !CDS_LOCATION = "C1128" &SEC = "1" #&CDS_SEC = "1";
"A":   PN = "1"  !CDS_PN = "1";
"B":   PN = "2"  !CDS_PN = "2";
BODY = "Q_CAP","I85": #LOCATION = "C1129" !CDS_LOCATION = "C1129" &SEC = "1" #&CDS_SEC = "1";
"A":   PN = "1"  !CDS_PN = "1";
"B":   PN = "2"  !CDS_PN = "2";
BODY = "Q_CAP","I86": #LOCATION = "C1126" !CDS_LOCATION = "C1126" &SEC = "1" #&CDS_SEC = "1";
"A":   PN = "1"  !CDS_PN = "1";
"B":   PN = "2"  !CDS_PN = "2";
BODY = "Q_CAP","I87": #LOCATION = "C1127" !CDS_LOCATION = "C1127" &SEC = "1" #&CDS_SEC = "1";
"A":   PN = "1"  !CDS_PN = "1";
"B":   PN = "2"  !CDS_PN = "2";
BODY = "Q_RES","I97": #LOCATION = "R25" !CDS_LOCATION = "R25" &SEC = "1" #&CDS_SEC = "1";
"A":   PN = "1"  !CDS_PN = "1";
"B":   PN = "2"  !CDS_PN = "2";
BODY = "Q_CAP","I105": #LOCATION = "C358" !CDS_LOCATION = "C358" &SEC = "1" #&CDS_SEC = "1";
"A":   PN = "1"  !CDS_PN = "1";
"B":   PN = "2"  !CDS_PN = "2";
BODY = "Q_CAP","I106": #LOCATION = "C357" !CDS_LOCATION = "C357" &SEC = "1" #&CDS_SEC = "1";
"A":   PN = "1"  !CDS_PN = "1";
"B":   PN = "2"  !CDS_PN = "2";
BODY = "Q_CAP","I107": #LOCATION = "C356" !CDS_LOCATION = "C356" &SEC = "1" #&CDS_SEC = "1";
"A":   PN = "1"  !CDS_PN = "1";
"B":   PN = "2"  !CDS_PN = "2";
BODY = "Q_CAP","I108": #LOCATION = "C355" !CDS_LOCATION = "C355" &SEC = "1" #&CDS_SEC = "1";
"A":   PN = "1"  !CDS_PN = "1";
"B":   PN = "2"  !CDS_PN = "2";
BODY = "Q_CAP","I109": #LOCATION = "C1176" !CDS_LOCATION = "C1176" &SEC = "1" #&CDS_SEC = "1";
"A":   PN = "1"  !CDS_PN = "1";
"B":   PN = "2"  !CDS_PN = "2";
BODY = "Q_CAP","I110": #LOCATION = "C1175" !CDS_LOCATION = "C1175" &SEC = "1" #&CDS_SEC = "1";
"A":   PN = "1"  !CDS_PN = "1";
"B":   PN = "2"  !CDS_PN = "2";
BODY = "Q_CAP","I111": #LOCATION = "C1174" !CDS_LOCATION = "C1174" &SEC = "1" #&CDS_SEC = "1";
"A":   PN = "1"  !CDS_PN = "1";
"B":   PN = "2"  !CDS_PN = "2";
BODY = "Q_CAP","I112": #LOCATION = "C1172" !CDS_LOCATION = "C1172" &SEC = "1" #&CDS_SEC = "1";
"A":   PN = "1"  !CDS_PN = "1";
"B":   PN = "2"  !CDS_PN = "2";
BODY = "Q_CAP","I113": #LOCATION = "C1173" !CDS_LOCATION = "C1173" &SEC = "1" #&CDS_SEC = "1";
"A":   PN = "1"  !CDS_PN = "1";
"B":   PN = "2"  !CDS_PN = "2";
BODY = "Q_CAP","I114": #LOCATION = "C1171" !CDS_LOCATION = "C1171" &SEC = "1" #&CDS_SEC = "1";
"A":   PN = "1"  !CDS_PN = "1";
"B":   PN = "2"  !CDS_PN = "2";
BODY = "Q_RES","I120": #LOCATION = "R804" !CDS_LOCATION = "R804" &SEC = "1" #&CDS_SEC = "1";
"A":   PN = "1"  !CDS_PN = "1";
"B":   PN = "2"  !CDS_PN = "2";
BODY = "Q_RES","I126": #LOCATION = "R18" !CDS_LOCATION = "R18" &SEC = "1" #&CDS_SEC = "1";
"A":   PN = "1"  !CDS_PN = "1";
"B":   PN = "2"  !CDS_PN = "2";
BODY = "Q_RES","I128": #LOCATION = "R19" !CDS_LOCATION = "R19" &SEC = "1" #&CDS_SEC = "1";
"A":   PN = "1"  !CDS_PN = "1";
"B":   PN = "2"  !CDS_PN = "2";
BODY = "Q_RES","I33": #LOCATION = "R639" !CDS_LOCATION = "R639" &SEC = "1" #&CDS_SEC = "1";
"A":   PN = "1"  !CDS_PN = "1";
"B":   PN = "2"  !CDS_PN = "2";
BODY = "Q_RES","I38": #LOCATION = "R1071" !CDS_LOCATION = "R1071" &SEC = "1" #&CDS_SEC = "1";
"A":   PN = "1"  !CDS_PN = "1";
"B":   PN = "2"  !CDS_PN = "2";
BODY = "Q_RES","I41": #LOCATION = "R757" !CDS_LOCATION = "R757" &SEC = "1" #&CDS_SEC = "1";
"A":   PN = "1"  !CDS_PN = "1";
"B":   PN = "2"  !CDS_PN = "2";
BODY = "Q_RES","I64": #LOCATION = "R654" !CDS_LOCATION = "R654" &SEC = "1" #&CDS_SEC = "1";
"A":   PN = "1"  !CDS_PN = "1";
"B":   PN = "2"  !CDS_PN = "2";
BODY = "Q_RES","I72": #LOCATION = "R1351" !CDS_LOCATION = "R1351" &SEC = "1" #&CDS_SEC = "1";
"A":   PN = "1"  !CDS_PN = "1";
"B":   PN = "2"  !CDS_PN = "2";
BODY = "Q_RES","I73": #LOCATION = "R1288" !CDS_LOCATION = "R1288" &SEC = "1" #&CDS_SEC = "1";
"A":   PN = "1"  !CDS_PN = "1";
"B":   PN = "2"  !CDS_PN = "2";
BODY = "Q_RES","I74": #LOCATION = "R1287" !CDS_LOCATION = "R1287" &SEC = "1" #&CDS_SEC = "1";
"A":   PN = "1"  !CDS_PN = "1";
"B":   PN = "2"  !CDS_PN = "2";
BODY = "Q_CAP","I81": #LOCATION = "C1133" !CDS_LOCATION = "C1133" &SEC = "1" #&CDS_SEC = "1";
"A":   PN = "1"  !CDS_PN = "1";
"B":   PN = "2"  !CDS_PN = "2";
BODY = "Q_RES","I93": #LOCATION = "R10" !CDS_LOCATION = "R10" &SEC = "1" #&CDS_SEC = "1";
"A":   PN = "1"  !CDS_PN = "1";
"B":   PN = "2"  !CDS_PN = "2";
BODY = "Q_RES","I94": #LOCATION = "R11" !CDS_LOCATION = "R11" &SEC = "1" #&CDS_SEC = "1";
"A":   PN = "1"  !CDS_PN = "1";
"B":   PN = "2"  !CDS_PN = "2";
BODY = "Q_RES","I95": #LOCATION = "R12" !CDS_LOCATION = "R12" &SEC = "1" #&CDS_SEC = "1";
"A":   PN = "1"  !CDS_PN = "1";
"B":   PN = "2"  !CDS_PN = "2";
BODY = "Q_CAP","I102": #LOCATION = "C362" !CDS_LOCATION = "C362" &SEC = "1" #&CDS_SEC = "1";
"A":   PN = "1"  !CDS_PN = "1";
"B":   PN = "2"  !CDS_PN = "2";
BODY = "Q_CAP","I103": #LOCATION = "C360" !CDS_LOCATION = "C360" &SEC = "1" #&CDS_SEC = "1";
"A":   PN = "1"  !CDS_PN = "1";
"B":   PN = "2"  !CDS_PN = "2";
BODY = "Q_CAP","I104": #LOCATION = "C361" !CDS_LOCATION = "C361" &SEC = "1" #&CDS_SEC = "1";
"A":   PN = "1"  !CDS_PN = "1";
"B":   PN = "2"  !CDS_PN = "2";
BODY = "Q_RES","I118": #LOCATION = "R800" !CDS_LOCATION = "R800" &SEC = "1" #&CDS_SEC = "1";
"A":   PN = "1"  !CDS_PN = "1";
"B":   PN = "2"  !CDS_PN = "2";
BODY = "Q_RES","I124": #LOCATION = "R16" !CDS_LOCATION = "R16" &SEC = "1" #&CDS_SEC = "1";
"A":   PN = "1"  !CDS_PN = "1";
"B":   PN = "2"  !CDS_PN = "2";
BODY = "Q_RES","I125": #LOCATION = "R17" !CDS_LOCATION = "R17" &SEC = "1" #&CDS_SEC = "1";
"A":   PN = "1"  !CDS_PN = "1";
"B":   PN = "2"  !CDS_PN = "2";
BODY = "Q_CAP","I135": #LOCATION = "C359" !CDS_LOCATION = "C359" &SEC = "1" #&CDS_SEC = "1";
"A":   PN = "1"  !CDS_PN = "1";
"B":   PN = "2"  !CDS_PN = "2";
BODY = "Q_RES","I137": #LOCATION = "R6114" !CDS_LOCATION = "R6114" &SEC = "1" #&CDS_SEC = "1";
"A":   PN = "1"  !CDS_PN = "1";
"B":   PN = "2"  !CDS_PN = "2";
BODY = "Q_RES","I141": #LOCATION = "R6115" !CDS_LOCATION = "R6115" &SEC = "1" #&CDS_SEC = "1";
"A":   PN = "1"  !CDS_PN = "1";
"B":   PN = "2"  !CDS_PN = "2";
BODY = "Q_RES","I143": #LOCATION = "R6185" !CDS_LOCATION = "R6185" &SEC = "1" #&CDS_SEC = "1";
"A":   PN = "1"  !CDS_PN = "1";
"B":   PN = "2"  !CDS_PN = "2";
BODY = "Q_RES","I146": #LOCATION = "R6186" !CDS_LOCATION = "R6186" &SEC = "1" #&CDS_SEC = "1";
"A":   PN = "1"  !CDS_PN = "1";
"B":   PN = "2"  !CDS_PN = "2";
BODY = "Q_RES","I151": #LOCATION = "R6187" !CDS_LOCATION = "R6187" &SEC = "1" #&CDS_SEC = "1";
"A":   PN = "1"  !CDS_PN = "1";
"B":   PN = "2"  !CDS_PN = "2";
BODY = "Q_RES","I152": #LOCATION = "R6188" !CDS_LOCATION = "R6188" &SEC = "1" #&CDS_SEC = "1";
"A":   PN = "1"  !CDS_PN = "1";
"B":   PN = "2"  !CDS_PN = "2";
BODY = "Q_RES","I154": #LOCATION = "R3" !CDS_LOCATION = "R3" &SEC = "1" #&CDS_SEC = "1";
"A":   PN = "1"  !CDS_PN = "1";
"B":   PN = "2"  !CDS_PN = "2";
BODY = "Q_RES","I156": #LOCATION = "R134" !CDS_LOCATION = "R134" &SEC = "1" #&CDS_SEC = "1";
"A":   PN = "1"  !CDS_PN = "1";
"B":   PN = "2"  !CDS_PN = "2";
BODY = "Q_RES","I157": #LOCATION = "R135" !CDS_LOCATION = "R135" &SEC = "1" #&CDS_SEC = "1";
"A":   PN = "1"  !CDS_PN = "1";
"B":   PN = "2"  !CDS_PN = "2";
BODY = "Q_RES","I162": #LOCATION = "R136" !CDS_LOCATION = "R136" &SEC = "1" #&CDS_SEC = "1";
"A":   PN = "1"  !CDS_PN = "1";
"B":   PN = "2"  !CDS_PN = "2";
BODY = "Q_RES","I163": #LOCATION = "R126" !CDS_LOCATION = "R126" &SEC = "1" #&CDS_SEC = "1";
"A":   PN = "1"  !CDS_PN = "1";
"B":   PN = "2"  !CDS_PN = "2";
BODY = "Q_RES","I166": #LOCATION = "R64" !CDS_LOCATION = "R64" &SEC = "1" #&CDS_SEC = "1";
"A":   PN = "1"  !CDS_PN = "1";
"B":   PN = "2"  !CDS_PN = "2";
BODY = "Q_RES","I170": #LOCATION = "R8033" !CDS_LOCATION = "R8033" &SEC = "1" #&CDS_SEC = "1";
"A":   PN = "1"  !CDS_PN = "1";
"B":   PN = "2"  !CDS_PN = "2";
BODY = "Q_RES","I171": #LOCATION = "R1304" !CDS_LOCATION = "R1304" &SEC = "1" #&CDS_SEC = "1";
"A":   PN = "1"  !CDS_PN = "1";
"B":   PN = "2"  !CDS_PN = "2";
DRAWING = "@t6g_mb_lib.t6g(sch_1):page338";
BODY = "Q_RES","I9": #LOCATION = "R1906" !CDS_LOCATION = "R1906" &SEC = "1" #&CDS_SEC = "1";
"A":   PN = "1"  !CDS_PN = "1";
"B":   PN = "2"  !CDS_PN = "2";
BODY = "MOSFET_NCH_DUAL","I11": #LOCATION = "Q123" !CDS_LOCATION = "Q123" &SEC = "1" #&CDS_SEC = "1";
"D1":   PN = "6"  !CDS_PN = "6";
"G1":   PN = "2"  !CDS_PN = "2";
"S1":   PN = "1"  !CDS_PN = "1";
BODY = "Q_RES","I15": #LOCATION = "R1905" !CDS_LOCATION = "R1905" &SEC = "1" #&CDS_SEC = "1";
"A":   PN = "1"  !CDS_PN = "1";
"B":   PN = "2"  !CDS_PN = "2";
BODY = "Q_RES","I17": #LOCATION = "R4068" !CDS_LOCATION = "R4068" &SEC = "1" #&CDS_SEC = "1";
"A":   PN = "1"  !CDS_PN = "1";
"B":   PN = "2"  !CDS_PN = "2";
BODY = "MOSFET_NCH_DUAL","I19": #LOCATION = "Q123" !CDS_LOCATION = "Q123" &SEC = "2" #&CDS_SEC = "2";
"D2":   PN = "3"  !CDS_PN = "3";
"G2":   PN = "5"  !CDS_PN = "5";
"S2":   PN = "4"  !CDS_PN = "4";
BODY = "MOSFET_NCH_DUAL","I23": #LOCATION = "Q124" !CDS_LOCATION = "Q124" &SEC = "1" #&CDS_SEC = "1";
"D1":   PN = "6"  !CDS_PN = "6";
"G1":   PN = "2"  !CDS_PN = "2";
"S1":   PN = "1"  !CDS_PN = "1";
BODY = "Q_RES","I24": #LOCATION = "R1908" !CDS_LOCATION = "R1908" &SEC = "1" #&CDS_SEC = "1";
"A":   PN = "1"  !CDS_PN = "1";
"B":   PN = "2"  !CDS_PN = "2";
BODY = "74LVC2G07DW7","I26": #LOCATION = "U8" !CDS_LOCATION = "U8" &SEC = "1" #&CDS_SEC = "1";
"1A":   PN = "1"  !CDS_PN = "1";
"1Y":   PN = "6"  !CDS_PN = "6";
"2A":   PN = "3"  !CDS_PN = "3";
"2Y":   PN = "4"  !CDS_PN = "4";
"GND":   PN = "2"  !CDS_PN = "2";
"VCC":   PN = "5"  !CDS_PN = "5";
BODY = "Q_RES","I28": #LOCATION = "R1907" !CDS_LOCATION = "R1907" &SEC = "1" #&CDS_SEC = "1";
"A":   PN = "1"  !CDS_PN = "1";
"B":   PN = "2"  !CDS_PN = "2";
BODY = "74LVC2G07DW7","I29": #LOCATION = "U211" !CDS_LOCATION = "U211" &SEC = "1" #&CDS_SEC = "1";
"1A":   PN = "1"  !CDS_PN = "1";
"1Y":   PN = "6"  !CDS_PN = "6";
"2A":   PN = "3"  !CDS_PN = "3";
"2Y":   PN = "4"  !CDS_PN = "4";
"GND":   PN = "2"  !CDS_PN = "2";
"VCC":   PN = "5"  !CDS_PN = "5";
BODY = "Q_CAP","I30": #LOCATION = "C593" !CDS_LOCATION = "C593" &SEC = "1" #&CDS_SEC = "1";
"A":   PN = "1"  !CDS_PN = "1";
"B":   PN = "2"  !CDS_PN = "2";
BODY = "Q_CAP","I33": #LOCATION = "C592" !CDS_LOCATION = "C592" &SEC = "1" #&CDS_SEC = "1";
"A":   PN = "1"  !CDS_PN = "1";
"B":   PN = "2"  !CDS_PN = "2";
BODY = "Q_RES","I36": #LOCATION = "PR3788" !CDS_LOCATION = "PR3788" &SEC = "1" #&CDS_SEC = "1";
"A":   PN = "1"  !CDS_PN = "1";
"B":   PN = "2"  !CDS_PN = "2";
BODY = "Q_RES","I40": #LOCATION = "R3784" !CDS_LOCATION = "R3784" &SEC = "1" #&CDS_SEC = "1";
"A":   PN = "1"  !CDS_PN = "1";
"B":   PN = "2"  !CDS_PN = "2";
BODY = "Q_RES","I42": #LOCATION = "PR3787" !CDS_LOCATION = "PR3787" &SEC = "1" #&CDS_SEC = "1";
"A":   PN = "1"  !CDS_PN = "1";
"B":   PN = "2"  !CDS_PN = "2";
BODY = "Q_RES","I43": #LOCATION = "PR3786" !CDS_LOCATION = "PR3786" &SEC = "1" #&CDS_SEC = "1";
"A":   PN = "1"  !CDS_PN = "1";
"B":   PN = "2"  !CDS_PN = "2";
BODY = "Q_CAP","I45": #LOCATION = "PC2079" !CDS_LOCATION = "PC2079" &SEC = "1" #&CDS_SEC = "1";
"A":   PN = "1"  !CDS_PN = "1";
"B":   PN = "2"  !CDS_PN = "2";
BODY = "Q_RES","I46": #LOCATION = "R1148" !CDS_LOCATION = "R1148" &SEC = "1" #&CDS_SEC = "1";
"A":   PN = "1"  !CDS_PN = "1";
"B":   PN = "2"  !CDS_PN = "2";
BODY = "Q_RES","I48": #LOCATION = "PR5484" !CDS_LOCATION = "PR5484" &SEC = "1" #&CDS_SEC = "1";
"A":   PN = "1"  !CDS_PN = "1";
"B":   PN = "2"  !CDS_PN = "2";
BODY = "MAX15090BEWIT","I50": #LOCATION = "PU203" !CDS_LOCATION = "PU203" &SEC = "1" #&CDS_SEC = "1";
"CB":   PN = "B1"  !CDS_PN = "B1";
"CDLY":   PN = "A7"  !CDS_PN = "A7";
"EN#":   PN = "B7"  !CDS_PN = "B7";
"FAULT#":   PN = "C7"  !CDS_PN = "C7";
"GATE":   PN = "A6"  !CDS_PN = "A6";
"GND_B2":   PN = "B2"  !CDS_PN = "B2";
"GND_C1":   PN = "C1"  !CDS_PN = "C1";
"GND_C2":   PN = "C2"  !CDS_PN = "C2";
"IN_A3":   PN = "A3"  !CDS_PN = "A3";
"IN_A5":   PN = "A5"  !CDS_PN = "A5";
"IN_B3":   PN = "B3"  !CDS_PN = "B3";
"IN_B5":   PN = "B5"  !CDS_PN = "B5";
"IN_C3":   PN = "C3"  !CDS_PN = "C3";
"IN_C5":   PN = "C5"  !CDS_PN = "C5";
"IN_D5":   PN = "D5"  !CDS_PN = "D5";
"ISENSE":   PN = "A1"  !CDS_PN = "A1";
"OUT_A4":   PN = "A4"  !CDS_PN = "A4";
"OUT_B4":   PN = "B4"  !CDS_PN = "B4";
"OUT_B6":   PN = "B6"  !CDS_PN = "B6";
"OUT_C4":   PN = "C4"  !CDS_PN = "C4";
"OUT_C6":   PN = "C6"  !CDS_PN = "C6";
"OUT_D4":   PN = "D4"  !CDS_PN = "D4";
"OUT_D6":   PN = "D6"  !CDS_PN = "D6";
"OV":   PN = "D3"  !CDS_PN = "D3";
"PG":   PN = "D7"  !CDS_PN = "D7";
"REG":   PN = "D1"  !CDS_PN = "D1";
"UV":   PN = "D2"  !CDS_PN = "D2";
"VCC":   PN = "A2"  !CDS_PN = "A2";
BODY = "Q_CAP","I54": #LOCATION = "PC2087" !CDS_LOCATION = "PC2087" &SEC = "1" #&CDS_SEC = "1";
"A":   PN = "1"  !CDS_PN = "1";
"B":   PN = "2"  !CDS_PN = "2";
BODY = "Q_CAP","I55": #LOCATION = "PC2085" !CDS_LOCATION = "PC2085" &SEC = "1" #&CDS_SEC = "1";
"A":   PN = "1"  !CDS_PN = "1";
"B":   PN = "2"  !CDS_PN = "2";
BODY = "Q_RES","I56": #LOCATION = "PR3792" !CDS_LOCATION = "PR3792" &SEC = "1" #&CDS_SEC = "1";
"A":   PN = "1"  !CDS_PN = "1";
"B":   PN = "2"  !CDS_PN = "2";
BODY = "Q_RES","I59": #LOCATION = "R4070" !CDS_LOCATION = "R4070" &SEC = "1" #&CDS_SEC = "1";
"A":   PN = "1"  !CDS_PN = "1";
"B":   PN = "2"  !CDS_PN = "2";
BODY = "Q_RES","I61": #LOCATION = "R3785" !CDS_LOCATION = "R3785" &SEC = "1" #&CDS_SEC = "1";
"A":   PN = "1"  !CDS_PN = "1";
"B":   PN = "2"  !CDS_PN = "2";
BODY = "Q_CAP","I62": #LOCATION = "PC5328" !CDS_LOCATION = "PC5328" &SEC = "1" #&CDS_SEC = "1";
"A":   PN = "1"  !CDS_PN = "1";
"B":   PN = "2"  !CDS_PN = "2";
BODY = "Q_RES","I64": #LOCATION = "PR3790" !CDS_LOCATION = "PR3790" &SEC = "1" #&CDS_SEC = "1";
"A":   PN = "1"  !CDS_PN = "1";
"B":   PN = "2"  !CDS_PN = "2";
BODY = "Q_RES","I66": #LOCATION = "PR3789" !CDS_LOCATION = "PR3789" &SEC = "1" #&CDS_SEC = "1";
"A":   PN = "1"  !CDS_PN = "1";
"B":   PN = "2"  !CDS_PN = "2";
BODY = "Q_CAP","I67": #LOCATION = "PC2093" !CDS_LOCATION = "PC2093" &SEC = "1" #&CDS_SEC = "1";
"A":   PN = "1"  !CDS_PN = "1";
"B":   PN = "2"  !CDS_PN = "2";
BODY = "Q_RES","I68": #LOCATION = "PR3798" !CDS_LOCATION = "PR3798" &SEC = "1" #&CDS_SEC = "1";
"A":   PN = "1"  !CDS_PN = "1";
"B":   PN = "2"  !CDS_PN = "2";
BODY = "Q_RES","I71": #LOCATION = "R1150" !CDS_LOCATION = "R1150" &SEC = "1" #&CDS_SEC = "1";
"A":   PN = "1"  !CDS_PN = "1";
"B":   PN = "2"  !CDS_PN = "2";
BODY = "Q_RES","I73": #LOCATION = "PR3781" !CDS_LOCATION = "PR3781" &SEC = "1" #&CDS_SEC = "1";
"A":   PN = "1"  !CDS_PN = "1";
"B":   PN = "2"  !CDS_PN = "2";
BODY = "Q_CAP","I74": #LOCATION = "PC2088" !CDS_LOCATION = "PC2088" &SEC = "1" #&CDS_SEC = "1";
"A":   PN = "1"  !CDS_PN = "1";
"B":   PN = "2"  !CDS_PN = "2";
BODY = "Q_RES","I75": #LOCATION = "R3144" !CDS_LOCATION = "R3144" &SEC = "1" #&CDS_SEC = "1";
"A":   PN = "1"  !CDS_PN = "1";
"B":   PN = "2"  !CDS_PN = "2";
BODY = "Q_RES","I76": #LOCATION = "PR4524" !CDS_LOCATION = "PR4524" &SEC = "1" #&CDS_SEC = "1";
"A":   PN = "1"  !CDS_PN = "1";
"B":   PN = "2"  !CDS_PN = "2";
BODY = "Q_CAP","I77": #LOCATION = "PC4056" !CDS_LOCATION = "PC4056" &SEC = "1" #&CDS_SEC = "1";
"A":   PN = "1"  !CDS_PN = "1";
"B":   PN = "2"  !CDS_PN = "2";
BODY = "SCHOTTKY_AC","I79": #LOCATION = "PD102" !CDS_LOCATION = "PD102" &SEC = "1" #&CDS_SEC = "1";
"A":   PN = "A"  !CDS_PN = "A";
"C":   PN = "C"  !CDS_PN = "C";
BODY = "Q_RES","I80": #LOCATION = "R3870" !CDS_LOCATION = "R3870" &SEC = "1" #&CDS_SEC = "1";
"A":   PN = "1"  !CDS_PN = "1";
"B":   PN = "2"  !CDS_PN = "2";
BODY = "Q_RES","I82": #LOCATION = "R3869" !CDS_LOCATION = "R3869" &SEC = "1" #&CDS_SEC = "1";
"A":   PN = "1"  !CDS_PN = "1";
"B":   PN = "2"  !CDS_PN = "2";
BODY = "Q_RES","I83": #LOCATION = "R3799" !CDS_LOCATION = "R3799" &SEC = "1" #&CDS_SEC = "1";
"A":   PN = "1"  !CDS_PN = "1";
"B":   PN = "2"  !CDS_PN = "2";
BODY = "Q_RES","I85": #LOCATION = "R3797" !CDS_LOCATION = "R3797" &SEC = "1" #&CDS_SEC = "1";
"A":   PN = "1"  !CDS_PN = "1";
"B":   PN = "2"  !CDS_PN = "2";
BODY = "Q_CAP","I86": #LOCATION = "PC2092" !CDS_LOCATION = "PC2092" &SEC = "1" #&CDS_SEC = "1";
"A":   PN = "1"  !CDS_PN = "1";
"B":   PN = "2"  !CDS_PN = "2";
BODY = "Q_CAP","I87": #LOCATION = "PC2080" !CDS_LOCATION = "PC2080" &SEC = "1" #&CDS_SEC = "1";
"A":   PN = "1"  !CDS_PN = "1";
"B":   PN = "2"  !CDS_PN = "2";
BODY = "Q_CAP","I89": #LOCATION = "PC2082" !CDS_LOCATION = "PC2082" &SEC = "1" #&CDS_SEC = "1";
"A":   PN = "1"  !CDS_PN = "1";
"B":   PN = "2"  !CDS_PN = "2";
BODY = "Q_CAP","I94": #LOCATION = "PC2144" !CDS_LOCATION = "PC2144" &SEC = "1" #&CDS_SEC = "1";
"A":   PN = "1"  !CDS_PN = "1";
"B":   PN = "2"  !CDS_PN = "2";
BODY = "Q_RES","I95": #LOCATION = "PR5481" !CDS_LOCATION = "PR5481" &SEC = "1" #&CDS_SEC = "1";
"A":   PN = "1"  !CDS_PN = "1";
"B":   PN = "2"  !CDS_PN = "2";
BODY = "Q_RES","I96": #LOCATION = "PR4525" !CDS_LOCATION = "PR4525" &SEC = "1" #&CDS_SEC = "1";
"A":   PN = "1"  !CDS_PN = "1";
"B":   PN = "2"  !CDS_PN = "2";
BODY = "SCHOTTKY_AC","I97": #LOCATION = "PD103" !CDS_LOCATION = "PD103" &SEC = "1" #&CDS_SEC = "1";
"A":   PN = "A"  !CDS_PN = "A";
"C":   PN = "C"  !CDS_PN = "C";
BODY = "Q_CAP","I100": #LOCATION = "PC2089" !CDS_LOCATION = "PC2089" &SEC = "1" #&CDS_SEC = "1";
"A":   PN = "1"  !CDS_PN = "1";
"B":   PN = "2"  !CDS_PN = "2";
BODY = "Q_RES","I101": #LOCATION = "R3796" !CDS_LOCATION = "R3796" &SEC = "1" #&CDS_SEC = "1";
"A":   PN = "1"  !CDS_PN = "1";
"B":   PN = "2"  !CDS_PN = "2";
BODY = "Q_CAP","I104": #LOCATION = "PC2091" !CDS_LOCATION = "PC2091" &SEC = "1" #&CDS_SEC = "1";
"A":   PN = "1"  !CDS_PN = "1";
"B":   PN = "2"  !CDS_PN = "2";
BODY = "Q_CAP","I106": #LOCATION = "PC2081" !CDS_LOCATION = "PC2081" &SEC = "1" #&CDS_SEC = "1";
"A":   PN = "1"  !CDS_PN = "1";
"B":   PN = "2"  !CDS_PN = "2";
BODY = "Q_CAP","I110": #LOCATION = "PC2086" !CDS_LOCATION = "PC2086" &SEC = "1" #&CDS_SEC = "1";
"A":   PN = "1"  !CDS_PN = "1";
"B":   PN = "2"  !CDS_PN = "2";
BODY = "Q_RES","I111": #LOCATION = "PR3780" !CDS_LOCATION = "PR3780" &SEC = "1" #&CDS_SEC = "1";
"A":   PN = "1"  !CDS_PN = "1";
"B":   PN = "2"  !CDS_PN = "2";
BODY = "MOSFET_NCH_DUAL","I112": #LOCATION = "Q124" !CDS_LOCATION = "Q124" &SEC = "2" #&CDS_SEC = "2";
"D2":   PN = "3"  !CDS_PN = "3";
"G2":   PN = "5"  !CDS_PN = "5";
"S2":   PN = "4"  !CDS_PN = "4";
BODY = "MAX15090BEWIT","I113": #LOCATION = "PU202" !CDS_LOCATION = "PU202" &SEC = "1" #&CDS_SEC = "1";
"CB":   PN = "B1"  !CDS_PN = "B1";
"CDLY":   PN = "A7"  !CDS_PN = "A7";
"EN#":   PN = "B7"  !CDS_PN = "B7";
"FAULT#":   PN = "C7"  !CDS_PN = "C7";
"GATE":   PN = "A6"  !CDS_PN = "A6";
"GND_B2":   PN = "B2"  !CDS_PN = "B2";
"GND_C1":   PN = "C1"  !CDS_PN = "C1";
"GND_C2":   PN = "C2"  !CDS_PN = "C2";
"IN_A3":   PN = "A3"  !CDS_PN = "A3";
"IN_A5":   PN = "A5"  !CDS_PN = "A5";
"IN_B3":   PN = "B3"  !CDS_PN = "B3";
"IN_B5":   PN = "B5"  !CDS_PN = "B5";
"IN_C3":   PN = "C3"  !CDS_PN = "C3";
"IN_C5":   PN = "C5"  !CDS_PN = "C5";
"IN_D5":   PN = "D5"  !CDS_PN = "D5";
"ISENSE":   PN = "A1"  !CDS_PN = "A1";
"OUT_A4":   PN = "A4"  !CDS_PN = "A4";
"OUT_B4":   PN = "B4"  !CDS_PN = "B4";
"OUT_B6":   PN = "B6"  !CDS_PN = "B6";
"OUT_C4":   PN = "C4"  !CDS_PN = "C4";
"OUT_C6":   PN = "C6"  !CDS_PN = "C6";
"OUT_D4":   PN = "D4"  !CDS_PN = "D4";
"OUT_D6":   PN = "D6"  !CDS_PN = "D6";
"OV":   PN = "D3"  !CDS_PN = "D3";
"PG":   PN = "D7"  !CDS_PN = "D7";
"REG":   PN = "D1"  !CDS_PN = "D1";
"UV":   PN = "D2"  !CDS_PN = "D2";
"VCC":   PN = "A2"  !CDS_PN = "A2";
BODY = "Q_RES","I114": #LOCATION = "PR3791" !CDS_LOCATION = "PR3791" &SEC = "1" #&CDS_SEC = "1";
"A":   PN = "1"  !CDS_PN = "1";
"B":   PN = "2"  !CDS_PN = "2";
BODY = "DIODE_TVS","I115": #LOCATION = "PD101" !CDS_LOCATION = "PD101" &SEC = "1" #&CDS_SEC = "1";
"A":   PN = "A"  !CDS_PN = "A";
"C":   PN = "C"  !CDS_PN = "C";
BODY = "Q_RES","I116": #LOCATION = "R576" !CDS_LOCATION = "R576" &SEC = "1" #&CDS_SEC = "1";
"A":   PN = "1"  !CDS_PN = "1";
"B":   PN = "2"  !CDS_PN = "2";
BODY = "Q_RES","I118": #LOCATION = "R577" !CDS_LOCATION = "R577" &SEC = "1" #&CDS_SEC = "1";
"A":   PN = "1"  !CDS_PN = "1";
"B":   PN = "2"  !CDS_PN = "2";
BODY = "Q_RES","I123": #LOCATION = "R4061" !CDS_LOCATION = "R4061" &SEC = "1" #&CDS_SEC = "1";
"A":   PN = "1"  !CDS_PN = "1";
"B":   PN = "2"  !CDS_PN = "2";
BODY = "Q_RES","I125": #LOCATION = "R561" !CDS_LOCATION = "R561" &SEC = "1" #&CDS_SEC = "1";
"A":   PN = "1"  !CDS_PN = "1";
"B":   PN = "2"  !CDS_PN = "2";
BODY = "Q_RES","I126": #LOCATION = "R5487" !CDS_LOCATION = "R5487" &SEC = "1" #&CDS_SEC = "1";
"A":   PN = "1"  !CDS_PN = "1";
"B":   PN = "2"  !CDS_PN = "2";
BODY = "Q_RES","I127": #LOCATION = "R4069" !CDS_LOCATION = "R4069" &SEC = "1" #&CDS_SEC = "1";
"A":   PN = "1"  !CDS_PN = "1";
"B":   PN = "2"  !CDS_PN = "2";
BODY = "Q_RES","I130": #LOCATION = "R6045" !CDS_LOCATION = "R6045" &SEC = "1" #&CDS_SEC = "1";
"A":   PN = "1"  !CDS_PN = "1";
"B":   PN = "2"  !CDS_PN = "2";
BODY = "Q_RES","I131": #LOCATION = "R3783" !CDS_LOCATION = "R3783" &SEC = "1" #&CDS_SEC = "1";
"A":   PN = "1"  !CDS_PN = "1";
"B":   PN = "2"  !CDS_PN = "2";
BODY = "Q_RES","I132": #LOCATION = "R3794" !CDS_LOCATION = "R3794" &SEC = "1" #&CDS_SEC = "1";
"A":   PN = "1"  !CDS_PN = "1";
"B":   PN = "2"  !CDS_PN = "2";
BODY = "Q_RES","I133": #LOCATION = "R1136" !CDS_LOCATION = "R1136" &SEC = "1" #&CDS_SEC = "1";
"A":   PN = "1"  !CDS_PN = "1";
"B":   PN = "2"  !CDS_PN = "2";
BODY = "Q_RES","I135": #LOCATION = "R1486" !CDS_LOCATION = "R1486" &SEC = "1" #&CDS_SEC = "1";
"A":   PN = "1"  !CDS_PN = "1";
"B":   PN = "2"  !CDS_PN = "2";
DRAWING = "@t6g_mb_lib.t6g(sch_1):page83";
BODY = "Q_RES","I22": #LOCATION = "R996" !CDS_LOCATION = "R996" &SEC = "1" #&CDS_SEC = "1";
"A":   PN = "1"  !CDS_PN = "1";
"B":   PN = "2"  !CDS_PN = "2";
BODY = "Q_CAP","I24": #LOCATION = "C552" !CDS_LOCATION = "C552" &SEC = "1" #&CDS_SEC = "1";
"A":   PN = "1"  !CDS_PN = "1";
"B":   PN = "2"  !CDS_PN = "2";
BODY = "SN74LVC1G07DBVR","I26": #LOCATION = "U92" !CDS_LOCATION = "U92" &SEC = "1" #&CDS_SEC = "1";
"A":   PN = "2"  !CDS_PN = "2";
"GND":   PN = "3"  !CDS_PN = "3";
"NC":   PN = "1"  !CDS_PN = "1";
"VCC":   PN = "5"  !CDS_PN = "5";
"Y":   PN = "4"  !CDS_PN = "4";
BODY = "Q_RES","I27": #LOCATION = "R71" !CDS_LOCATION = "R71" &SEC = "1" #&CDS_SEC = "1";
"A":   PN = "1"  !CDS_PN = "1";
"B":   PN = "2"  !CDS_PN = "2";
BODY = "Q_RES","I29": #LOCATION = "R1338" !CDS_LOCATION = "R1338" &SEC = "1" #&CDS_SEC = "1";
"A":   PN = "1"  !CDS_PN = "1";
"B":   PN = "2"  !CDS_PN = "2";
BODY = "Q_RES","I54": #LOCATION = "R6145" !CDS_LOCATION = "R6145" &SEC = "1" #&CDS_SEC = "1";
"A":   PN = "1"  !CDS_PN = "1";
"B":   PN = "2"  !CDS_PN = "2";
BODY = "Q_RES","I50": #LOCATION = "R6122" !CDS_LOCATION = "R6122" &SEC = "1" #&CDS_SEC = "1";
"A":   PN = "1"  !CDS_PN = "1";
"B":   PN = "2"  !CDS_PN = "2";
BODY = "Q_RES","I52": #LOCATION = "R6144" !CDS_LOCATION = "R6144" &SEC = "1" #&CDS_SEC = "1";
"A":   PN = "1"  !CDS_PN = "1";
"B":   PN = "2"  !CDS_PN = "2";
BODY = "Q_RES","I36": #LOCATION = "R6143" !CDS_LOCATION = "R6143" &SEC = "1" #&CDS_SEC = "1";
"A":   PN = "1"  !CDS_PN = "1";
"B":   PN = "2"  !CDS_PN = "2";
BODY = "Q_RES","I39": #LOCATION = "R6138" !CDS_LOCATION = "R6138" &SEC = "1" #&CDS_SEC = "1";
"A":   PN = "1"  !CDS_PN = "1";
"B":   PN = "2"  !CDS_PN = "2";
BODY = "Q_RES","I46": #LOCATION = "R6127" !CDS_LOCATION = "R6127" &SEC = "1" #&CDS_SEC = "1";
"A":   PN = "1"  !CDS_PN = "1";
"B":   PN = "2"  !CDS_PN = "2";
BODY = "Q_RES","I55": #LOCATION = "R6139" !CDS_LOCATION = "R6139" &SEC = "1" #&CDS_SEC = "1";
"A":   PN = "1"  !CDS_PN = "1";
"B":   PN = "2"  !CDS_PN = "2";
BODY = "Q_RES","I56": #LOCATION = "R6140" !CDS_LOCATION = "R6140" &SEC = "1" #&CDS_SEC = "1";
"A":   PN = "1"  !CDS_PN = "1";
"B":   PN = "2"  !CDS_PN = "2";
BODY = "Q_RES","I64": #LOCATION = "R6128" !CDS_LOCATION = "R6128" &SEC = "1" #&CDS_SEC = "1";
"A":   PN = "1"  !CDS_PN = "1";
"B":   PN = "2"  !CDS_PN = "2";
BODY = "Q_RES","I65": #LOCATION = "R6129" !CDS_LOCATION = "R6129" &SEC = "1" #&CDS_SEC = "1";
"A":   PN = "1"  !CDS_PN = "1";
"B":   PN = "2"  !CDS_PN = "2";
BODY = "Q_RES","I71": #LOCATION = "R6123" !CDS_LOCATION = "R6123" &SEC = "1" #&CDS_SEC = "1";
"A":   PN = "1"  !CDS_PN = "1";
"B":   PN = "2"  !CDS_PN = "2";
BODY = "Q_RES","I72": #LOCATION = "R6124" !CDS_LOCATION = "R6124" &SEC = "1" #&CDS_SEC = "1";
"A":   PN = "1"  !CDS_PN = "1";
"B":   PN = "2"  !CDS_PN = "2";
BODY = "Q_RES","I115": #LOCATION = "R6120" !CDS_LOCATION = "R6120" &SEC = "1" #&CDS_SEC = "1";
"A":   PN = "1"  !CDS_PN = "1";
"B":   PN = "2"  !CDS_PN = "2";
BODY = "Q_RES","I116": #LOCATION = "R6125" !CDS_LOCATION = "R6125" &SEC = "1" #&CDS_SEC = "1";
"A":   PN = "1"  !CDS_PN = "1";
"B":   PN = "2"  !CDS_PN = "2";
BODY = "Q_RES","I117": #LOCATION = "R6136" !CDS_LOCATION = "R6136" &SEC = "1" #&CDS_SEC = "1";
"A":   PN = "1"  !CDS_PN = "1";
"B":   PN = "2"  !CDS_PN = "2";
BODY = "Q_RES","I118": #LOCATION = "R6141" !CDS_LOCATION = "R6141" &SEC = "1" #&CDS_SEC = "1";
"A":   PN = "1"  !CDS_PN = "1";
"B":   PN = "2"  !CDS_PN = "2";
BODY = "Q_RES","I119": #LOCATION = "R6126" !CDS_LOCATION = "R6126" &SEC = "1" #&CDS_SEC = "1";
"A":   PN = "1"  !CDS_PN = "1";
"B":   PN = "2"  !CDS_PN = "2";
BODY = "Q_RES","I120": #LOCATION = "R6121" !CDS_LOCATION = "R6121" &SEC = "1" #&CDS_SEC = "1";
"A":   PN = "1"  !CDS_PN = "1";
"B":   PN = "2"  !CDS_PN = "2";
BODY = "Q_RES","I121": #LOCATION = "R6137" !CDS_LOCATION = "R6137" &SEC = "1" #&CDS_SEC = "1";
"A":   PN = "1"  !CDS_PN = "1";
"B":   PN = "2"  !CDS_PN = "2";
BODY = "Q_RES","I122": #LOCATION = "R6142" !CDS_LOCATION = "R6142" &SEC = "1" #&CDS_SEC = "1";
"A":   PN = "1"  !CDS_PN = "1";
"B":   PN = "2"  !CDS_PN = "2";
BODY = "Q_RES","I131": #LOCATION = "R6130" !CDS_LOCATION = "R6130" &SEC = "1" #&CDS_SEC = "1";
"A":   PN = "1"  !CDS_PN = "1";
"B":   PN = "2"  !CDS_PN = "2";
BODY = "Q_RES","I132": #LOCATION = "R6133" !CDS_LOCATION = "R6133" &SEC = "1" #&CDS_SEC = "1";
"A":   PN = "1"  !CDS_PN = "1";
"B":   PN = "2"  !CDS_PN = "2";
BODY = "Q_RES","I133": #LOCATION = "R6134" !CDS_LOCATION = "R6134" &SEC = "1" #&CDS_SEC = "1";
"A":   PN = "1"  !CDS_PN = "1";
"B":   PN = "2"  !CDS_PN = "2";
BODY = "Q_RES","I134": #LOCATION = "R6131" !CDS_LOCATION = "R6131" &SEC = "1" #&CDS_SEC = "1";
"A":   PN = "1"  !CDS_PN = "1";
"B":   PN = "2"  !CDS_PN = "2";
BODY = "Q_RES","I135": #LOCATION = "R6132" !CDS_LOCATION = "R6132" &SEC = "1" #&CDS_SEC = "1";
"A":   PN = "1"  !CDS_PN = "1";
"B":   PN = "2"  !CDS_PN = "2";
BODY = "Q_RES","I136": #LOCATION = "R6135" !CDS_LOCATION = "R6135" &SEC = "1" #&CDS_SEC = "1";
"A":   PN = "1"  !CDS_PN = "1";
"B":   PN = "2"  !CDS_PN = "2";
BODY = "Q_RES","I137": #LOCATION = "R6149" !CDS_LOCATION = "R6149" &SEC = "1" #&CDS_SEC = "1";
"A":   PN = "1"  !CDS_PN = "1";
"B":   PN = "2"  !CDS_PN = "2";
BODY = "Q_RES","I138": #LOCATION = "R6146" !CDS_LOCATION = "R6146" &SEC = "1" #&CDS_SEC = "1";
"A":   PN = "1"  !CDS_PN = "1";
"B":   PN = "2"  !CDS_PN = "2";
BODY = "Q_RES","I139": #LOCATION = "R6150" !CDS_LOCATION = "R6150" &SEC = "1" #&CDS_SEC = "1";
"A":   PN = "1"  !CDS_PN = "1";
"B":   PN = "2"  !CDS_PN = "2";
BODY = "Q_RES","I140": #LOCATION = "R6147" !CDS_LOCATION = "R6147" &SEC = "1" #&CDS_SEC = "1";
"A":   PN = "1"  !CDS_PN = "1";
"B":   PN = "2"  !CDS_PN = "2";
BODY = "Q_RES","I141": #LOCATION = "R6151" !CDS_LOCATION = "R6151" &SEC = "1" #&CDS_SEC = "1";
"A":   PN = "1"  !CDS_PN = "1";
"B":   PN = "2"  !CDS_PN = "2";
BODY = "Q_RES","I142": #LOCATION = "R6148" !CDS_LOCATION = "R6148" &SEC = "1" #&CDS_SEC = "1";
"A":   PN = "1"  !CDS_PN = "1";
"B":   PN = "2"  !CDS_PN = "2";
DRAWING = "@t6g_mb_lib.t6g(sch_1):page81";
BODY = "Q_RES","I44": #LOCATION = "R262" !CDS_LOCATION = "R262" &SEC = "1" #&CDS_SEC = "1";
"A":   PN = "1"  !CDS_PN = "1";
"B":   PN = "2"  !CDS_PN = "2";
BODY = "Q_RES","I45": #LOCATION = "R180" !CDS_LOCATION = "R180" &SEC = "1" #&CDS_SEC = "1";
"A":   PN = "1"  !CDS_PN = "1";
"B":   PN = "2"  !CDS_PN = "2";
BODY = "Q_RES","I46": #LOCATION = "R181" !CDS_LOCATION = "R181" &SEC = "1" #&CDS_SEC = "1";
"A":   PN = "1"  !CDS_PN = "1";
"B":   PN = "2"  !CDS_PN = "2";
BODY = "Q_RES","I47": #LOCATION = "R263" !CDS_LOCATION = "R263" &SEC = "1" #&CDS_SEC = "1";
"A":   PN = "1"  !CDS_PN = "1";
"B":   PN = "2"  !CDS_PN = "2";
BODY = "Q_RES","I48": #LOCATION = "R184" !CDS_LOCATION = "R184" &SEC = "1" #&CDS_SEC = "1";
"A":   PN = "1"  !CDS_PN = "1";
"B":   PN = "2"  !CDS_PN = "2";
BODY = "Q_RES","I49": #LOCATION = "R260" !CDS_LOCATION = "R260" &SEC = "1" #&CDS_SEC = "1";
"A":   PN = "1"  !CDS_PN = "1";
"B":   PN = "2"  !CDS_PN = "2";
BODY = "Q_RES","I50": #LOCATION = "R261" !CDS_LOCATION = "R261" &SEC = "1" #&CDS_SEC = "1";
"A":   PN = "1"  !CDS_PN = "1";
"B":   PN = "2"  !CDS_PN = "2";
BODY = "Q_RES","I51": #LOCATION = "R232" !CDS_LOCATION = "R232" &SEC = "1" #&CDS_SEC = "1";
"A":   PN = "1"  !CDS_PN = "1";
"B":   PN = "2"  !CDS_PN = "2";
BODY = "Q_RES","I52": #LOCATION = "R222" !CDS_LOCATION = "R222" &SEC = "1" #&CDS_SEC = "1";
"A":   PN = "1"  !CDS_PN = "1";
"B":   PN = "2"  !CDS_PN = "2";
BODY = "Q_RES","I53": #LOCATION = "R264" !CDS_LOCATION = "R264" &SEC = "1" #&CDS_SEC = "1";
"A":   PN = "1"  !CDS_PN = "1";
"B":   PN = "2"  !CDS_PN = "2";
BODY = "Q_RES","I54": #LOCATION = "R233" !CDS_LOCATION = "R233" &SEC = "1" #&CDS_SEC = "1";
"A":   PN = "1"  !CDS_PN = "1";
"B":   PN = "2"  !CDS_PN = "2";
BODY = "Q_RES","I55": #LOCATION = "R268" !CDS_LOCATION = "R268" &SEC = "1" #&CDS_SEC = "1";
"A":   PN = "1"  !CDS_PN = "1";
"B":   PN = "2"  !CDS_PN = "2";
BODY = "Q_RES","I56": #LOCATION = "R269" !CDS_LOCATION = "R269" &SEC = "1" #&CDS_SEC = "1";
"A":   PN = "1"  !CDS_PN = "1";
"B":   PN = "2"  !CDS_PN = "2";
BODY = "Q_RES","I57": #LOCATION = "R141" !CDS_LOCATION = "R141" &SEC = "1" #&CDS_SEC = "1";
"A":   PN = "1"  !CDS_PN = "1";
"B":   PN = "2"  !CDS_PN = "2";
BODY = "Q_RES","I58": #LOCATION = "R189" !CDS_LOCATION = "R189" &SEC = "1" #&CDS_SEC = "1";
"A":   PN = "1"  !CDS_PN = "1";
"B":   PN = "2"  !CDS_PN = "2";
BODY = "Q_RES","I59": #LOCATION = "R137" !CDS_LOCATION = "R137" &SEC = "1" #&CDS_SEC = "1";
"A":   PN = "1"  !CDS_PN = "1";
"B":   PN = "2"  !CDS_PN = "2";
BODY = "Q_RES","I60": #LOCATION = "R231" !CDS_LOCATION = "R231" &SEC = "1" #&CDS_SEC = "1";
"A":   PN = "1"  !CDS_PN = "1";
"B":   PN = "2"  !CDS_PN = "2";
BODY = "Q_RES","I61": #LOCATION = "R188" !CDS_LOCATION = "R188" &SEC = "1" #&CDS_SEC = "1";
"A":   PN = "1"  !CDS_PN = "1";
"B":   PN = "2"  !CDS_PN = "2";
BODY = "Q_RES","I62": #LOCATION = "R239" !CDS_LOCATION = "R239" &SEC = "1" #&CDS_SEC = "1";
"A":   PN = "1"  !CDS_PN = "1";
"B":   PN = "2"  !CDS_PN = "2";
BODY = "Q_RES","I63": #LOCATION = "R243" !CDS_LOCATION = "R243" &SEC = "1" #&CDS_SEC = "1";
"A":   PN = "1"  !CDS_PN = "1";
"B":   PN = "2"  !CDS_PN = "2";
BODY = "Q_RES","I64": #LOCATION = "R190" !CDS_LOCATION = "R190" &SEC = "1" #&CDS_SEC = "1";
"A":   PN = "1"  !CDS_PN = "1";
"B":   PN = "2"  !CDS_PN = "2";
BODY = "Q_RES","I65": #LOCATION = "R246" !CDS_LOCATION = "R246" &SEC = "1" #&CDS_SEC = "1";
"A":   PN = "1"  !CDS_PN = "1";
"B":   PN = "2"  !CDS_PN = "2";
BODY = "Q_RES","I66": #LOCATION = "R236" !CDS_LOCATION = "R236" &SEC = "1" #&CDS_SEC = "1";
"A":   PN = "1"  !CDS_PN = "1";
"B":   PN = "2"  !CDS_PN = "2";
BODY = "Q_RES","I67": #LOCATION = "R245" !CDS_LOCATION = "R245" &SEC = "1" #&CDS_SEC = "1";
"A":   PN = "1"  !CDS_PN = "1";
"B":   PN = "2"  !CDS_PN = "2";
BODY = "Q_RES","I68": #LOCATION = "R187" !CDS_LOCATION = "R187" &SEC = "1" #&CDS_SEC = "1";
"A":   PN = "1"  !CDS_PN = "1";
"B":   PN = "2"  !CDS_PN = "2";
BODY = "Q_RES","I69": #LOCATION = "R237" !CDS_LOCATION = "R237" &SEC = "1" #&CDS_SEC = "1";
"A":   PN = "1"  !CDS_PN = "1";
"B":   PN = "2"  !CDS_PN = "2";
BODY = "Q_RES","I70": #LOCATION = "R235" !CDS_LOCATION = "R235" &SEC = "1" #&CDS_SEC = "1";
"A":   PN = "1"  !CDS_PN = "1";
"B":   PN = "2"  !CDS_PN = "2";
BODY = "Q_RES","I71": #LOCATION = "R238" !CDS_LOCATION = "R238" &SEC = "1" #&CDS_SEC = "1";
"A":   PN = "1"  !CDS_PN = "1";
"B":   PN = "2"  !CDS_PN = "2";
BODY = "Q_RES","I72": #LOCATION = "R244" !CDS_LOCATION = "R244" &SEC = "1" #&CDS_SEC = "1";
"A":   PN = "1"  !CDS_PN = "1";
"B":   PN = "2"  !CDS_PN = "2";
BODY = "Q_RES","I73": #LOCATION = "R267" !CDS_LOCATION = "R267" &SEC = "1" #&CDS_SEC = "1";
"A":   PN = "1"  !CDS_PN = "1";
"B":   PN = "2"  !CDS_PN = "2";
BODY = "Q_RES","I75": #LOCATION = "R234" !CDS_LOCATION = "R234" &SEC = "1" #&CDS_SEC = "1";
"A":   PN = "1"  !CDS_PN = "1";
"B":   PN = "2"  !CDS_PN = "2";
BODY = "Q_RES","I77": #LOCATION = "R204" !CDS_LOCATION = "R204" &SEC = "1" #&CDS_SEC = "1";
"A":   PN = "1"  !CDS_PN = "1";
"B":   PN = "2"  !CDS_PN = "2";
BODY = "Q_RES","I80": #LOCATION = "R185" !CDS_LOCATION = "R185" &SEC = "1" #&CDS_SEC = "1";
"A":   PN = "1"  !CDS_PN = "1";
"B":   PN = "2"  !CDS_PN = "2";
BODY = "Q_RES","I81": #LOCATION = "R959" !CDS_LOCATION = "R959" &SEC = "1" #&CDS_SEC = "1";
"A":   PN = "1"  !CDS_PN = "1";
"B":   PN = "2"  !CDS_PN = "2";
BODY = "Q_RES","I82": #LOCATION = "R183" !CDS_LOCATION = "R183" &SEC = "1" #&CDS_SEC = "1";
"A":   PN = "1"  !CDS_PN = "1";
"B":   PN = "2"  !CDS_PN = "2";
BODY = "Q_RES","I99": #LOCATION = "R6052" !CDS_LOCATION = "R6052" &SEC = "1" #&CDS_SEC = "1";
"A":   PN = "1"  !CDS_PN = "1";
"B":   PN = "2"  !CDS_PN = "2";
BODY = "Q_RES","I100": #LOCATION = "R223" !CDS_LOCATION = "R223" &SEC = "1" #&CDS_SEC = "1";
"A":   PN = "1"  !CDS_PN = "1";
"B":   PN = "2"  !CDS_PN = "2";
BODY = "Q_RES","I101": #LOCATION = "R182" !CDS_LOCATION = "R182" &SEC = "1" #&CDS_SEC = "1";
"A":   PN = "1"  !CDS_PN = "1";
"B":   PN = "2"  !CDS_PN = "2";
BODY = "Q_RES","I102": #LOCATION = "R6051" !CDS_LOCATION = "R6051" &SEC = "1" #&CDS_SEC = "1";
"A":   PN = "1"  !CDS_PN = "1";
"B":   PN = "2"  !CDS_PN = "2";
BODY = "Q_RES","I103": #LOCATION = "R227" !CDS_LOCATION = "R227" &SEC = "1" #&CDS_SEC = "1";
"A":   PN = "1"  !CDS_PN = "1";
"B":   PN = "2"  !CDS_PN = "2";
BODY = "LCMXO3LF9400C5BG484C","I143": #LOCATION = "U18" !CDS_LOCATION = "U18" #SEC = "1" !CDS_SEC = "1";
"PL2A":   PN = "D3"  !CDS_PN = "D3";
"PL2B":   PN = "D4"  !CDS_PN = "D4";
"PL2C":   PN = "F6"  !CDS_PN = "F6";
"PL2D":   PN = "G7"  !CDS_PN = "G7";
"PL3A||L_GPLLT_FB":   PN = "E4"  !CDS_PN = "E4";
"PL3B||L_GPLLC_FB":   PN = "F5"  !CDS_PN = "F5";
"PL3C":   PN = "G6"  !CDS_PN = "G6";
"PL3D":   PN = "H7"  !CDS_PN = "H7";
"PL4A||L_GPLLT_IN":   PN = "C1"  !CDS_PN = "C1";
"PL4B||L_GPLLC_IN":   PN = "D2"  !CDS_PN = "D2";
"PL4C":   PN = "G5"  !CDS_PN = "G5";
"PL4D":   PN = "H6"  !CDS_PN = "H6";
"PL5A":   PN = "D1"  !CDS_PN = "D1";
"PL5B":   PN = "E2"  !CDS_PN = "E2";
"PL5C":   PN = "E3"  !CDS_PN = "E3";
"PL5D":   PN = "F4"  !CDS_PN = "F4";
"PL6A":   PN = "E1"  !CDS_PN = "E1";
"PL6B":   PN = "F1"  !CDS_PN = "F1";
"PL6C":   PN = "G3"  !CDS_PN = "G3";
"PL6D":   PN = "G4"  !CDS_PN = "G4";
"PL7A||PCLKT5_0":   PN = "G2"  !CDS_PN = "G2";
"PL7B||PCLKC5_0":   PN = "G1"  !CDS_PN = "G1";
"PL7C":   PN = "H4"  !CDS_PN = "H4";
"PL7D":   PN = "H3"  !CDS_PN = "H3";
"PL10A":   PN = "H2"  !CDS_PN = "H2";
"PL10B":   PN = "H1"  !CDS_PN = "H1";
"PL10C":   PN = "J7"  !CDS_PN = "J7";
"PL10D":   PN = "J6"  !CDS_PN = "J6";
"PL11A":   PN = "H5"  !CDS_PN = "H5";
"PL11B":   PN = "J5"  !CDS_PN = "J5";
"PL11C":   PN = "J4"  !CDS_PN = "J4";
"PL11D":   PN = "J3"  !CDS_PN = "J3";
"PL12A":   PN = "J2"  !CDS_PN = "J2";
"PL12B":   PN = "J1"  !CDS_PN = "J1";
"PL12C":   PN = "K7"  !CDS_PN = "K7";
"PL12D":   PN = "K6"  !CDS_PN = "K6";
"PL13A":   PN = "L7"  !CDS_PN = "L7";
"PL13B":   PN = "K5"  !CDS_PN = "K5";
"PL13C":   PN = "K4"  !CDS_PN = "K4";
"PL13D":   PN = "K3"  !CDS_PN = "K3";
"PL14A":   PN = "K2"  !CDS_PN = "K2";
"PL14B":   PN = "K1"  !CDS_PN = "K1";
"PL14C":   PN = "L6"  !CDS_PN = "L6";
"PL14D":   PN = "L5"  !CDS_PN = "L5";
"PL16A||PCLKT4_0":   PN = "L1"  !CDS_PN = "L1";
"PL16B||PCLKC4_0":   PN = "M2"  !CDS_PN = "M2";
"PL16C":   PN = "L3"  !CDS_PN = "L3";
"PL16D":   PN = "L4"  !CDS_PN = "L4";
"PL17A":   PN = "M1"  !CDS_PN = "M1";
"PL17B":   PN = "N1"  !CDS_PN = "N1";
"PL17C":   PN = "M6"  !CDS_PN = "M6";
"PL17D":   PN = "M5"  !CDS_PN = "M5";
"PL18A":   PN = "N2"  !CDS_PN = "N2";
"PL18B":   PN = "P1"  !CDS_PN = "P1";
"PL18C":   PN = "N3"  !CDS_PN = "N3";
"PL18D":   PN = "N4"  !CDS_PN = "N4";
"PL19A":   PN = "P2"  !CDS_PN = "P2";
"PL19B":   PN = "R1"  !CDS_PN = "R1";
"PL19C":   PN = "P3"  !CDS_PN = "P3";
"PL19D":   PN = "M7"  !CDS_PN = "M7";
"PL20A":   PN = "P4"  !CDS_PN = "P4";
"PL20B":   PN = "N5"  !CDS_PN = "N5";
"PL20C":   PN = "N6"  !CDS_PN = "N6";
"PL20D":   PN = "N7"  !CDS_PN = "N7";
"PL21A":   PN = "R2"  !CDS_PN = "R2";
"PL21B":   PN = "T1"  !CDS_PN = "T1";
"PL21C":   PN = "P5"  !CDS_PN = "P5";
"PL21D":   PN = "P6"  !CDS_PN = "P6";
"PL24A":   PN = "R3"  !CDS_PN = "R3";
"PL24B":   PN = "R4"  !CDS_PN = "R4";
"PL24C":   PN = "R5"  !CDS_PN = "R5";
"PL24D":   PN = "P7"  !CDS_PN = "P7";
"PL25A":   PN = "T2"  !CDS_PN = "T2";
"PL25B":   PN = "U1"  !CDS_PN = "U1";
"PL25C":   PN = "R6"  !CDS_PN = "R6";
"PL25D":   PN = "R7"  !CDS_PN = "R7";
"PL26A":   PN = "T3"  !CDS_PN = "T3";
"PL26B":   PN = "T4"  !CDS_PN = "T4";
"PL26C":   PN = "T5"  !CDS_PN = "T5";
"PL26D":   PN = "T6"  !CDS_PN = "T6";
"PL27A||PCLKT3_0":   PN = "U2"  !CDS_PN = "U2";
"PL27B||PCLKC3_0":   PN = "V1"  !CDS_PN = "V1";
"PL27C":   PN = "U3"  !CDS_PN = "U3";
"PL27D":   PN = "U4"  !CDS_PN = "U4";
"PL28A":   PN = "W1"  !CDS_PN = "W1";
"PL28B":   PN = "W2"  !CDS_PN = "W2";
"PL28C":   PN = "V4"  !CDS_PN = "V4";
"PL28D":   PN = "U5"  !CDS_PN = "U5";
"PL29A":   PN = "Y1"  !CDS_PN = "Y1";
"PL29B":   PN = "AA1"  !CDS_PN = "AA1";
"PL29C":   PN = "W3"  !CDS_PN = "W3";
"PL29D":   PN = "Y2"  !CDS_PN = "Y2";
"PL30A":   PN = "Y3"  !CDS_PN = "Y3";
"PL30B":   PN = "W4"  !CDS_PN = "W4";
"PL30C":   PN = "V5"  !CDS_PN = "V5";
"PL30D":   PN = "T7"  !CDS_PN = "T7";
BODY = "LCMXO3LF9400C5BG484C","I1": #LOCATION = "U18" !CDS_LOCATION = "U18" #SEC = "6" !CDS_SEC = "6";
"GND1":   PN = "A1"  !CDS_PN = "A1";
"GND2":   PN = "A22"  !CDS_PN = "A22";
"GND3":   PN = "B7"  !CDS_PN = "B7";
"GND4":   PN = "B16"  !CDS_PN = "B16";
"GND5":   PN = "C2"  !CDS_PN = "C2";
"GND6":   PN = "C11"  !CDS_PN = "C11";
"GND7":   PN = "E5"  !CDS_PN = "E5";
"GND8":   PN = "E18"  !CDS_PN = "E18";
"GND9":   PN = "F2"  !CDS_PN = "F2";
"GND10":   PN = "F21"  !CDS_PN = "F21";
"GND11":   PN = "H8"  !CDS_PN = "H8";
"GND12":   PN = "H10"  !CDS_PN = "H10";
"GND13":   PN = "H13"  !CDS_PN = "H13";
"GND14":   PN = "H15"  !CDS_PN = "H15";
"GND15":   PN = "J9"  !CDS_PN = "J9";
"GND16":   PN = "J10"  !CDS_PN = "J10";
"GND17":   PN = "J11"  !CDS_PN = "J11";
"GND18":   PN = "J12"  !CDS_PN = "J12";
"GND19":   PN = "J13"  !CDS_PN = "J13";
"GND20":   PN = "J14"  !CDS_PN = "J14";
"GND21":   PN = "K9"  !CDS_PN = "K9";
"GND22":   PN = "K14"  !CDS_PN = "K14";
"GND23":   PN = "K21"  !CDS_PN = "K21";
"GND24":   PN = "L2"  !CDS_PN = "L2";
"GND25":   PN = "L9"  !CDS_PN = "L9";
"GND26":   PN = "L10"  !CDS_PN = "L10";
"GND27":   PN = "L13"  !CDS_PN = "L13";
"GND28":   PN = "L14"  !CDS_PN = "L14";
"GND29":   PN = "L18"  !CDS_PN = "L18";
"GND30":   PN = "M4"  !CDS_PN = "M4";
"GND31":   PN = "M9"  !CDS_PN = "M9";
"GND32":   PN = "M10"  !CDS_PN = "M10";
"GND33":   PN = "M13"  !CDS_PN = "M13";
"GND34":   PN = "M14"  !CDS_PN = "M14";
"GND35":   PN = "N9"  !CDS_PN = "N9";
"GND36":   PN = "N14"  !CDS_PN = "N14";
"GND37":   PN = "N21"  !CDS_PN = "N21";
"GND38":   PN = "P9"  !CDS_PN = "P9";
"GND39":   PN = "P10"  !CDS_PN = "P10";
"GND40":   PN = "P11"  !CDS_PN = "P11";
"GND41":   PN = "P12"  !CDS_PN = "P12";
"GND42":   PN = "P13"  !CDS_PN = "P13";
"GND43":   PN = "P14"  !CDS_PN = "P14";
"GND44":   PN = "R8"  !CDS_PN = "R8";
"GND45":   PN = "R15"  !CDS_PN = "R15";
"GND46":   PN = "V2"  !CDS_PN = "V2";
"GND47":   PN = "V21"  !CDS_PN = "V21";
"GND48":   PN = "W12"  !CDS_PN = "W12";
"GND49":   PN = "Y7"  !CDS_PN = "Y7";
"GND50":   PN = "Y16"  !CDS_PN = "Y16";
"GND51":   PN = "AB1"  !CDS_PN = "AB1";
"GND52":   PN = "AB22"  !CDS_PN = "AB22";
BODY = "Q_RES","I74": #LOCATION = "R205" !CDS_LOCATION = "R205" &SEC = "1" #&CDS_SEC = "1";
"A":   PN = "1"  !CDS_PN = "1";
"B":   PN = "2"  !CDS_PN = "2";
BODY = "Q_RES","I83": #LOCATION = "R6054" !CDS_LOCATION = "R6054" &SEC = "1" #&CDS_SEC = "1";
"A":   PN = "1"  !CDS_PN = "1";
"B":   PN = "2"  !CDS_PN = "2";
BODY = "Q_RES","I84": #LOCATION = "R275" !CDS_LOCATION = "R275" &SEC = "1" #&CDS_SEC = "1";
"A":   PN = "1"  !CDS_PN = "1";
"B":   PN = "2"  !CDS_PN = "2";
BODY = "Q_RES","I85": #LOCATION = "R6053" !CDS_LOCATION = "R6053" &SEC = "1" #&CDS_SEC = "1";
"A":   PN = "1"  !CDS_PN = "1";
"B":   PN = "2"  !CDS_PN = "2";
BODY = "Q_RES","I86": #LOCATION = "R958" !CDS_LOCATION = "R958" &SEC = "1" #&CDS_SEC = "1";
"A":   PN = "1"  !CDS_PN = "1";
"B":   PN = "2"  !CDS_PN = "2";
BODY = "Q_RES","I104": #LOCATION = "R271" !CDS_LOCATION = "R271" &SEC = "1" #&CDS_SEC = "1";
"A":   PN = "1"  !CDS_PN = "1";
"B":   PN = "2"  !CDS_PN = "2";
BODY = "Q_RES","I105": #LOCATION = "R285" !CDS_LOCATION = "R285" &SEC = "1" #&CDS_SEC = "1";
"A":   PN = "1"  !CDS_PN = "1";
"B":   PN = "2"  !CDS_PN = "2";
BODY = "Q_RES","I106": #LOCATION = "R81" !CDS_LOCATION = "R81" &SEC = "1" #&CDS_SEC = "1";
"A":   PN = "1"  !CDS_PN = "1";
"B":   PN = "2"  !CDS_PN = "2";
BODY = "Q_RES","I107": #LOCATION = "R221" !CDS_LOCATION = "R221" &SEC = "1" #&CDS_SEC = "1";
"A":   PN = "1"  !CDS_PN = "1";
"B":   PN = "2"  !CDS_PN = "2";
BODY = "Q_RES","I108": #LOCATION = "R266" !CDS_LOCATION = "R266" &SEC = "1" #&CDS_SEC = "1";
"A":   PN = "1"  !CDS_PN = "1";
"B":   PN = "2"  !CDS_PN = "2";
BODY = "Q_RES","I109": #LOCATION = "R220" !CDS_LOCATION = "R220" &SEC = "1" #&CDS_SEC = "1";
"A":   PN = "1"  !CDS_PN = "1";
"B":   PN = "2"  !CDS_PN = "2";
BODY = "Q_RES","I110": #LOCATION = "R179" !CDS_LOCATION = "R179" &SEC = "1" #&CDS_SEC = "1";
"A":   PN = "1"  !CDS_PN = "1";
"B":   PN = "2"  !CDS_PN = "2";
BODY = "Q_RES","I111": #LOCATION = "R226" !CDS_LOCATION = "R226" &SEC = "1" #&CDS_SEC = "1";
"A":   PN = "1"  !CDS_PN = "1";
"B":   PN = "2"  !CDS_PN = "2";
BODY = "Q_RES","I112": #LOCATION = "R270" !CDS_LOCATION = "R270" &SEC = "1" #&CDS_SEC = "1";
"A":   PN = "1"  !CDS_PN = "1";
"B":   PN = "2"  !CDS_PN = "2";
BODY = "Q_RES","I113": #LOCATION = "R278" !CDS_LOCATION = "R278" &SEC = "1" #&CDS_SEC = "1";
"A":   PN = "1"  !CDS_PN = "1";
"B":   PN = "2"  !CDS_PN = "2";
BODY = "Q_RES","I140": #LOCATION = "R284" !CDS_LOCATION = "R284" &SEC = "1" #&CDS_SEC = "1";
"A":   PN = "1"  !CDS_PN = "1";
"B":   PN = "2"  !CDS_PN = "2";
BODY = "LCMXO3LF9400C5BG484C","I141": #LOCATION = "U18" !CDS_LOCATION = "U18" #SEC = "5" !CDS_SEC = "5";
"VCC1":   PN = "K10"  !CDS_PN = "K10";
"VCC2":   PN = "K11"  !CDS_PN = "K11";
"VCC3":   PN = "K12"  !CDS_PN = "K12";
"VCC4":   PN = "K13"  !CDS_PN = "K13";
"VCC5":   PN = "L11"  !CDS_PN = "L11";
"VCC6":   PN = "L12"  !CDS_PN = "L12";
"VCC7":   PN = "M11"  !CDS_PN = "M11";
"VCC8":   PN = "M12"  !CDS_PN = "M12";
"VCC9":   PN = "N10"  !CDS_PN = "N10";
"VCC10":   PN = "N11"  !CDS_PN = "N11";
"VCC11":   PN = "N12"  !CDS_PN = "N12";
"VCC12":   PN = "N13"  !CDS_PN = "N13";
"VCCIO0_1":   PN = "C7"  !CDS_PN = "C7";
"VCCIO0_2":   PN = "C12"  !CDS_PN = "C12";
"VCCIO0_3":   PN = "C16"  !CDS_PN = "C16";
"VCCIO0_4":   PN = "G10"  !CDS_PN = "G10";
"VCCIO0_5":   PN = "G13"  !CDS_PN = "G13";
"VCCIO0_6":   PN = "H9"  !CDS_PN = "H9";
"VCCIO0_7":   PN = "H11"  !CDS_PN = "H11";
"VCCIO0_8":   PN = "H12"  !CDS_PN = "H12";
"VCCIO0_9":   PN = "H14"  !CDS_PN = "H14";
"VCCIO1_1":   PN = "F20"  !CDS_PN = "F20";
"VCCIO1_2":   PN = "J15"  !CDS_PN = "J15";
"VCCIO1_3":   PN = "K15"  !CDS_PN = "K15";
"VCCIO1_4":   PN = "L15"  !CDS_PN = "L15";
"VCCIO1_5":   PN = "M15"  !CDS_PN = "M15";
"VCCIO1_6":   PN = "M18"  !CDS_PN = "M18";
"VCCIO1_7":   PN = "N15"  !CDS_PN = "N15";
"VCCIO1_8":   PN = "P15"  !CDS_PN = "P15";
"VCCIO1_9":   PN = "V20"  !CDS_PN = "V20";
"VCCIO2_1":   PN = "R9"  !CDS_PN = "R9";
"VCCIO2_2":   PN = "R10"  !CDS_PN = "R10";
"VCCIO2_3":   PN = "R11"  !CDS_PN = "R11";
"VCCIO2_4":   PN = "R12"  !CDS_PN = "R12";
"VCCIO2_5":   PN = "R13"  !CDS_PN = "R13";
"VCCIO2_6":   PN = "R14"  !CDS_PN = "R14";
"VCCIO2_7":   PN = "W7"  !CDS_PN = "W7";
"VCCIO2_8":   PN = "W11"  !CDS_PN = "W11";
"VCCIO2_9":   PN = "W16"  !CDS_PN = "W16";
"VCCIO3_1":   PN = "N8"  !CDS_PN = "N8";
"VCCIO3_2":   PN = "P8"  !CDS_PN = "P8";
"VCCIO3_3":   PN = "V3"  !CDS_PN = "V3";
"VCCIO4_1":   PN = "L8"  !CDS_PN = "L8";
"VCCIO4_2":   PN = "M8"  !CDS_PN = "M8";
"VCCIO4_3":   PN = "M3"  !CDS_PN = "M3";
"VCCIO5_1":   PN = "F3"  !CDS_PN = "F3";
"VCCIO5_2":   PN = "J8"  !CDS_PN = "J8";
"VCCIO5_3":   PN = "K8"  !CDS_PN = "K8";
BODY = "Q_RES","I146": #LOCATION = "R6073" !CDS_LOCATION = "R6073" &SEC = "1" #&CDS_SEC = "1";
"A":   PN = "1"  !CDS_PN = "1";
"B":   PN = "2"  !CDS_PN = "2";
BODY = "Q_RES","I164": #LOCATION = "R6183" !CDS_LOCATION = "R6183" &SEC = "1" #&CDS_SEC = "1";
"A":   PN = "1"  !CDS_PN = "1";
"B":   PN = "2"  !CDS_PN = "2";
BODY = "Q_RES","I165": #LOCATION = "R6184" !CDS_LOCATION = "R6184" &SEC = "1" #&CDS_SEC = "1";
"A":   PN = "1"  !CDS_PN = "1";
"B":   PN = "2"  !CDS_PN = "2";
BODY = "Q_RES","I168": #LOCATION = "R132" !CDS_LOCATION = "R132" &SEC = "1" #&CDS_SEC = "1";
"A":   PN = "1"  !CDS_PN = "1";
"B":   PN = "2"  !CDS_PN = "2";
BODY = "Q_RES","I169": #LOCATION = "R133" !CDS_LOCATION = "R133" &SEC = "1" #&CDS_SEC = "1";
"A":   PN = "1"  !CDS_PN = "1";
"B":   PN = "2"  !CDS_PN = "2";
BODY = "Q_RES","I176": #LOCATION = "R1340" !CDS_LOCATION = "R1340" &SEC = "1" #&CDS_SEC = "1";
"A":   PN = "1"  !CDS_PN = "1";
"B":   PN = "2"  !CDS_PN = "2";
BODY = "Q_RES","I178": #LOCATION = "R1329" !CDS_LOCATION = "R1329" &SEC = "1" #&CDS_SEC = "1";
"A":   PN = "1"  !CDS_PN = "1";
"B":   PN = "2"  !CDS_PN = "2";
BODY = "Q_RES","I180": #LOCATION = "R1339" !CDS_LOCATION = "R1339" &SEC = "1" #&CDS_SEC = "1";
"A":   PN = "1"  !CDS_PN = "1";
"B":   PN = "2"  !CDS_PN = "2";
DRAWING = "@t6g_mb_lib.t6g(sch_1):page339";
BODY = "Q_CAP","I60": #LOCATION = "PC2153" !CDS_LOCATION = "PC2153" &SEC = "1" #&CDS_SEC = "1";
"A":   PN = "1"  !CDS_PN = "1";
"B":   PN = "2"  !CDS_PN = "2";
BODY = "Q_RES","I63": #LOCATION = "PR3835" !CDS_LOCATION = "PR3835" &SEC = "1" #&CDS_SEC = "1";
"A":   PN = "1"  !CDS_PN = "1";
"B":   PN = "2"  !CDS_PN = "2";
BODY = "Q_CAP","I64": #LOCATION = "PC2155" !CDS_LOCATION = "PC2155" &SEC = "1" #&CDS_SEC = "1";
"A":   PN = "1"  !CDS_PN = "1";
"B":   PN = "2"  !CDS_PN = "2";
BODY = "Q_CAP","I68": #LOCATION = "PC2154" !CDS_LOCATION = "PC2154" &SEC = "1" #&CDS_SEC = "1";
"A":   PN = "1"  !CDS_PN = "1";
"B":   PN = "2"  !CDS_PN = "2";
BODY = "Q_RES","I71": #LOCATION = "PR3837" !CDS_LOCATION = "PR3837" &SEC = "1" #&CDS_SEC = "1";
"A":   PN = "1"  !CDS_PN = "1";
"B":   PN = "2"  !CDS_PN = "2";
BODY = "Q_CAP","I73": #LOCATION = "PC2156" !CDS_LOCATION = "PC2156" &SEC = "1" #&CDS_SEC = "1";
"A":   PN = "1"  !CDS_PN = "1";
"B":   PN = "2"  !CDS_PN = "2";
BODY = "Q_RES","I74": #LOCATION = "PR3839" !CDS_LOCATION = "PR3839" &SEC = "1" #&CDS_SEC = "1";
"A":   PN = "1"  !CDS_PN = "1";
"B":   PN = "2"  !CDS_PN = "2";
BODY = "Q_RES","I75": #LOCATION = "R4532" !CDS_LOCATION = "R4532" &SEC = "1" #&CDS_SEC = "1";
"A":   PN = "1"  !CDS_PN = "1";
"B":   PN = "2"  !CDS_PN = "2";
BODY = "Q_RES","I76": #LOCATION = "PR3838" !CDS_LOCATION = "PR3838" &SEC = "1" #&CDS_SEC = "1";
"A":   PN = "1"  !CDS_PN = "1";
"B":   PN = "2"  !CDS_PN = "2";
BODY = "Q_RES","I80": #LOCATION = "PR3842" !CDS_LOCATION = "PR3842" &SEC = "1" #&CDS_SEC = "1";
"A":   PN = "1"  !CDS_PN = "1";
"B":   PN = "2"  !CDS_PN = "2";
BODY = "Q_RES","I81": #LOCATION = "PR3840" !CDS_LOCATION = "PR3840" &SEC = "1" #&CDS_SEC = "1";
"A":   PN = "1"  !CDS_PN = "1";
"B":   PN = "2"  !CDS_PN = "2";
BODY = "Q_RES","I82": #LOCATION = "PR3841" !CDS_LOCATION = "PR3841" &SEC = "1" #&CDS_SEC = "1";
"A":   PN = "1"  !CDS_PN = "1";
"B":   PN = "2"  !CDS_PN = "2";
BODY = "Q_RES","I84": #LOCATION = "R3872" !CDS_LOCATION = "R3872" &SEC = "1" #&CDS_SEC = "1";
"A":   PN = "1"  !CDS_PN = "1";
"B":   PN = "2"  !CDS_PN = "2";
BODY = "Q_RES","I85": #LOCATION = "R3871" !CDS_LOCATION = "R3871" &SEC = "1" #&CDS_SEC = "1";
"A":   PN = "1"  !CDS_PN = "1";
"B":   PN = "2"  !CDS_PN = "2";
BODY = "Q_CAP","I86": #LOCATION = "PC2158" !CDS_LOCATION = "PC2158" &SEC = "1" #&CDS_SEC = "1";
"A":   PN = "1"  !CDS_PN = "1";
"B":   PN = "2"  !CDS_PN = "2";
BODY = "Q_RES","I88": #LOCATION = "PR3843" !CDS_LOCATION = "PR3843" &SEC = "1" #&CDS_SEC = "1";
"A":   PN = "1"  !CDS_PN = "1";
"B":   PN = "2"  !CDS_PN = "2";
BODY = "Q_CAP","I91": #LOCATION = "PC2160" !CDS_LOCATION = "PC2160" &SEC = "1" #&CDS_SEC = "1";
"A":   PN = "1"  !CDS_PN = "1";
"B":   PN = "2"  !CDS_PN = "2";
BODY = "Q_CAP","I98": #LOCATION = "PC2157" !CDS_LOCATION = "PC2157" &SEC = "1" #&CDS_SEC = "1";
"A":   PN = "1"  !CDS_PN = "1";
"B":   PN = "2"  !CDS_PN = "2";
BODY = "Q_RES","I100": #LOCATION = "PR3844" !CDS_LOCATION = "PR3844" &SEC = "1" #&CDS_SEC = "1";
"A":   PN = "1"  !CDS_PN = "1";
"B":   PN = "2"  !CDS_PN = "2";
BODY = "Q_RES","I102": #LOCATION = "PR3846" !CDS_LOCATION = "PR3846" &SEC = "1" #&CDS_SEC = "1";
"A":   PN = "1"  !CDS_PN = "1";
"B":   PN = "2"  !CDS_PN = "2";
BODY = "Q_CAP","I104": #LOCATION = "PC2161" !CDS_LOCATION = "PC2161" &SEC = "1" #&CDS_SEC = "1";
"A":   PN = "1"  !CDS_PN = "1";
"B":   PN = "2"  !CDS_PN = "2";
BODY = "Q_CAP","I106": #LOCATION = "PC2162" !CDS_LOCATION = "PC2162" &SEC = "1" #&CDS_SEC = "1";
"A":   PN = "1"  !CDS_PN = "1";
"B":   PN = "2"  !CDS_PN = "2";
BODY = "Q_CAP","I108": #LOCATION = "PC2163" !CDS_LOCATION = "PC2163" &SEC = "1" #&CDS_SEC = "1";
"A":   PN = "1"  !CDS_PN = "1";
"B":   PN = "2"  !CDS_PN = "2";
BODY = "Q_CAP","I111": #LOCATION = "PC2159" !CDS_LOCATION = "PC2159" &SEC = "1" #&CDS_SEC = "1";
"A":   PN = "1"  !CDS_PN = "1";
"B":   PN = "2"  !CDS_PN = "2";
BODY = "MP5016GQHLZ","I113": #LOCATION = "PU205" !CDS_LOCATION = "PU205" &SEC = "1" #&CDS_SEC = "1";
"DV_DT":   PN = "10"  !CDS_PN = "10";
"EN":   PN = "9"  !CDS_PN = "9";
"GATE":   PN = "8"  !CDS_PN = "8";
"GND":   PN = "3"  !CDS_PN = "3";
"ILIMIT":   PN = "4"  !CDS_PN = "4";
"MODE":   PN = "5"  !CDS_PN = "5";
"SOURCE":   PN = "6_7"  !CDS_PN = "6_7";
"VCC":   PN = "1_2"  !CDS_PN = "1_2";
BODY = "Q_RES","I128": #LOCATION = "R3834" !CDS_LOCATION = "R3834" &SEC = "1" #&CDS_SEC = "1";
"A":   PN = "1"  !CDS_PN = "1";
"B":   PN = "2"  !CDS_PN = "2";
BODY = "Q_RES","I130": #LOCATION = "R591" !CDS_LOCATION = "R591" &SEC = "1" #&CDS_SEC = "1";
"A":   PN = "1"  !CDS_PN = "1";
"B":   PN = "2"  !CDS_PN = "2";
BODY = "Q_RES","I131": #LOCATION = "R3845" !CDS_LOCATION = "R3845" &SEC = "1" #&CDS_SEC = "1";
"A":   PN = "1"  !CDS_PN = "1";
"B":   PN = "2"  !CDS_PN = "2";
BODY = "Q_RES","I134": #LOCATION = "R1487" !CDS_LOCATION = "R1487" &SEC = "1" #&CDS_SEC = "1";
"A":   PN = "1"  !CDS_PN = "1";
"B":   PN = "2"  !CDS_PN = "2";
BODY = "Q_RES","I135": #LOCATION = "R1137" !CDS_LOCATION = "R1137" &SEC = "1" #&CDS_SEC = "1";
"A":   PN = "1"  !CDS_PN = "1";
"B":   PN = "2"  !CDS_PN = "2";
BODY = "RS31312R","I137": #LOCATION = "PU204" !CDS_LOCATION = "PU204" #SEC = "1" !CDS_SEC = "1";
"AVIN":   PN = "12"  !CDS_PN = "12";
"EN":   PN = "1"  !CDS_PN = "1";
"ENTM":   PN = "3"  !CDS_PN = "3";
"FLTB":   PN = "9"  !CDS_PN = "9";
"GND":   PN = "7"  !CDS_PN = "7";
"IMON":   PN = "8"  !CDS_PN = "8";
"ISET":   PN = "5"  !CDS_PN = "5";
"LOADEN":   PN = "2"  !CDS_PN = "2";
"OV":   PN = "11"  !CDS_PN = "11";
"PG":   PN = "10"  !CDS_PN = "10";
"SS":   PN = "6"  !CDS_PN = "6";
"TIMER":   PN = "4"  !CDS_PN = "4";
"VIN_21_22":   PN = "21_22"  !CDS_PN = "21_22";
"VIN_23":   PN = "23"  !CDS_PN = "23";
"VIN_24":   PN = "24"  !CDS_PN = "24";
"VIN_25":   PN = "25"  !CDS_PN = "25";
"VIN_26":   PN = "26"  !CDS_PN = "26";
"VOUT_13":   PN = "13"  !CDS_PN = "13";
"VOUT_14":   PN = "14"  !CDS_PN = "14";
"VOUT_15":   PN = "15"  !CDS_PN = "15";
"VOUT_16":   PN = "16"  !CDS_PN = "16";
"VOUT_17":   PN = "17"  !CDS_PN = "17";
"VOUT_18":   PN = "18"  !CDS_PN = "18";
"VOUT_19":   PN = "19"  !CDS_PN = "19";
"VOUT_20":   PN = "20"  !CDS_PN = "20";
DRAWING = "@t6g_mb_lib.t6g(sch_1):page244";
BODY = "Q_CAP","I2": #LOCATION = "PC1648" !CDS_LOCATION = "PC1648" &SEC = "1" #&CDS_SEC = "1";
"A":   PN = "1"  !CDS_PN = "1";
"B":   PN = "2"  !CDS_PN = "2";
BODY = "Q_INDUCTOR","I5": #LOCATION = "PL8064" !CDS_LOCATION = "PL8064" &SEC = "1" #&CDS_SEC = "1";
"1":   PN = "1"  !CDS_PN = "1";
"2":   PN = "2"  !CDS_PN = "2";
BODY = "Q_CAP","I7": #LOCATION = "PC1849" !CDS_LOCATION = "PC1849" &SEC = "1" #&CDS_SEC = "1";
"A":   PN = "1"  !CDS_PN = "1";
"B":   PN = "2"  !CDS_PN = "2";
BODY = "Q_CAP","I8": #LOCATION = "PC1848" !CDS_LOCATION = "PC1848" #SEC = "1" !CDS_SEC = "1";
"A":   PN = "1"  !CDS_PN = "1";
"B":   PN = "2"  !CDS_PN = "2";
BODY = "Q_CAP","I10": #LOCATION = "PC1850" !CDS_LOCATION = "PC1850" &SEC = "1" #&CDS_SEC = "1";
"A":   PN = "1"  !CDS_PN = "1";
"B":   PN = "2"  !CDS_PN = "2";
BODY = "Q_CAP","I11": #LOCATION = "PC1898" !CDS_LOCATION = "PC1898" &SEC = "1" #&CDS_SEC = "1";
"A":   PN = "1"  !CDS_PN = "1";
"B":   PN = "2"  !CDS_PN = "2";
BODY = "Q_CAP","I13": #LOCATION = "PC1846" !CDS_LOCATION = "PC1846" &SEC = "1" #&CDS_SEC = "1";
"A":   PN = "1"  !CDS_PN = "1";
"B":   PN = "2"  !CDS_PN = "2";
BODY = "Q_RES","I15": #LOCATION = "PR8089" !CDS_LOCATION = "PR8089" #SEC = "1" !CDS_SEC = "1";
"A":   PN = "1"  !CDS_PN = "1";
"B":   PN = "2"  !CDS_PN = "2";
BODY = "Q_CAP","I19": #LOCATION = "PC1853" !CDS_LOCATION = "PC1853" &SEC = "1" #&CDS_SEC = "1";
"A":   PN = "1"  !CDS_PN = "1";
"B":   PN = "2"  !CDS_PN = "2";
BODY = "Q_CAP","I20": #LOCATION = "PC1877" !CDS_LOCATION = "PC1877" &SEC = "1" #&CDS_SEC = "1";
"A":   PN = "1"  !CDS_PN = "1";
"B":   PN = "2"  !CDS_PN = "2";
BODY = "Q_RES","I23": #LOCATION = "PR8091" !CDS_LOCATION = "PR8091" &SEC = "1" #&CDS_SEC = "1";
"A":   PN = "1"  !CDS_PN = "1";
"B":   PN = "2"  !CDS_PN = "2";
BODY = "Q_CAP","I24": #LOCATION = "PC1847" !CDS_LOCATION = "PC1847" &SEC = "1" #&CDS_SEC = "1";
"A":   PN = "1"  !CDS_PN = "1";
"B":   PN = "2"  !CDS_PN = "2";
BODY = "Q_RES","I25": #LOCATION = "R2356" !CDS_LOCATION = "R2356" #SEC = "1" !CDS_SEC = "1";
"A":   PN = "1"  !CDS_PN = "1";
"B":   PN = "2"  !CDS_PN = "2";
BODY = "Q_RES","I26": #LOCATION = "R2316" !CDS_LOCATION = "R2316" &SEC = "1" #&CDS_SEC = "1";
"A":   PN = "1"  !CDS_PN = "1";
"B":   PN = "2"  !CDS_PN = "2";
BODY = "Q_RES","I27": #LOCATION = "PR8092" !CDS_LOCATION = "PR8092" &SEC = "1" #&CDS_SEC = "1";
"A":   PN = "1"  !CDS_PN = "1";
"B":   PN = "2"  !CDS_PN = "2";
BODY = "Q_INDUCTOR","I28": #LOCATION = "PL8065" !CDS_LOCATION = "PL8065" &SEC = "1" #&CDS_SEC = "1";
"1":   PN = "1"  !CDS_PN = "1";
"2":   PN = "2"  !CDS_PN = "2";
BODY = "Q_CAPP","I30": #LOCATION = "PC1845" !CDS_LOCATION = "PC1845" &SEC = "1" #&CDS_SEC = "1";
"A":   PN = "1"  !CDS_PN = "1";
"B":   PN = "2"  !CDS_PN = "2";
BODY = "Q_CAP","I31": #LOCATION = "PC1855" !CDS_LOCATION = "PC1855" &SEC = "1" #&CDS_SEC = "1";
"A":   PN = "1"  !CDS_PN = "1";
"B":   PN = "2"  !CDS_PN = "2";
BODY = "Q_CAP","I32": #LOCATION = "PC1856" !CDS_LOCATION = "PC1856" &SEC = "1" #&CDS_SEC = "1";
"A":   PN = "1"  !CDS_PN = "1";
"B":   PN = "2"  !CDS_PN = "2";
BODY = "Q_CAP","I34": #LOCATION = "PC1852" !CDS_LOCATION = "PC1852" #SEC = "1" !CDS_SEC = "1";
"A":   PN = "1"  !CDS_PN = "1";
"B":   PN = "2"  !CDS_PN = "2";
BODY = "Q_RES","I37": #LOCATION = "PR3337" !CDS_LOCATION = "PR3337" &SEC = "1" #&CDS_SEC = "1";
"A":   PN = "1"  !CDS_PN = "1";
"B":   PN = "2"  !CDS_PN = "2";
BODY = "MPQ8633AGLEC807Z","I38": #LOCATION = "U326" !CDS_LOCATION = "U326" &SEC = "1" #&CDS_SEC = "1";
"AGND":   PN = "2"  !CDS_PN = "2";
"BST":   PN = "1"  !CDS_PN = "1";
"CS":   PN = "3"  !CDS_PN = "3";
"EN":   PN = "8"  !CDS_PN = "8";
"FB":   PN = "7"  !CDS_PN = "7";
"MODE":   PN = "4"  !CDS_PN = "4";
"PGND":   PN = "11_18"  !CDS_PN = "11_18";
"PGOOD":   PN = "9"  !CDS_PN = "9";
"RGND":   PN = "6"  !CDS_PN = "6";
"SW":   PN = "20"  !CDS_PN = "20";
"TRK_REF":   PN = "5"  !CDS_PN = "5";
"VCC":   PN = "19"  !CDS_PN = "19";
"VIN1":   PN = "10"  !CDS_PN = "10";
"VIN2":   PN = "21"  !CDS_PN = "21";
BODY = "Q_RES","I40": #LOCATION = "R6097" !CDS_LOCATION = "R6097" &SEC = "1" #&CDS_SEC = "1";
"A":   PN = "1"  !CDS_PN = "1";
"B":   PN = "2"  !CDS_PN = "2";
DRAWING = "@t6g_mb_lib.t6g(sch_1):page167";
BODY = "Q_CAP","I2": #LOCATION = "PC118" !CDS_LOCATION = "PC118" #SEC = "1" !CDS_SEC = "1";
"A":   PN = "1"  !CDS_PN = "1";
"B":   PN = "2"  !CDS_PN = "2";
BODY = "Q_CAP","I5": #LOCATION = "C348" !CDS_LOCATION = "C348" &SEC = "1" #&CDS_SEC = "1";
"A":   PN = "1"  !CDS_PN = "1";
"B":   PN = "2"  !CDS_PN = "2";
BODY = "Q_CAP","I8": #LOCATION = "PC6000" !CDS_LOCATION = "PC6000" &SEC = "1" #&CDS_SEC = "1";
"A":   PN = "1"  !CDS_PN = "1";
"B":   PN = "2"  !CDS_PN = "2";
BODY = "Q_INDUCTOR","I10": #LOCATION = "PL71" !CDS_LOCATION = "PL71" #SEC = "1" !CDS_SEC = "1";
"1":   PN = "1"  !CDS_PN = "1";
"2":   PN = "2"  !CDS_PN = "2";
BODY = "Q_CAP","I12": #LOCATION = "PC119" !CDS_LOCATION = "PC119" #SEC = "1" !CDS_SEC = "1";
"A":   PN = "1"  !CDS_PN = "1";
"B":   PN = "2"  !CDS_PN = "2";
BODY = "Q_CAP","I13": #LOCATION = "PC120" !CDS_LOCATION = "PC120" #SEC = "1" !CDS_SEC = "1";
"A":   PN = "1"  !CDS_PN = "1";
"B":   PN = "2"  !CDS_PN = "2";
BODY = "Q_RES","I15": #LOCATION = "PR452" !CDS_LOCATION = "PR452" #SEC = "1" !CDS_SEC = "1";
"A":   PN = "1"  !CDS_PN = "1";
"B":   PN = "2"  !CDS_PN = "2";
BODY = "Q_RES","I17": #LOCATION = "PR6000" !CDS_LOCATION = "PR6000" &SEC = "1" #&CDS_SEC = "1";
"A":   PN = "1"  !CDS_PN = "1";
"B":   PN = "2"  !CDS_PN = "2";
BODY = "Q_CAP","I19": #LOCATION = "PC127" !CDS_LOCATION = "PC127" #SEC = "1" !CDS_SEC = "1";
"A":   PN = "1"  !CDS_PN = "1";
"B":   PN = "2"  !CDS_PN = "2";
BODY = "Q_RES","I23": #LOCATION = "PR454" !CDS_LOCATION = "PR454" #SEC = "1" !CDS_SEC = "1";
"A":   PN = "1"  !CDS_PN = "1";
"B":   PN = "2"  !CDS_PN = "2";
BODY = "Q_CAP","I24": #LOCATION = "PC132" !CDS_LOCATION = "PC132" #SEC = "1" !CDS_SEC = "1";
"A":   PN = "1"  !CDS_PN = "1";
"B":   PN = "2"  !CDS_PN = "2";
BODY = "Q_RES","I25": #LOCATION = "PR455" !CDS_LOCATION = "PR455" #SEC = "1" !CDS_SEC = "1";
"A":   PN = "1"  !CDS_PN = "1";
"B":   PN = "2"  !CDS_PN = "2";
BODY = "Q_CAP","I27": #LOCATION = "PC129" !CDS_LOCATION = "PC129" #SEC = "1" !CDS_SEC = "1";
"A":   PN = "1"  !CDS_PN = "1";
"B":   PN = "2"  !CDS_PN = "2";
BODY = "Q_CAP","I28": #LOCATION = "PC130" !CDS_LOCATION = "PC130" #SEC = "1" !CDS_SEC = "1";
"A":   PN = "1"  !CDS_PN = "1";
"B":   PN = "2"  !CDS_PN = "2";
BODY = "Q_CAP","I29": #LOCATION = "PC123" !CDS_LOCATION = "PC123" #SEC = "1" !CDS_SEC = "1";
"A":   PN = "1"  !CDS_PN = "1";
"B":   PN = "2"  !CDS_PN = "2";
BODY = "Q_CAP","I30": #LOCATION = "PC126" !CDS_LOCATION = "PC126" &SEC = "1" #&CDS_SEC = "1";
"A":   PN = "1"  !CDS_PN = "1";
"B":   PN = "2"  !CDS_PN = "2";
BODY = "Q_RES","I31": #LOCATION = "R453" !CDS_LOCATION = "R453" #SEC = "1" !CDS_SEC = "1";
"A":   PN = "1"  !CDS_PN = "1";
"B":   PN = "2"  !CDS_PN = "2";
BODY = "Q_RES","I33": #LOCATION = "R225" !CDS_LOCATION = "R225" &SEC = "1" #&CDS_SEC = "1";
"A":   PN = "1"  !CDS_PN = "1";
"B":   PN = "2"  !CDS_PN = "2";
BODY = "Q_CAP","I35": #LOCATION = "PC134" !CDS_LOCATION = "PC134" #SEC = "1" !CDS_SEC = "1";
"A":   PN = "1"  !CDS_PN = "1";
"B":   PN = "2"  !CDS_PN = "2";
BODY = "Q_CAP","I36": #LOCATION = "PC135" !CDS_LOCATION = "PC135" #SEC = "1" !CDS_SEC = "1";
"A":   PN = "1"  !CDS_PN = "1";
"B":   PN = "2"  !CDS_PN = "2";
BODY = "Q_CAP","I37": #LOCATION = "PC136" !CDS_LOCATION = "PC136" #SEC = "1" !CDS_SEC = "1";
"A":   PN = "1"  !CDS_PN = "1";
"B":   PN = "2"  !CDS_PN = "2";
BODY = "Q_CAP","I40": #LOCATION = "PC128" !CDS_LOCATION = "PC128" #SEC = "1" !CDS_SEC = "1";
"A":   PN = "1"  !CDS_PN = "1";
"B":   PN = "2"  !CDS_PN = "2";
BODY = "MPQ8633AGLEC807Z","I41": #LOCATION = "PU55" !CDS_LOCATION = "PU55" #SEC = "1" !CDS_SEC = "1";
"AGND":   PN = "2"  !CDS_PN = "2";
"BST":   PN = "1"  !CDS_PN = "1";
"CS":   PN = "3"  !CDS_PN = "3";
"EN":   PN = "8"  !CDS_PN = "8";
"FB":   PN = "7"  !CDS_PN = "7";
"MODE":   PN = "4"  !CDS_PN = "4";
"PGND":   PN = "11_18"  !CDS_PN = "11_18";
"PGOOD":   PN = "9"  !CDS_PN = "9";
"RGND":   PN = "6"  !CDS_PN = "6";
"SW":   PN = "20"  !CDS_PN = "20";
"TRK_REF":   PN = "5"  !CDS_PN = "5";
"VCC":   PN = "19"  !CDS_PN = "19";
"VIN1":   PN = "10"  !CDS_PN = "10";
"VIN2":   PN = "21"  !CDS_PN = "21";
BODY = "Q_CAP","I43": #LOCATION = "C5002" !CDS_LOCATION = "C5002" &SEC = "1" #&CDS_SEC = "1";
"A":   PN = "1"  !CDS_PN = "1";
"B":   PN = "2"  !CDS_PN = "2";
BODY = "Q_CAP","I44": #LOCATION = "PC8000" !CDS_LOCATION = "PC8000" &SEC = "1" #&CDS_SEC = "1";
"A":   PN = "1"  !CDS_PN = "1";
"B":   PN = "2"  !CDS_PN = "2";
BODY = "Q_CAP","I45": #LOCATION = "PC8001" !CDS_LOCATION = "PC8001" &SEC = "1" #&CDS_SEC = "1";
"A":   PN = "1"  !CDS_PN = "1";
"B":   PN = "2"  !CDS_PN = "2";
BODY = "Q_RES","I46": #LOCATION = "PR8000" !CDS_LOCATION = "PR8000" &SEC = "1" #&CDS_SEC = "1";
"A":   PN = "1"  !CDS_PN = "1";
"B":   PN = "2"  !CDS_PN = "2";
BODY = "Q_INDUCTOR","I47": #LOCATION = "PL72" !CDS_LOCATION = "PL72" #SEC = "1" !CDS_SEC = "1";
"1":   PN = "1"  !CDS_PN = "1";
"2":   PN = "2"  !CDS_PN = "2";
DRAWING = "@t6g_mb_lib.t6g(sch_1):page171";
BODY = "Q_CAP","I4": #LOCATION = "PC150_6" !CDS_LOCATION = "PC150_6" &SEC = "1" #&CDS_SEC = "1";
"A":   PN = "1"  !CDS_PN = "1";
"B":   PN = "2"  !CDS_PN = "2";
BODY = "Q_RES","I8": #LOCATION = "PR431" !CDS_LOCATION = "PR431" &SEC = "1" #&CDS_SEC = "1";
"A":   PN = "1"  !CDS_PN = "1";
"B":   PN = "2"  !CDS_PN = "2";
BODY = "Q_CAP","I11": #LOCATION = "PC151" !CDS_LOCATION = "PC151" &SEC = "1" #&CDS_SEC = "1";
"A":   PN = "1"  !CDS_PN = "1";
"B":   PN = "2"  !CDS_PN = "2";
BODY = "Q_RES","I13": #LOCATION = "PR430" !CDS_LOCATION = "PR430" &SEC = "1" #&CDS_SEC = "1";
"A":   PN = "1"  !CDS_PN = "1";
"B":   PN = "2"  !CDS_PN = "2";
BODY = "Q_CAP","I14": #LOCATION = "PC152_C0P0_6" !CDS_LOCATION = "PC152_C0P0_6" &SEC = "1" #&CDS_SEC = "1";
"A":   PN = "1"  !CDS_PN = "1";
"B":   PN = "2"  !CDS_PN = "2";
BODY = "ISL99390FRZTR5935","I18": #LOCATION = "PU48" !CDS_LOCATION = "PU48" &SEC = "1" #&CDS_SEC = "1";
"AGND":   PN = "2"  !CDS_PN = "2";
"BOOT":   PN = "33"  !CDS_PN = "33";
"DNC":   PN = "31"  !CDS_PN = "31";
"EN":   PN = "35"  !CDS_PN = "35";
"GL1":   PN = "6"  !CDS_PN = "6";
"GL2":   PN = "41"  !CDS_PN = "41";
"IOUT":   PN = "38"  !CDS_PN = "38";
"LSET":   PN = "37"  !CDS_PN = "37";
"PGND1":   PN = "5"  !CDS_PN = "5";
"PGND2":   PN = "7_9-20_24"  !CDS_PN = "7_9-20_24";
"PGND3":   PN = "40"  !CDS_PN = "40";
"PHASE":   PN = "32"  !CDS_PN = "32";
"PVCC":   PN = "4"  !CDS_PN = "4";
"PWM":   PN = "34"  !CDS_PN = "34";
"REFIN":   PN = "39"  !CDS_PN = "39";
"SW":   PN = "10_19"  !CDS_PN = "10_19";
"TOUT_FLT":   PN = "36"  !CDS_PN = "36";
"VCC":   PN = "3"  !CDS_PN = "3";
"VIN1":   PN = "25_29"  !CDS_PN = "25_29";
"VIN2":   PN = "30"  !CDS_PN = "30";
"VOS":   PN = "1"  !CDS_PN = "1";
BODY = "Q_RES","I21": #LOCATION = "PR433" !CDS_LOCATION = "PR433" &SEC = "1" #&CDS_SEC = "1";
"A":   PN = "1"  !CDS_PN = "1";
"B":   PN = "2"  !CDS_PN = "2";
BODY = "Q_RES","I22": #LOCATION = "PR500" !CDS_LOCATION = "PR500" &SEC = "1" #&CDS_SEC = "1";
"A":   PN = "1"  !CDS_PN = "1";
"B":   PN = "2"  !CDS_PN = "2";
BODY = "Q_CAP","I23": #LOCATION = "PC182" !CDS_LOCATION = "PC182" &SEC = "1" #&CDS_SEC = "1";
"A":   PN = "1"  !CDS_PN = "1";
"B":   PN = "2"  !CDS_PN = "2";
BODY = "Q_CAP","I24": #LOCATION = "PC153_6" !CDS_LOCATION = "PC153_6" &SEC = "1" #&CDS_SEC = "1";
"A":   PN = "1"  !CDS_PN = "1";
"B":   PN = "2"  !CDS_PN = "2";
BODY = "Q_RES","I26": #LOCATION = "PR432" !CDS_LOCATION = "PR432" &SEC = "1" #&CDS_SEC = "1";
"A":   PN = "1"  !CDS_PN = "1";
"B":   PN = "2"  !CDS_PN = "2";
BODY = "Q_CAP","I27": #LOCATION = "PC154_6" !CDS_LOCATION = "PC154_6" &SEC = "1" #&CDS_SEC = "1";
"A":   PN = "1"  !CDS_PN = "1";
"B":   PN = "2"  !CDS_PN = "2";
BODY = "Q_CAP","I28": #LOCATION = "PC157_6" !CDS_LOCATION = "PC157_6" &SEC = "1" #&CDS_SEC = "1";
"A":   PN = "1"  !CDS_PN = "1";
"B":   PN = "2"  !CDS_PN = "2";
BODY = "Q_CAP","I29": #LOCATION = "PC158_6" !CDS_LOCATION = "PC158_6" &SEC = "1" #&CDS_SEC = "1";
"A":   PN = "1"  !CDS_PN = "1";
"B":   PN = "2"  !CDS_PN = "2";
BODY = "Q_RES","I31": #LOCATION = "PR501" !CDS_LOCATION = "PR501" &SEC = "1" #&CDS_SEC = "1";
"A":   PN = "1"  !CDS_PN = "1";
"B":   PN = "2"  !CDS_PN = "2";
BODY = "Q_RES","I32": #LOCATION = "PR355" !CDS_LOCATION = "PR355" &SEC = "1" #&CDS_SEC = "1";
"A":   PN = "1"  !CDS_PN = "1";
"B":   PN = "2"  !CDS_PN = "2";
BODY = "Q_CAP","I33": #LOCATION = "PC566_5" !CDS_LOCATION = "PC566_5" &SEC = "1" #&CDS_SEC = "1";
"A":   PN = "1"  !CDS_PN = "1";
"B":   PN = "2"  !CDS_PN = "2";
BODY = "Q_RES","I36": #LOCATION = "PR353" !CDS_LOCATION = "PR353" &SEC = "1" #&CDS_SEC = "1";
"A":   PN = "1"  !CDS_PN = "1";
"B":   PN = "2"  !CDS_PN = "2";
BODY = "Q_CAP","I38": #LOCATION = "PC567" !CDS_LOCATION = "PC567" &SEC = "1" #&CDS_SEC = "1";
"A":   PN = "1"  !CDS_PN = "1";
"B":   PN = "2"  !CDS_PN = "2";
BODY = "Q_RES","I40": #LOCATION = "PR352" !CDS_LOCATION = "PR352" &SEC = "1" #&CDS_SEC = "1";
"A":   PN = "1"  !CDS_PN = "1";
"B":   PN = "2"  !CDS_PN = "2";
BODY = "Q_CAP","I42": #LOCATION = "PC568_C0P0_5" !CDS_LOCATION = "PC568_C0P0_5" &SEC = "1" #&CDS_SEC = "1";
"A":   PN = "1"  !CDS_PN = "1";
"B":   PN = "2"  !CDS_PN = "2";
BODY = "Q_CAP","I44": #LOCATION = "PC570_5" !CDS_LOCATION = "PC570_5" &SEC = "1" #&CDS_SEC = "1";
"A":   PN = "1"  !CDS_PN = "1";
"B":   PN = "2"  !CDS_PN = "2";
BODY = "Q_RES","I45": #LOCATION = "PR354" !CDS_LOCATION = "PR354" &SEC = "1" #&CDS_SEC = "1";
"A":   PN = "1"  !CDS_PN = "1";
"B":   PN = "2"  !CDS_PN = "2";
BODY = "Q_CAP","I46": #LOCATION = "PC184" !CDS_LOCATION = "PC184" &SEC = "1" #&CDS_SEC = "1";
"A":   PN = "1"  !CDS_PN = "1";
"B":   PN = "2"  !CDS_PN = "2";
BODY = "Q_CAP","I47": #LOCATION = "PC569_5" !CDS_LOCATION = "PC569_5" &SEC = "1" #&CDS_SEC = "1";
"A":   PN = "1"  !CDS_PN = "1";
"B":   PN = "2"  !CDS_PN = "2";
BODY = "Q_CAP","I48": #LOCATION = "PC571_5" !CDS_LOCATION = "PC571_5" &SEC = "1" #&CDS_SEC = "1";
"A":   PN = "1"  !CDS_PN = "1";
"B":   PN = "2"  !CDS_PN = "2";
BODY = "Q_CAP","I49": #LOCATION = "PC572_5" !CDS_LOCATION = "PC572_5" &SEC = "1" #&CDS_SEC = "1";
"A":   PN = "1"  !CDS_PN = "1";
"B":   PN = "2"  !CDS_PN = "2";
BODY = "Q_INDUCTOR","I51": #LOCATION = "PL50" !CDS_LOCATION = "PL50" &SEC = "1" #&CDS_SEC = "1";
"1":   PN = "1"  !CDS_PN = "1";
"2":   PN = "2"  !CDS_PN = "2";
BODY = "Q_INDUCTOR4P_14","I52": #LOCATION = "PL70" !CDS_LOCATION = "PL70" &SEC = "1" #&CDS_SEC = "1";
"1":   PN = "1"  !CDS_PN = "1";
"2":   PN = "2"  !CDS_PN = "2";
"3":   PN = "3"  !CDS_PN = "3";
"4":   PN = "4"  !CDS_PN = "4";
BODY = "Q_CAP","I54": #LOCATION = "PC161" !CDS_LOCATION = "PC161" &SEC = "1" #&CDS_SEC = "1";
"A":   PN = "1"  !CDS_PN = "1";
"B":   PN = "2"  !CDS_PN = "2";
BODY = "Q_CAP","I55": #LOCATION = "PC159_6" !CDS_LOCATION = "PC159_6" &SEC = "1" #&CDS_SEC = "1";
"A":   PN = "1"  !CDS_PN = "1";
"B":   PN = "2"  !CDS_PN = "2";
BODY = "Q_CAP","I59": #LOCATION = "PC163_6" !CDS_LOCATION = "PC163_6" &SEC = "1" #&CDS_SEC = "1";
"A":   PN = "1"  !CDS_PN = "1";
"B":   PN = "2"  !CDS_PN = "2";
BODY = "Q_CAP","I60": #LOCATION = "PC166_6" !CDS_LOCATION = "PC166_6" &SEC = "1" #&CDS_SEC = "1";
"A":   PN = "1"  !CDS_PN = "1";
"B":   PN = "2"  !CDS_PN = "2";
BODY = "Q_CAP","I63": #LOCATION = "PC574" !CDS_LOCATION = "PC574" &SEC = "1" #&CDS_SEC = "1";
"A":   PN = "1"  !CDS_PN = "1";
"B":   PN = "2"  !CDS_PN = "2";
BODY = "Q_INDUCTOR4P_14","I64": #LOCATION = "PL61" !CDS_LOCATION = "PL61" &SEC = "1" #&CDS_SEC = "1";
"1":   PN = "1"  !CDS_PN = "1";
"2":   PN = "2"  !CDS_PN = "2";
"3":   PN = "3"  !CDS_PN = "3";
"4":   PN = "4"  !CDS_PN = "4";
BODY = "Q_CAP","I66": #LOCATION = "PC573_5" !CDS_LOCATION = "PC573_5" &SEC = "1" #&CDS_SEC = "1";
"A":   PN = "1"  !CDS_PN = "1";
"B":   PN = "2"  !CDS_PN = "2";
BODY = "Q_CAP","I69": #LOCATION = "PC575_5" !CDS_LOCATION = "PC575_5" &SEC = "1" #&CDS_SEC = "1";
"A":   PN = "1"  !CDS_PN = "1";
"B":   PN = "2"  !CDS_PN = "2";
BODY = "Q_CAP","I71": #LOCATION = "PC576_5" !CDS_LOCATION = "PC576_5" &SEC = "1" #&CDS_SEC = "1";
"A":   PN = "1"  !CDS_PN = "1";
"B":   PN = "2"  !CDS_PN = "2";
BODY = "ISL99390FRZTR5935","I73": #LOCATION = "PU10" !CDS_LOCATION = "PU10" &SEC = "1" #&CDS_SEC = "1";
"AGND":   PN = "2"  !CDS_PN = "2";
"BOOT":   PN = "33"  !CDS_PN = "33";
"DNC":   PN = "31"  !CDS_PN = "31";
"EN":   PN = "35"  !CDS_PN = "35";
"GL1":   PN = "6"  !CDS_PN = "6";
"GL2":   PN = "41"  !CDS_PN = "41";
"IOUT":   PN = "38"  !CDS_PN = "38";
"LSET":   PN = "37"  !CDS_PN = "37";
"PGND1":   PN = "5"  !CDS_PN = "5";
"PGND2":   PN = "7_9-20_24"  !CDS_PN = "7_9-20_24";
"PGND3":   PN = "40"  !CDS_PN = "40";
"PHASE":   PN = "32"  !CDS_PN = "32";
"PVCC":   PN = "4"  !CDS_PN = "4";
"PWM":   PN = "34"  !CDS_PN = "34";
"REFIN":   PN = "39"  !CDS_PN = "39";
"SW":   PN = "10_19"  !CDS_PN = "10_19";
"TOUT_FLT":   PN = "36"  !CDS_PN = "36";
"VCC":   PN = "3"  !CDS_PN = "3";
"VIN1":   PN = "25_29"  !CDS_PN = "25_29";
"VIN2":   PN = "30"  !CDS_PN = "30";
"VOS":   PN = "1"  !CDS_PN = "1";
DRAWING = "@t6g_mb_lib.t6g(sch_1):page175";
BODY = "Q_RES","I2": #LOCATION = "R8047" !CDS_LOCATION = "R8047" &SEC = "1" #&CDS_SEC = "1";
"A":   PN = "1"  !CDS_PN = "1";
"B":   PN = "2"  !CDS_PN = "2";
BODY = "Q_CAP","I3": #LOCATION = "C8066" !CDS_LOCATION = "C8066" &SEC = "1" #&CDS_SEC = "1";
"A":   PN = "1"  !CDS_PN = "1";
"B":   PN = "2"  !CDS_PN = "2";
BODY = "MOSFET_N","I6": #LOCATION = "PQ14" !CDS_LOCATION = "PQ14" &SEC = "1" #&CDS_SEC = "1";
"DRAIN":   PN = "D"  !CDS_PN = "D";
"GATE":   PN = "G"  !CDS_PN = "G";
"SOURCE":   PN = "S"  !CDS_PN = "S";
BODY = "Q_RES","I8": #LOCATION = "PR54" !CDS_LOCATION = "PR54" &SEC = "1" #&CDS_SEC = "1";
"A":   PN = "1"  !CDS_PN = "1";
"B":   PN = "2"  !CDS_PN = "2";
BODY = "Q_RES","I9": #LOCATION = "PR53" !CDS_LOCATION = "PR53" &SEC = "1" #&CDS_SEC = "1";
"A":   PN = "1"  !CDS_PN = "1";
"B":   PN = "2"  !CDS_PN = "2";
BODY = "Q_RES","I12": #LOCATION = "PR67" !CDS_LOCATION = "PR67" &SEC = "1" #&CDS_SEC = "1";
"A":   PN = "1"  !CDS_PN = "1";
"B":   PN = "2"  !CDS_PN = "2";
BODY = "MOSFET_PCH_GDS_ESD_PROTECTED","I13": #LOCATION = "PQ10" !CDS_LOCATION = "PQ10" &SEC = "1" #&CDS_SEC = "1";
"D":   PN = "D"  !CDS_PN = "D";
"G":   PN = "G"  !CDS_PN = "G";
"S":   PN = "S"  !CDS_PN = "S";
BODY = "Q_RES","I17": #LOCATION = "PR55" !CDS_LOCATION = "PR55" &SEC = "1" #&CDS_SEC = "1";
"A":   PN = "1"  !CDS_PN = "1";
"B":   PN = "2"  !CDS_PN = "2";
BODY = "Q_RES","I19": #LOCATION = "PR50" !CDS_LOCATION = "PR50" &SEC = "1" #&CDS_SEC = "1";
"A":   PN = "1"  !CDS_PN = "1";
"B":   PN = "2"  !CDS_PN = "2";
BODY = "Q_RES","I22": #LOCATION = "PR52" !CDS_LOCATION = "PR52" &SEC = "1" #&CDS_SEC = "1";
"A":   PN = "1"  !CDS_PN = "1";
"B":   PN = "2"  !CDS_PN = "2";
BODY = "Q_RES","I23": #LOCATION = "PR49" !CDS_LOCATION = "PR49" &SEC = "1" #&CDS_SEC = "1";
"A":   PN = "1"  !CDS_PN = "1";
"B":   PN = "2"  !CDS_PN = "2";
BODY = "Q_RES","I28": #LOCATION = "PR40" !CDS_LOCATION = "PR40" &SEC = "1" #&CDS_SEC = "1";
"A":   PN = "1"  !CDS_PN = "1";
"B":   PN = "2"  !CDS_PN = "2";
BODY = "Q_RES","I32": #LOCATION = "R8042" !CDS_LOCATION = "R8042" &SEC = "1" #&CDS_SEC = "1";
"A":   PN = "1"  !CDS_PN = "1";
"B":   PN = "2"  !CDS_PN = "2";
BODY = "Q_CAP","I33": #LOCATION = "C303" !CDS_LOCATION = "C303" &SEC = "1" #&CDS_SEC = "1";
"A":   PN = "1"  !CDS_PN = "1";
"B":   PN = "2"  !CDS_PN = "2";
BODY = "Q_CAP","I34": #LOCATION = "C304" !CDS_LOCATION = "C304" &SEC = "1" #&CDS_SEC = "1";
"A":   PN = "1"  !CDS_PN = "1";
"B":   PN = "2"  !CDS_PN = "2";
BODY = "Q_CAP","I35": #LOCATION = "C305" !CDS_LOCATION = "C305" &SEC = "1" #&CDS_SEC = "1";
"A":   PN = "1"  !CDS_PN = "1";
"B":   PN = "2"  !CDS_PN = "2";
BODY = "Q_RES","I36": #LOCATION = "PR51" !CDS_LOCATION = "PR51" &SEC = "1" #&CDS_SEC = "1";
"A":   PN = "1"  !CDS_PN = "1";
"B":   PN = "2"  !CDS_PN = "2";
BODY = "Q_RES","I40": #LOCATION = "PR41" !CDS_LOCATION = "PR41" &SEC = "1" #&CDS_SEC = "1";
"A":   PN = "1"  !CDS_PN = "1";
"B":   PN = "2"  !CDS_PN = "2";
BODY = "Q_RES","I42": #LOCATION = "R8043" !CDS_LOCATION = "R8043" &SEC = "1" #&CDS_SEC = "1";
"A":   PN = "1"  !CDS_PN = "1";
"B":   PN = "2"  !CDS_PN = "2";
BODY = "Q_RES","I43": #LOCATION = "R8045" !CDS_LOCATION = "R8045" &SEC = "1" #&CDS_SEC = "1";
"A":   PN = "1"  !CDS_PN = "1";
"B":   PN = "2"  !CDS_PN = "2";
BODY = "Q_RES","I44": #LOCATION = "R8048" !CDS_LOCATION = "R8048" &SEC = "1" #&CDS_SEC = "1";
"A":   PN = "1"  !CDS_PN = "1";
"B":   PN = "2"  !CDS_PN = "2";
BODY = "Q_CAP","I50": #LOCATION = "PC67" !CDS_LOCATION = "PC67" &SEC = "1" #&CDS_SEC = "1";
"A":   PN = "1"  !CDS_PN = "1";
"B":   PN = "2"  !CDS_PN = "2";
BODY = "Q_RES","I51": #LOCATION = "PR74" !CDS_LOCATION = "PR74" &SEC = "1" #&CDS_SEC = "1";
"A":   PN = "1"  !CDS_PN = "1";
"B":   PN = "2"  !CDS_PN = "2";
BODY = "Q_RES","I53": #LOCATION = "R8066" !CDS_LOCATION = "R8066" &SEC = "1" #&CDS_SEC = "1";
"A":   PN = "1"  !CDS_PN = "1";
"B":   PN = "2"  !CDS_PN = "2";
BODY = "Q_RES","I54": #LOCATION = "R8065" !CDS_LOCATION = "R8065" &SEC = "1" #&CDS_SEC = "1";
"A":   PN = "1"  !CDS_PN = "1";
"B":   PN = "2"  !CDS_PN = "2";
BODY = "Q_CAP","I55": #LOCATION = "C8072" !CDS_LOCATION = "C8072" &SEC = "1" #&CDS_SEC = "1";
"A":   PN = "1"  !CDS_PN = "1";
"B":   PN = "2"  !CDS_PN = "2";
BODY = "Q_RES","I59": #LOCATION = "PR600" !CDS_LOCATION = "PR600" &SEC = "1" #&CDS_SEC = "1";
"A":   PN = "1"  !CDS_PN = "1";
"B":   PN = "2"  !CDS_PN = "2";
BODY = "Q_CAP","I60": #LOCATION = "PC74" !CDS_LOCATION = "PC74" &SEC = "1" #&CDS_SEC = "1";
"A":   PN = "1"  !CDS_PN = "1";
"B":   PN = "2"  !CDS_PN = "2";
BODY = "Q_CAP","I63": #LOCATION = "PC73" !CDS_LOCATION = "PC73" &SEC = "1" #&CDS_SEC = "1";
"A":   PN = "1"  !CDS_PN = "1";
"B":   PN = "2"  !CDS_PN = "2";
BODY = "Q_RES","I66": #LOCATION = "R8064" !CDS_LOCATION = "R8064" &SEC = "1" #&CDS_SEC = "1";
"A":   PN = "1"  !CDS_PN = "1";
"B":   PN = "2"  !CDS_PN = "2";
BODY = "Q_RES","I67": #LOCATION = "R8063" !CDS_LOCATION = "R8063" &SEC = "1" #&CDS_SEC = "1";
"A":   PN = "1"  !CDS_PN = "1";
"B":   PN = "2"  !CDS_PN = "2";
BODY = "Q_RES","I68": #LOCATION = "R8070" !CDS_LOCATION = "R8070" &SEC = "1" #&CDS_SEC = "1";
"A":   PN = "1"  !CDS_PN = "1";
"B":   PN = "2"  !CDS_PN = "2";
BODY = "Q_CAP","I69": #LOCATION = "PC71" !CDS_LOCATION = "PC71" &SEC = "1" #&CDS_SEC = "1";
"A":   PN = "1"  !CDS_PN = "1";
"B":   PN = "2"  !CDS_PN = "2";
BODY = "Q_RES","I70": #LOCATION = "PR69" !CDS_LOCATION = "PR69" &SEC = "1" #&CDS_SEC = "1";
"A":   PN = "1"  !CDS_PN = "1";
"B":   PN = "2"  !CDS_PN = "2";
BODY = "Q_RES","I71": #LOCATION = "R8075" !CDS_LOCATION = "R8075" &SEC = "1" #&CDS_SEC = "1";
"A":   PN = "1"  !CDS_PN = "1";
"B":   PN = "2"  !CDS_PN = "2";
BODY = "Q_CAP","I73": #LOCATION = "PC78" !CDS_LOCATION = "PC78" &SEC = "1" #&CDS_SEC = "1";
"A":   PN = "1"  !CDS_PN = "1";
"B":   PN = "2"  !CDS_PN = "2";
BODY = "Q_CAP","I75": #LOCATION = "PC77" !CDS_LOCATION = "PC77" &SEC = "1" #&CDS_SEC = "1";
"A":   PN = "1"  !CDS_PN = "1";
"B":   PN = "2"  !CDS_PN = "2";
BODY = "Q_RES","I76": #LOCATION = "PR532" !CDS_LOCATION = "PR532" &SEC = "1" #&CDS_SEC = "1";
"A":   PN = "1"  !CDS_PN = "1";
"B":   PN = "2"  !CDS_PN = "2";
BODY = "Q_RES","I77": #LOCATION = "PR32" !CDS_LOCATION = "PR32" &SEC = "1" #&CDS_SEC = "1";
"A":   PN = "1"  !CDS_PN = "1";
"B":   PN = "2"  !CDS_PN = "2";
BODY = "Q_RES","I78": #LOCATION = "PR68" !CDS_LOCATION = "PR68" &SEC = "1" #&CDS_SEC = "1";
"A":   PN = "1"  !CDS_PN = "1";
"B":   PN = "2"  !CDS_PN = "2";
BODY = "Q_CAP","I80": #LOCATION = "PC68" !CDS_LOCATION = "PC68" &SEC = "1" #&CDS_SEC = "1";
"A":   PN = "1"  !CDS_PN = "1";
"B":   PN = "2"  !CDS_PN = "2";
BODY = "Q_RES","I81": #LOCATION = "R8073" !CDS_LOCATION = "R8073" &SEC = "1" #&CDS_SEC = "1";
"A":   PN = "1"  !CDS_PN = "1";
"B":   PN = "2"  !CDS_PN = "2";
BODY = "Q_RES","I82": #LOCATION = "R8072" !CDS_LOCATION = "R8072" &SEC = "1" #&CDS_SEC = "1";
"A":   PN = "1"  !CDS_PN = "1";
"B":   PN = "2"  !CDS_PN = "2";
BODY = "Q_RES","I83": #LOCATION = "R61" !CDS_LOCATION = "R61" &SEC = "1" #&CDS_SEC = "1";
"A":   PN = "1"  !CDS_PN = "1";
"B":   PN = "2"  !CDS_PN = "2";
BODY = "Q_RES","I84": #LOCATION = "PR62" !CDS_LOCATION = "PR62" &SEC = "1" #&CDS_SEC = "1";
"A":   PN = "1"  !CDS_PN = "1";
"B":   PN = "2"  !CDS_PN = "2";
BODY = "Q_RES","I85": #LOCATION = "R8071" !CDS_LOCATION = "R8071" &SEC = "1" #&CDS_SEC = "1";
"A":   PN = "1"  !CDS_PN = "1";
"B":   PN = "2"  !CDS_PN = "2";
BODY = "Q_CAP","I86": #LOCATION = "C8069" !CDS_LOCATION = "C8069" &SEC = "1" #&CDS_SEC = "1";
"A":   PN = "1"  !CDS_PN = "1";
"B":   PN = "2"  !CDS_PN = "2";
BODY = "Q_RES","I88": #LOCATION = "R8058" !CDS_LOCATION = "R8058" &SEC = "1" #&CDS_SEC = "1";
"A":   PN = "1"  !CDS_PN = "1";
"B":   PN = "2"  !CDS_PN = "2";
BODY = "Q_RES","I89": #LOCATION = "R8057" !CDS_LOCATION = "R8057" &SEC = "1" #&CDS_SEC = "1";
"A":   PN = "1"  !CDS_PN = "1";
"B":   PN = "2"  !CDS_PN = "2";
BODY = "Q_RES","I90": #LOCATION = "R8056" !CDS_LOCATION = "R8056" &SEC = "1" #&CDS_SEC = "1";
"A":   PN = "1"  !CDS_PN = "1";
"B":   PN = "2"  !CDS_PN = "2";
BODY = "Q_CAP","I91": #LOCATION = "C8070" !CDS_LOCATION = "C8070" &SEC = "1" #&CDS_SEC = "1";
"A":   PN = "1"  !CDS_PN = "1";
"B":   PN = "2"  !CDS_PN = "2";
BODY = "Q_CAP","I94": #LOCATION = "PC15" !CDS_LOCATION = "PC15" &SEC = "1" #&CDS_SEC = "1";
"A":   PN = "1"  !CDS_PN = "1";
"B":   PN = "2"  !CDS_PN = "2";
BODY = "Q_CAP","I96": #LOCATION = "PC14" !CDS_LOCATION = "PC14" &SEC = "1" #&CDS_SEC = "1";
"A":   PN = "1"  !CDS_PN = "1";
"B":   PN = "2"  !CDS_PN = "2";
BODY = "Q_CAP","I98": #LOCATION = "PC76" !CDS_LOCATION = "PC76" &SEC = "1" #&CDS_SEC = "1";
"A":   PN = "1"  !CDS_PN = "1";
"B":   PN = "2"  !CDS_PN = "2";
BODY = "Q_CAP","I100": #LOCATION = "PC75" !CDS_LOCATION = "PC75" &SEC = "1" #&CDS_SEC = "1";
"A":   PN = "1"  !CDS_PN = "1";
"B":   PN = "2"  !CDS_PN = "2";
BODY = "Q_RES","I126": #LOCATION = "PR76" !CDS_LOCATION = "PR76" &SEC = "1" #&CDS_SEC = "1";
"A":   PN = "1"  !CDS_PN = "1";
"B":   PN = "2"  !CDS_PN = "2";
BODY = "RAA229620GNPHA0","I128": #LOCATION = "PU12" !CDS_LOCATION = "PU12" &SEC = "1" #&CDS_SEC = "1";
"CS0":   PN = "38"  !CDS_PN = "38";
"CS1":   PN = "37"  !CDS_PN = "37";
"CS2":   PN = "36"  !CDS_PN = "36";
"CS3":   PN = "35"  !CDS_PN = "35";
"CS4":   PN = "34"  !CDS_PN = "34";
"CS5":   PN = "33"  !CDS_PN = "33";
"CS6":   PN = "32"  !CDS_PN = "32";
"CS7":   PN = "31"  !CDS_PN = "31";
"CS8":   PN = "30"  !CDS_PN = "30";
"CS9":   PN = "29"  !CDS_PN = "29";
"CS10":   PN = "28"  !CDS_PN = "28";
"CS11":   PN = "27"  !CDS_PN = "27";
"EN0":   PN = "17"  !CDS_PN = "17";
"EN1||ADDR_CFG":   PN = "42"  !CDS_PN = "42";
"NPMALERT":   PN = "15"  !CDS_PN = "15";
"OCP_L":   PN = "41"  !CDS_PN = "41";
"PG0":   PN = "16"  !CDS_PN = "16";
"PG1":   PN = "20"  !CDS_PN = "20";
"PMSCL":   PN = "14"  !CDS_PN = "14";
"PMSDA":   PN = "13"  !CDS_PN = "13";
"PWM0":   PN = "1"  !CDS_PN = "1";
"PWM1":   PN = "2"  !CDS_PN = "2";
"PWM2":   PN = "3"  !CDS_PN = "3";
"PWM3":   PN = "4"  !CDS_PN = "4";
"PWM4":   PN = "5"  !CDS_PN = "5";
"PWM5":   PN = "6"  !CDS_PN = "6";
"PWM6":   PN = "7"  !CDS_PN = "7";
"PWM7":   PN = "8"  !CDS_PN = "8";
"PWM8":   PN = "9"  !CDS_PN = "9";
"PWM9":   PN = "10"  !CDS_PN = "10";
"PWM10":   PN = "11"  !CDS_PN = "11";
"PWM11":   PN = "12"  !CDS_PN = "12";
"RESET_L":   PN = "18"  !CDS_PN = "18";
"RGND0":   PN = "26"  !CDS_PN = "26";
"RGND1":   PN = "39"  !CDS_PN = "39";
"SVC":   PN = "22"  !CDS_PN = "22";
"SVD":   PN = "21"  !CDS_PN = "21";
"SVTI":   PN = "24"  !CDS_PN = "24";
"SVTO":   PN = "23"  !CDS_PN = "23";
"TEMP0":   PN = "44"  !CDS_PN = "44";
"TEMP1":   PN = "43"  !CDS_PN = "43";
"TH_GND":   PN = "TH"  !CDS_PN = "TH";
"VCC":   PN = "47"  !CDS_PN = "47";
"VCCS":   PN = "48"  !CDS_PN = "48";
"VDDIO":   PN = "19"  !CDS_PN = "19";
"VINSEN":   PN = "46"  !CDS_PN = "46";
"VMON||IINSEN":   PN = "45"  !CDS_PN = "45";
"VSEN0":   PN = "25"  !CDS_PN = "25";
"VSEN1":   PN = "40"  !CDS_PN = "40";
BODY = "Q_RES","I129": #LOCATION = "R6086" !CDS_LOCATION = "R6086" &SEC = "1" #&CDS_SEC = "1";
"A":   PN = "1"  !CDS_PN = "1";
"B":   PN = "2"  !CDS_PN = "2";
BODY = "Q_CAP","I130": #LOCATION = "C5013" !CDS_LOCATION = "C5013" &SEC = "1" #&CDS_SEC = "1";
"A":   PN = "1"  !CDS_PN = "1";
"B":   PN = "2"  !CDS_PN = "2";
BODY = "Q_CAP","I133": #LOCATION = "C5005" !CDS_LOCATION = "C5005" &SEC = "1" #&CDS_SEC = "1";
"A":   PN = "1"  !CDS_PN = "1";
"B":   PN = "2"  !CDS_PN = "2";
BODY = "Q_CAP","I135": #LOCATION = "C5004" !CDS_LOCATION = "C5004" &SEC = "1" #&CDS_SEC = "1";
"A":   PN = "1"  !CDS_PN = "1";
"B":   PN = "2"  !CDS_PN = "2";
BODY = "Q_RES","I136": #LOCATION = "PR8008" !CDS_LOCATION = "PR8008" &SEC = "1" #&CDS_SEC = "1";
"A":   PN = "1"  !CDS_PN = "1";
"B":   PN = "2"  !CDS_PN = "2";
BODY = "Q_RES","I137": #LOCATION = "PR8007" !CDS_LOCATION = "PR8007" &SEC = "1" #&CDS_SEC = "1";
"A":   PN = "1"  !CDS_PN = "1";
"B":   PN = "2"  !CDS_PN = "2";
DRAWING = "@t6g_mb_lib.t6g(sch_1):page180";
BODY = "Q_CAP","I2": #LOCATION = "PC146_8" !CDS_LOCATION = "PC146_8" &SEC = "1" #&CDS_SEC = "1";
"A":   PN = "1"  !CDS_PN = "1";
"B":   PN = "2"  !CDS_PN = "2";
BODY = "Q_RES","I4": #LOCATION = "PR97" !CDS_LOCATION = "PR97" &SEC = "1" #&CDS_SEC = "1";
"A":   PN = "1"  !CDS_PN = "1";
"B":   PN = "2"  !CDS_PN = "2";
BODY = "Q_CAP","I10": #LOCATION = "PC142" !CDS_LOCATION = "PC142" &SEC = "1" #&CDS_SEC = "1";
"A":   PN = "1"  !CDS_PN = "1";
"B":   PN = "2"  !CDS_PN = "2";
BODY = "Q_RES","I12": #LOCATION = "PR99" !CDS_LOCATION = "PR99" &SEC = "1" #&CDS_SEC = "1";
"A":   PN = "1"  !CDS_PN = "1";
"B":   PN = "2"  !CDS_PN = "2";
BODY = "Q_CAP","I13": #LOCATION = "PC144_IOP0_2" !CDS_LOCATION = "PC144_IOP0_2" &SEC = "1" #&CDS_SEC = "1";
"A":   PN = "1"  !CDS_PN = "1";
"B":   PN = "2"  !CDS_PN = "2";
BODY = "ISL99390FRZTR5935","I15": #LOCATION = "PU18" !CDS_LOCATION = "PU18" &SEC = "1" #&CDS_SEC = "1";
"AGND":   PN = "2"  !CDS_PN = "2";
"BOOT":   PN = "33"  !CDS_PN = "33";
"DNC":   PN = "31"  !CDS_PN = "31";
"EN":   PN = "35"  !CDS_PN = "35";
"GL1":   PN = "6"  !CDS_PN = "6";
"GL2":   PN = "41"  !CDS_PN = "41";
"IOUT":   PN = "38"  !CDS_PN = "38";
"LSET":   PN = "37"  !CDS_PN = "37";
"PGND1":   PN = "5"  !CDS_PN = "5";
"PGND2":   PN = "7_9-20_24"  !CDS_PN = "7_9-20_24";
"PGND3":   PN = "40"  !CDS_PN = "40";
"PHASE":   PN = "32"  !CDS_PN = "32";
"PVCC":   PN = "4"  !CDS_PN = "4";
"PWM":   PN = "34"  !CDS_PN = "34";
"REFIN":   PN = "39"  !CDS_PN = "39";
"SW":   PN = "10_19"  !CDS_PN = "10_19";
"TOUT_FLT":   PN = "36"  !CDS_PN = "36";
"VCC":   PN = "3"  !CDS_PN = "3";
"VIN1":   PN = "25_29"  !CDS_PN = "25_29";
"VIN2":   PN = "30"  !CDS_PN = "30";
"VOS":   PN = "1"  !CDS_PN = "1";
BODY = "Q_RES","I17": #LOCATION = "PR102" !CDS_LOCATION = "PR102" &SEC = "1" #&CDS_SEC = "1";
"A":   PN = "1"  !CDS_PN = "1";
"B":   PN = "2"  !CDS_PN = "2";
BODY = "Q_CAP","I18": #LOCATION = "PC149_2" !CDS_LOCATION = "PC149_2" &SEC = "1" #&CDS_SEC = "1";
"A":   PN = "1"  !CDS_PN = "1";
"B":   PN = "2"  !CDS_PN = "2";
BODY = "Q_CAP","I20": #LOCATION = "PC145_7" !CDS_LOCATION = "PC145_7" &SEC = "1" #&CDS_SEC = "1";
"A":   PN = "1"  !CDS_PN = "1";
"B":   PN = "2"  !CDS_PN = "2";
BODY = "Q_RES","I22": #LOCATION = "PR98" !CDS_LOCATION = "PR98" &SEC = "1" #&CDS_SEC = "1";
"A":   PN = "1"  !CDS_PN = "1";
"B":   PN = "2"  !CDS_PN = "2";
BODY = "Q_CAP","I28": #LOCATION = "PC143" !CDS_LOCATION = "PC143" &SEC = "1" #&CDS_SEC = "1";
"A":   PN = "1"  !CDS_PN = "1";
"B":   PN = "2"  !CDS_PN = "2";
BODY = "Q_RES","I29": #LOCATION = "PR100" !CDS_LOCATION = "PR100" &SEC = "1" #&CDS_SEC = "1";
"A":   PN = "1"  !CDS_PN = "1";
"B":   PN = "2"  !CDS_PN = "2";
BODY = "Q_CAP","I31": #LOCATION = "PC147_IOP0_1" !CDS_LOCATION = "PC147_IOP0_1" &SEC = "1" #&CDS_SEC = "1";
"A":   PN = "1"  !CDS_PN = "1";
"B":   PN = "2"  !CDS_PN = "2";
BODY = "Q_RES","I34": #LOCATION = "PR101" !CDS_LOCATION = "PR101" &SEC = "1" #&CDS_SEC = "1";
"A":   PN = "1"  !CDS_PN = "1";
"B":   PN = "2"  !CDS_PN = "2";
BODY = "Q_RES","I36": #LOCATION = "PR223" !CDS_LOCATION = "PR223" &SEC = "1" #&CDS_SEC = "1";
"A":   PN = "1"  !CDS_PN = "1";
"B":   PN = "2"  !CDS_PN = "2";
BODY = "Q_CAP","I37": #LOCATION = "PC159" !CDS_LOCATION = "PC159" &SEC = "1" #&CDS_SEC = "1";
"A":   PN = "1"  !CDS_PN = "1";
"B":   PN = "2"  !CDS_PN = "2";
BODY = "Q_RES","I39": #LOCATION = "PR104" !CDS_LOCATION = "PR104" &SEC = "1" #&CDS_SEC = "1";
"A":   PN = "1"  !CDS_PN = "1";
"B":   PN = "2"  !CDS_PN = "2";
BODY = "Q_INDUCTOR4P_14","I40": #LOCATION = "PL18" !CDS_LOCATION = "PL18" &SEC = "1" #&CDS_SEC = "1";
"1":   PN = "1"  !CDS_PN = "1";
"2":   PN = "2"  !CDS_PN = "2";
"3":   PN = "3"  !CDS_PN = "3";
"4":   PN = "4"  !CDS_PN = "4";
BODY = "Q_CAP","I41": #LOCATION = "PC156" !CDS_LOCATION = "PC156" &SEC = "1" #&CDS_SEC = "1";
"A":   PN = "1"  !CDS_PN = "1";
"B":   PN = "2"  !CDS_PN = "2";
BODY = "Q_CAP","I42": #LOCATION = "PC151_2" !CDS_LOCATION = "PC151_2" &SEC = "1" #&CDS_SEC = "1";
"A":   PN = "1"  !CDS_PN = "1";
"B":   PN = "2"  !CDS_PN = "2";
BODY = "Q_CAP","I43": #LOCATION = "PC153_2" !CDS_LOCATION = "PC153_2" &SEC = "1" #&CDS_SEC = "1";
"A":   PN = "1"  !CDS_PN = "1";
"B":   PN = "2"  !CDS_PN = "2";
BODY = "Q_CAP","I45": #LOCATION = "PC157_2" !CDS_LOCATION = "PC157_2" &SEC = "1" #&CDS_SEC = "1";
"A":   PN = "1"  !CDS_PN = "1";
"B":   PN = "2"  !CDS_PN = "2";
BODY = "Q_CAP","I47": #LOCATION = "PC159_2" !CDS_LOCATION = "PC159_2" &SEC = "1" #&CDS_SEC = "1";
"A":   PN = "1"  !CDS_PN = "1";
"B":   PN = "2"  !CDS_PN = "2";
BODY = "Q_RES","I49": #LOCATION = "PR103" !CDS_LOCATION = "PR103" &SEC = "1" #&CDS_SEC = "1";
"A":   PN = "1"  !CDS_PN = "1";
"B":   PN = "2"  !CDS_PN = "2";
BODY = "Q_CAP","I51": #LOCATION = "PC168_2" !CDS_LOCATION = "PC168_2" &SEC = "1" #&CDS_SEC = "1";
"A":   PN = "1"  !CDS_PN = "1";
"B":   PN = "2"  !CDS_PN = "2";
BODY = "Q_CAP","I53": #LOCATION = "PC170_2" !CDS_LOCATION = "PC170_2" &SEC = "1" #&CDS_SEC = "1";
"A":   PN = "1"  !CDS_PN = "1";
"B":   PN = "2"  !CDS_PN = "2";
BODY = "Q_CAPP","I54": #LOCATION = "PC160" !CDS_LOCATION = "PC160" &SEC = "1" #&CDS_SEC = "1";
"A":   PN = "1"  !CDS_PN = "1";
"B":   PN = "2"  !CDS_PN = "2";
BODY = "Q_CAPP","I57": #LOCATION = "PC162" !CDS_LOCATION = "PC162" &SEC = "1" #&CDS_SEC = "1";
"A":   PN = "1"  !CDS_PN = "1";
"B":   PN = "2"  !CDS_PN = "2";
BODY = "Q_CAPP","I58": #LOCATION = "PC165" !CDS_LOCATION = "PC165" &SEC = "1" #&CDS_SEC = "1";
"A":   PN = "1"  !CDS_PN = "1";
"B":   PN = "2"  !CDS_PN = "2";
BODY = "Q_RES","I60": #LOCATION = "PR221" !CDS_LOCATION = "PR221" &SEC = "1" #&CDS_SEC = "1";
"A":   PN = "1"  !CDS_PN = "1";
"B":   PN = "2"  !CDS_PN = "2";
BODY = "Q_CAP","I61": #LOCATION = "PC158" !CDS_LOCATION = "PC158" &SEC = "1" #&CDS_SEC = "1";
"A":   PN = "1"  !CDS_PN = "1";
"B":   PN = "2"  !CDS_PN = "2";
BODY = "Q_CAP","I63": #LOCATION = "PC155" !CDS_LOCATION = "PC155" &SEC = "1" #&CDS_SEC = "1";
"A":   PN = "1"  !CDS_PN = "1";
"B":   PN = "2"  !CDS_PN = "2";
BODY = "Q_INDUCTOR4P_14","I64": #LOCATION = "PL17" !CDS_LOCATION = "PL17" &SEC = "1" #&CDS_SEC = "1";
"1":   PN = "1"  !CDS_PN = "1";
"2":   PN = "2"  !CDS_PN = "2";
"3":   PN = "3"  !CDS_PN = "3";
"4":   PN = "4"  !CDS_PN = "4";
BODY = "Q_CAP","I66": #LOCATION = "PC158_1" !CDS_LOCATION = "PC158_1" &SEC = "1" #&CDS_SEC = "1";
"A":   PN = "1"  !CDS_PN = "1";
"B":   PN = "2"  !CDS_PN = "2";
BODY = "Q_CAPP","I67": #LOCATION = "PC164" !CDS_LOCATION = "PC164" &SEC = "1" #&CDS_SEC = "1";
"A":   PN = "1"  !CDS_PN = "1";
"B":   PN = "2"  !CDS_PN = "2";
BODY = "Q_INDUCTOR","I69": #LOCATION = "PL19" !CDS_LOCATION = "PL19" &SEC = "1" #&CDS_SEC = "1";
"1":   PN = "1"  !CDS_PN = "1";
"2":   PN = "2"  !CDS_PN = "2";
BODY = "Q_CAP","I72": #LOCATION = "PC148" !CDS_LOCATION = "PC148" &SEC = "1" #&CDS_SEC = "1";
"A":   PN = "1"  !CDS_PN = "1";
"B":   PN = "2"  !CDS_PN = "2";
BODY = "Q_CAP","I73": #LOCATION = "PC107" !CDS_LOCATION = "PC107" &SEC = "1" #&CDS_SEC = "1";
"A":   PN = "1"  !CDS_PN = "1";
"B":   PN = "2"  !CDS_PN = "2";
BODY = "Q_CAP","I74": #LOCATION = "PC166_1" !CDS_LOCATION = "PC166_1" &SEC = "1" #&CDS_SEC = "1";
"A":   PN = "1"  !CDS_PN = "1";
"B":   PN = "2"  !CDS_PN = "2";
BODY = "Q_CAP","I75": #LOCATION = "PC169_1" !CDS_LOCATION = "PC169_1" &SEC = "1" #&CDS_SEC = "1";
"A":   PN = "1"  !CDS_PN = "1";
"B":   PN = "2"  !CDS_PN = "2";
BODY = "Q_RES","I78": #LOCATION = "PR410" !CDS_LOCATION = "PR410" &SEC = "1" #&CDS_SEC = "1";
"A":   PN = "1"  !CDS_PN = "1";
"B":   PN = "2"  !CDS_PN = "2";
BODY = "Q_CAP","I80": #LOCATION = "PC154_1" !CDS_LOCATION = "PC154_1" &SEC = "1" #&CDS_SEC = "1";
"A":   PN = "1"  !CDS_PN = "1";
"B":   PN = "2"  !CDS_PN = "2";
BODY = "Q_CAP","I81": #LOCATION = "PC152_1" !CDS_LOCATION = "PC152_1" &SEC = "1" #&CDS_SEC = "1";
"A":   PN = "1"  !CDS_PN = "1";
"B":   PN = "2"  !CDS_PN = "2";
BODY = "Q_CAP","I82": #LOCATION = "PC150_1" !CDS_LOCATION = "PC150_1" &SEC = "1" #&CDS_SEC = "1";
"A":   PN = "1"  !CDS_PN = "1";
"B":   PN = "2"  !CDS_PN = "2";
BODY = "Q_CAP","I83": #LOCATION = "PC148_1" !CDS_LOCATION = "PC148_1" &SEC = "1" #&CDS_SEC = "1";
"A":   PN = "1"  !CDS_PN = "1";
"B":   PN = "2"  !CDS_PN = "2";
BODY = "ISL99390FRZTR5935","I84": #LOCATION = "PU17" !CDS_LOCATION = "PU17" &SEC = "1" #&CDS_SEC = "1";
"AGND":   PN = "2"  !CDS_PN = "2";
"BOOT":   PN = "33"  !CDS_PN = "33";
"DNC":   PN = "31"  !CDS_PN = "31";
"EN":   PN = "35"  !CDS_PN = "35";
"GL1":   PN = "6"  !CDS_PN = "6";
"GL2":   PN = "41"  !CDS_PN = "41";
"IOUT":   PN = "38"  !CDS_PN = "38";
"LSET":   PN = "37"  !CDS_PN = "37";
"PGND1":   PN = "5"  !CDS_PN = "5";
"PGND2":   PN = "7_9-20_24"  !CDS_PN = "7_9-20_24";
"PGND3":   PN = "40"  !CDS_PN = "40";
"PHASE":   PN = "32"  !CDS_PN = "32";
"PVCC":   PN = "4"  !CDS_PN = "4";
"PWM":   PN = "34"  !CDS_PN = "34";
"REFIN":   PN = "39"  !CDS_PN = "39";
"SW":   PN = "10_19"  !CDS_PN = "10_19";
"TOUT_FLT":   PN = "36"  !CDS_PN = "36";
"VCC":   PN = "3"  !CDS_PN = "3";
"VIN1":   PN = "25_29"  !CDS_PN = "25_29";
"VIN2":   PN = "30"  !CDS_PN = "30";
"VOS":   PN = "1"  !CDS_PN = "1";
BODY = "Q_CAP","I85": #LOCATION = "PC7000" !CDS_LOCATION = "PC7000" &SEC = "1" #&CDS_SEC = "1";
"A":   PN = "1"  !CDS_PN = "1";
"B":   PN = "2"  !CDS_PN = "2";
DRAWING = "@t6g_mb_lib.t6g(sch_1):page184";
BODY = "Q_CAP","I4": #LOCATION = "C674" !CDS_LOCATION = "C674" &SEC = "1" #&CDS_SEC = "1";
"A":   PN = "1"  !CDS_PN = "1";
"B":   PN = "2"  !CDS_PN = "2";
BODY = "Q_CAP","I5": #LOCATION = "PC6001" !CDS_LOCATION = "PC6001" &SEC = "1" #&CDS_SEC = "1";
"A":   PN = "1"  !CDS_PN = "1";
"B":   PN = "2"  !CDS_PN = "2";
BODY = "Q_INDUCTOR","I7": #LOCATION = "PL77" !CDS_LOCATION = "PL77" &SEC = "1" #&CDS_SEC = "1";
"1":   PN = "1"  !CDS_PN = "1";
"2":   PN = "2"  !CDS_PN = "2";
BODY = "Q_CAP","I8": #LOCATION = "PC111" !CDS_LOCATION = "PC111" &SEC = "1" #&CDS_SEC = "1";
"A":   PN = "1"  !CDS_PN = "1";
"B":   PN = "2"  !CDS_PN = "2";
BODY = "Q_CAP","I11": #LOCATION = "PC212" !CDS_LOCATION = "PC212" #SEC = "1" !CDS_SEC = "1";
"A":   PN = "1"  !CDS_PN = "1";
"B":   PN = "2"  !CDS_PN = "2";
BODY = "Q_RES","I12": #LOCATION = "PR477" !CDS_LOCATION = "PR477" &SEC = "1" #&CDS_SEC = "1";
"A":   PN = "1"  !CDS_PN = "1";
"B":   PN = "2"  !CDS_PN = "2";
BODY = "Q_RES","I15": #LOCATION = "PR417" !CDS_LOCATION = "PR417" &SEC = "1" #&CDS_SEC = "1";
"A":   PN = "1"  !CDS_PN = "1";
"B":   PN = "2"  !CDS_PN = "2";
BODY = "Q_RES","I17": #LOCATION = "PR448" !CDS_LOCATION = "PR448" #SEC = "1" !CDS_SEC = "1";
"A":   PN = "1"  !CDS_PN = "1";
"B":   PN = "2"  !CDS_PN = "2";
BODY = "MPQ8633BGLEC838Z","I18": #LOCATION = "PU57" !CDS_LOCATION = "PU57" &SEC = "1" #&CDS_SEC = "1";
"AGND":   PN = "2"  !CDS_PN = "2";
"BST":   PN = "1"  !CDS_PN = "1";
"CS":   PN = "3"  !CDS_PN = "3";
"EN":   PN = "8"  !CDS_PN = "8";
"FB":   PN = "7"  !CDS_PN = "7";
"MODE":   PN = "4"  !CDS_PN = "4";
"PGND":   PN = "11_18"  !CDS_PN = "11_18";
"PGOOD":   PN = "9"  !CDS_PN = "9";
"RGND":   PN = "6"  !CDS_PN = "6";
"SW":   PN = "20"  !CDS_PN = "20";
"TRK_REF":   PN = "5"  !CDS_PN = "5";
"VCC":   PN = "19"  !CDS_PN = "19";
"VIN1":   PN = "10"  !CDS_PN = "10";
"VIN2":   PN = "21"  !CDS_PN = "21";
BODY = "Q_CAP","I21": #LOCATION = "PC258" !CDS_LOCATION = "PC258" &SEC = "1" #&CDS_SEC = "1";
"A":   PN = "1"  !CDS_PN = "1";
"B":   PN = "2"  !CDS_PN = "2";
BODY = "Q_CAP","I22": #LOCATION = "PC113" !CDS_LOCATION = "PC113" &SEC = "1" #&CDS_SEC = "1";
"A":   PN = "1"  !CDS_PN = "1";
"B":   PN = "2"  !CDS_PN = "2";
BODY = "Q_RES","I23": #LOCATION = "PR470" !CDS_LOCATION = "PR470" &SEC = "1" #&CDS_SEC = "1";
"A":   PN = "1"  !CDS_PN = "1";
"B":   PN = "2"  !CDS_PN = "2";
BODY = "Q_CAP","I24": #LOCATION = "PC209" !CDS_LOCATION = "PC209" #SEC = "1" !CDS_SEC = "1";
"A":   PN = "1"  !CDS_PN = "1";
"B":   PN = "2"  !CDS_PN = "2";
BODY = "Q_CAP","I25": #LOCATION = "PC227" !CDS_LOCATION = "PC227" &SEC = "1" #&CDS_SEC = "1";
"A":   PN = "1"  !CDS_PN = "1";
"B":   PN = "2"  !CDS_PN = "2";
BODY = "Q_CAP","I26": #LOCATION = "PC254" !CDS_LOCATION = "PC254" &SEC = "1" #&CDS_SEC = "1";
"A":   PN = "1"  !CDS_PN = "1";
"B":   PN = "2"  !CDS_PN = "2";
BODY = "Q_CAP","I27": #LOCATION = "PC81" !CDS_LOCATION = "PC81" &SEC = "1" #&CDS_SEC = "1";
"A":   PN = "1"  !CDS_PN = "1";
"B":   PN = "2"  !CDS_PN = "2";
BODY = "Q_CAP","I28": #LOCATION = "PC237" !CDS_LOCATION = "PC237" &SEC = "1" #&CDS_SEC = "1";
"A":   PN = "1"  !CDS_PN = "1";
"B":   PN = "2"  !CDS_PN = "2";
BODY = "Q_RES","I29": #LOCATION = "R8465" !CDS_LOCATION = "R8465" #SEC = "1" !CDS_SEC = "1";
"A":   PN = "1"  !CDS_PN = "1";
"B":   PN = "2"  !CDS_PN = "2";
BODY = "Q_RES","I31": #LOCATION = "PR418" !CDS_LOCATION = "PR418" &SEC = "1" #&CDS_SEC = "1";
"A":   PN = "1"  !CDS_PN = "1";
"B":   PN = "2"  !CDS_PN = "2";
BODY = "Q_CAP","I33": #LOCATION = "PC259" !CDS_LOCATION = "PC259" &SEC = "1" #&CDS_SEC = "1";
"A":   PN = "1"  !CDS_PN = "1";
"B":   PN = "2"  !CDS_PN = "2";
BODY = "Q_CAP","I34": #LOCATION = "PC6005" !CDS_LOCATION = "PC6005" &SEC = "1" #&CDS_SEC = "1";
"A":   PN = "1"  !CDS_PN = "1";
"B":   PN = "2"  !CDS_PN = "2";
BODY = "Q_RES","I35": #LOCATION = "PR471" !CDS_LOCATION = "PR471" &SEC = "1" #&CDS_SEC = "1";
"A":   PN = "1"  !CDS_PN = "1";
"B":   PN = "2"  !CDS_PN = "2";
BODY = "Q_INDUCTOR","I36": #LOCATION = "PL78" !CDS_LOCATION = "PL78" &SEC = "1" #&CDS_SEC = "1";
"1":   PN = "1"  !CDS_PN = "1";
"2":   PN = "2"  !CDS_PN = "2";
BODY = "Q_RES","I37": #LOCATION = "PR435" !CDS_LOCATION = "PR435" &SEC = "1" #&CDS_SEC = "1";
"A":   PN = "1"  !CDS_PN = "1";
"B":   PN = "2"  !CDS_PN = "2";
BODY = "Q_RES","I38": #LOCATION = "PR434" !CDS_LOCATION = "PR434" &SEC = "1" #&CDS_SEC = "1";
"A":   PN = "1"  !CDS_PN = "1";
"B":   PN = "2"  !CDS_PN = "2";
BODY = "Q_CAP","I39": #LOCATION = "PC114" !CDS_LOCATION = "PC114" &SEC = "1" #&CDS_SEC = "1";
"A":   PN = "1"  !CDS_PN = "1";
"B":   PN = "2"  !CDS_PN = "2";
BODY = "Q_CAP","I40": #LOCATION = "PC288" !CDS_LOCATION = "PC288" &SEC = "1" #&CDS_SEC = "1";
"A":   PN = "1"  !CDS_PN = "1";
"B":   PN = "2"  !CDS_PN = "2";
BODY = "Q_CAP","I41": #LOCATION = "PC260" !CDS_LOCATION = "PC260" &SEC = "1" #&CDS_SEC = "1";
"A":   PN = "1"  !CDS_PN = "1";
"B":   PN = "2"  !CDS_PN = "2";
BODY = "Q_RES","I42": #LOCATION = "PR438" !CDS_LOCATION = "PR438" &SEC = "1" #&CDS_SEC = "1";
"A":   PN = "1"  !CDS_PN = "1";
"B":   PN = "2"  !CDS_PN = "2";
BODY = "Q_CAP","I46": #LOCATION = "PC261" !CDS_LOCATION = "PC261" &SEC = "1" #&CDS_SEC = "1";
"A":   PN = "1"  !CDS_PN = "1";
"B":   PN = "2"  !CDS_PN = "2";
BODY = "Q_CAPP","I47": #LOCATION = "PC115" !CDS_LOCATION = "PC115" &SEC = "1" #&CDS_SEC = "1";
"A":   PN = "1"  !CDS_PN = "1";
"B":   PN = "2"  !CDS_PN = "2";
BODY = "Q_CAP","I48": #LOCATION = "PC215" !CDS_LOCATION = "PC215" #SEC = "1" !CDS_SEC = "1";
"A":   PN = "1"  !CDS_PN = "1";
"B":   PN = "2"  !CDS_PN = "2";
BODY = "Q_RES","I51": #LOCATION = "PR439" !CDS_LOCATION = "PR439" &SEC = "1" #&CDS_SEC = "1";
"A":   PN = "1"  !CDS_PN = "1";
"B":   PN = "2"  !CDS_PN = "2";
BODY = "Q_RES","I52": #LOCATION = "R177" !CDS_LOCATION = "R177" &SEC = "1" #&CDS_SEC = "1";
"A":   PN = "1"  !CDS_PN = "1";
"B":   PN = "2"  !CDS_PN = "2";
BODY = "Q_CAP","I54": #LOCATION = "PC285" !CDS_LOCATION = "PC285" &SEC = "1" #&CDS_SEC = "1";
"A":   PN = "1"  !CDS_PN = "1";
"B":   PN = "2"  !CDS_PN = "2";
BODY = "Q_CAP","I56": #LOCATION = "C5001" !CDS_LOCATION = "C5001" &SEC = "1" #&CDS_SEC = "1";
"A":   PN = "1"  !CDS_PN = "1";
"B":   PN = "2"  !CDS_PN = "2";
BODY = "Q_CAP","I57": #LOCATION = "PC8002" !CDS_LOCATION = "PC8002" &SEC = "1" #&CDS_SEC = "1";
"A":   PN = "1"  !CDS_PN = "1";
"B":   PN = "2"  !CDS_PN = "2";
BODY = "Q_RES","I58": #LOCATION = "PR8001" !CDS_LOCATION = "PR8001" #SEC = "1" !CDS_SEC = "1";
"A":   PN = "1"  !CDS_PN = "1";
"B":   PN = "2"  !CDS_PN = "2";
DRAWING = "@t6g_mb_lib.t6g(sch_1):page187";
BODY = "Q_CAP","I2": #LOCATION = "PC285_4" !CDS_LOCATION = "PC285_4" &SEC = "1" #&CDS_SEC = "1";
"A":   PN = "1"  !CDS_PN = "1";
"B":   PN = "2"  !CDS_PN = "2";
BODY = "Q_CAP","I6": #LOCATION = "PC287" !CDS_LOCATION = "PC287" &SEC = "1" #&CDS_SEC = "1";
"A":   PN = "1"  !CDS_PN = "1";
"B":   PN = "2"  !CDS_PN = "2";
BODY = "ISL99390FRZTR5935","I9": #LOCATION = "PU28" !CDS_LOCATION = "PU28" &SEC = "1" #&CDS_SEC = "1";
"AGND":   PN = "2"  !CDS_PN = "2";
"BOOT":   PN = "33"  !CDS_PN = "33";
"DNC":   PN = "31"  !CDS_PN = "31";
"EN":   PN = "35"  !CDS_PN = "35";
"GL1":   PN = "6"  !CDS_PN = "6";
"GL2":   PN = "41"  !CDS_PN = "41";
"IOUT":   PN = "38"  !CDS_PN = "38";
"LSET":   PN = "37"  !CDS_PN = "37";
"PGND1":   PN = "5"  !CDS_PN = "5";
"PGND2":   PN = "7_9-20_24"  !CDS_PN = "7_9-20_24";
"PGND3":   PN = "40"  !CDS_PN = "40";
"PHASE":   PN = "32"  !CDS_PN = "32";
"PVCC":   PN = "4"  !CDS_PN = "4";
"PWM":   PN = "34"  !CDS_PN = "34";
"REFIN":   PN = "39"  !CDS_PN = "39";
"SW":   PN = "10_19"  !CDS_PN = "10_19";
"TOUT_FLT":   PN = "36"  !CDS_PN = "36";
"VCC":   PN = "3"  !CDS_PN = "3";
"VIN1":   PN = "25_29"  !CDS_PN = "25_29";
"VIN2":   PN = "30"  !CDS_PN = "30";
"VOS":   PN = "1"  !CDS_PN = "1";
BODY = "Q_RES","I11": #LOCATION = "PR196" !CDS_LOCATION = "PR196" &SEC = "1" #&CDS_SEC = "1";
"A":   PN = "1"  !CDS_PN = "1";
"B":   PN = "2"  !CDS_PN = "2";
BODY = "Q_RES","I12": #LOCATION = "PR194" !CDS_LOCATION = "PR194" &SEC = "1" #&CDS_SEC = "1";
"A":   PN = "1"  !CDS_PN = "1";
"B":   PN = "2"  !CDS_PN = "2";
BODY = "Q_CAP","I15": #LOCATION = "PC289_C0P1_4" !CDS_LOCATION = "PC289_C0P1_4" &SEC = "1" #&CDS_SEC = "1";
"A":   PN = "1"  !CDS_PN = "1";
"B":   PN = "2"  !CDS_PN = "2";
BODY = "Q_RES","I17": #LOCATION = "PR200" !CDS_LOCATION = "PR200" &SEC = "1" #&CDS_SEC = "1";
"A":   PN = "1"  !CDS_PN = "1";
"B":   PN = "2"  !CDS_PN = "2";
BODY = "Q_RES","I19": #LOCATION = "PR523" !CDS_LOCATION = "PR523" &SEC = "1" #&CDS_SEC = "1";
"A":   PN = "1"  !CDS_PN = "1";
"B":   PN = "2"  !CDS_PN = "2";
BODY = "Q_CAP","I20": #LOCATION = "PC317" !CDS_LOCATION = "PC317" &SEC = "1" #&CDS_SEC = "1";
"A":   PN = "1"  !CDS_PN = "1";
"B":   PN = "2"  !CDS_PN = "2";
BODY = "Q_RES","I21": #LOCATION = "PR198" !CDS_LOCATION = "PR198" &SEC = "1" #&CDS_SEC = "1";
"A":   PN = "1"  !CDS_PN = "1";
"B":   PN = "2"  !CDS_PN = "2";
BODY = "Q_CAP","I22": #LOCATION = "PC293_4" !CDS_LOCATION = "PC293_4" &SEC = "1" #&CDS_SEC = "1";
"A":   PN = "1"  !CDS_PN = "1";
"B":   PN = "2"  !CDS_PN = "2";
BODY = "Q_CAP","I23": #LOCATION = "PC291_4" !CDS_LOCATION = "PC291_4" &SEC = "1" #&CDS_SEC = "1";
"A":   PN = "1"  !CDS_PN = "1";
"B":   PN = "2"  !CDS_PN = "2";
BODY = "Q_CAP","I24": #LOCATION = "PC295_4" !CDS_LOCATION = "PC295_4" &SEC = "1" #&CDS_SEC = "1";
"A":   PN = "1"  !CDS_PN = "1";
"B":   PN = "2"  !CDS_PN = "2";
BODY = "Q_CAP","I25": #LOCATION = "PC297_4" !CDS_LOCATION = "PC297_4" &SEC = "1" #&CDS_SEC = "1";
"A":   PN = "1"  !CDS_PN = "1";
"B":   PN = "2"  !CDS_PN = "2";
BODY = "Q_RES","I27": #LOCATION = "PR199" !CDS_LOCATION = "PR199" &SEC = "1" #&CDS_SEC = "1";
"A":   PN = "1"  !CDS_PN = "1";
"B":   PN = "2"  !CDS_PN = "2";
BODY = "Q_CAP","I28": #LOCATION = "PC284_3" !CDS_LOCATION = "PC284_3" &SEC = "1" #&CDS_SEC = "1";
"A":   PN = "1"  !CDS_PN = "1";
"B":   PN = "2"  !CDS_PN = "2";
BODY = "Q_RES","I34": #LOCATION = "PR195" !CDS_LOCATION = "PR195" &SEC = "1" #&CDS_SEC = "1";
"A":   PN = "1"  !CDS_PN = "1";
"B":   PN = "2"  !CDS_PN = "2";
BODY = "Q_CAP","I37": #LOCATION = "PC286" !CDS_LOCATION = "PC286" &SEC = "1" #&CDS_SEC = "1";
"A":   PN = "1"  !CDS_PN = "1";
"B":   PN = "2"  !CDS_PN = "2";
BODY = "Q_RES","I38": #LOCATION = "PR193" !CDS_LOCATION = "PR193" &SEC = "1" #&CDS_SEC = "1";
"A":   PN = "1"  !CDS_PN = "1";
"B":   PN = "2"  !CDS_PN = "2";
BODY = "ISL99390FRZTR5935","I39": #LOCATION = "PU27" !CDS_LOCATION = "PU27" &SEC = "1" #&CDS_SEC = "1";
"AGND":   PN = "2"  !CDS_PN = "2";
"BOOT":   PN = "33"  !CDS_PN = "33";
"DNC":   PN = "31"  !CDS_PN = "31";
"EN":   PN = "35"  !CDS_PN = "35";
"GL1":   PN = "6"  !CDS_PN = "6";
"GL2":   PN = "41"  !CDS_PN = "41";
"IOUT":   PN = "38"  !CDS_PN = "38";
"LSET":   PN = "37"  !CDS_PN = "37";
"PGND1":   PN = "5"  !CDS_PN = "5";
"PGND2":   PN = "7_9-20_24"  !CDS_PN = "7_9-20_24";
"PGND3":   PN = "40"  !CDS_PN = "40";
"PHASE":   PN = "32"  !CDS_PN = "32";
"PVCC":   PN = "4"  !CDS_PN = "4";
"PWM":   PN = "34"  !CDS_PN = "34";
"REFIN":   PN = "39"  !CDS_PN = "39";
"SW":   PN = "10_19"  !CDS_PN = "10_19";
"TOUT_FLT":   PN = "36"  !CDS_PN = "36";
"VCC":   PN = "3"  !CDS_PN = "3";
"VIN1":   PN = "25_29"  !CDS_PN = "25_29";
"VIN2":   PN = "30"  !CDS_PN = "30";
"VOS":   PN = "1"  !CDS_PN = "1";
BODY = "Q_CAP","I41": #LOCATION = "PC288_C0P1_3" !CDS_LOCATION = "PC288_C0P1_3" &SEC = "1" #&CDS_SEC = "1";
"A":   PN = "1"  !CDS_PN = "1";
"B":   PN = "2"  !CDS_PN = "2";
BODY = "Q_CAP","I44": #LOCATION = "PC290_3" !CDS_LOCATION = "PC290_3" &SEC = "1" #&CDS_SEC = "1";
"A":   PN = "1"  !CDS_PN = "1";
"B":   PN = "2"  !CDS_PN = "2";
BODY = "Q_RES","I45": #LOCATION = "PR522" !CDS_LOCATION = "PR522" &SEC = "1" #&CDS_SEC = "1";
"A":   PN = "1"  !CDS_PN = "1";
"B":   PN = "2"  !CDS_PN = "2";
BODY = "Q_CAP","I46": #LOCATION = "PC316" !CDS_LOCATION = "PC316" &SEC = "1" #&CDS_SEC = "1";
"A":   PN = "1"  !CDS_PN = "1";
"B":   PN = "2"  !CDS_PN = "2";
BODY = "Q_RES","I47": #LOCATION = "PR197" !CDS_LOCATION = "PR197" &SEC = "1" #&CDS_SEC = "1";
"A":   PN = "1"  !CDS_PN = "1";
"B":   PN = "2"  !CDS_PN = "2";
BODY = "Q_CAP","I48": #LOCATION = "PC292_3" !CDS_LOCATION = "PC292_3" &SEC = "1" #&CDS_SEC = "1";
"A":   PN = "1"  !CDS_PN = "1";
"B":   PN = "2"  !CDS_PN = "2";
BODY = "Q_CAP","I49": #LOCATION = "PC294_3" !CDS_LOCATION = "PC294_3" &SEC = "1" #&CDS_SEC = "1";
"A":   PN = "1"  !CDS_PN = "1";
"B":   PN = "2"  !CDS_PN = "2";
BODY = "Q_CAP","I50": #LOCATION = "PC296_3" !CDS_LOCATION = "PC296_3" &SEC = "1" #&CDS_SEC = "1";
"A":   PN = "1"  !CDS_PN = "1";
"B":   PN = "2"  !CDS_PN = "2";
BODY = "Q_CAP","I52": #LOCATION = "PC301" !CDS_LOCATION = "PC301" &SEC = "1" #&CDS_SEC = "1";
"A":   PN = "1"  !CDS_PN = "1";
"B":   PN = "2"  !CDS_PN = "2";
BODY = "Q_INDUCTOR4P_14","I53": #LOCATION = "PL32" !CDS_LOCATION = "PL32" &SEC = "1" #&CDS_SEC = "1";
"1":   PN = "1"  !CDS_PN = "1";
"2":   PN = "2"  !CDS_PN = "2";
"3":   PN = "3"  !CDS_PN = "3";
"4":   PN = "4"  !CDS_PN = "4";
BODY = "Q_CAP","I55": #LOCATION = "PC299_4" !CDS_LOCATION = "PC299_4" &SEC = "1" #&CDS_SEC = "1";
"A":   PN = "1"  !CDS_PN = "1";
"B":   PN = "2"  !CDS_PN = "2";
BODY = "Q_CAP","I58": #LOCATION = "PC303_4" !CDS_LOCATION = "PC303_4" &SEC = "1" #&CDS_SEC = "1";
"A":   PN = "1"  !CDS_PN = "1";
"B":   PN = "2"  !CDS_PN = "2";
BODY = "Q_CAP","I60": #LOCATION = "PC305_4" !CDS_LOCATION = "PC305_4" &SEC = "1" #&CDS_SEC = "1";
"A":   PN = "1"  !CDS_PN = "1";
"B":   PN = "2"  !CDS_PN = "2";
BODY = "Q_CAP","I63": #LOCATION = "PC300" !CDS_LOCATION = "PC300" &SEC = "1" #&CDS_SEC = "1";
"A":   PN = "1"  !CDS_PN = "1";
"B":   PN = "2"  !CDS_PN = "2";
BODY = "Q_CAP","I65": #LOCATION = "PC298_3" !CDS_LOCATION = "PC298_3" &SEC = "1" #&CDS_SEC = "1";
"A":   PN = "1"  !CDS_PN = "1";
"B":   PN = "2"  !CDS_PN = "2";
BODY = "Q_INDUCTOR4P_14","I67": #LOCATION = "PL31" !CDS_LOCATION = "PL31" &SEC = "1" #&CDS_SEC = "1";
"1":   PN = "1"  !CDS_PN = "1";
"2":   PN = "2"  !CDS_PN = "2";
"3":   PN = "3"  !CDS_PN = "3";
"4":   PN = "4"  !CDS_PN = "4";
BODY = "Q_CAP","I69": #LOCATION = "PC302_3" !CDS_LOCATION = "PC302_3" &SEC = "1" #&CDS_SEC = "1";
"A":   PN = "1"  !CDS_PN = "1";
"B":   PN = "2"  !CDS_PN = "2";
BODY = "Q_CAP","I71": #LOCATION = "PC304_3" !CDS_LOCATION = "PC304_3" &SEC = "1" #&CDS_SEC = "1";
"A":   PN = "1"  !CDS_PN = "1";
"B":   PN = "2"  !CDS_PN = "2";
DRAWING = "@t6g_mb_lib.t6g(sch_1):page188";
BODY = "Q_CAP","I4": #LOCATION = "PC124_6" !CDS_LOCATION = "PC124_6" &SEC = "1" #&CDS_SEC = "1";
"A":   PN = "1"  !CDS_PN = "1";
"B":   PN = "2"  !CDS_PN = "2";
BODY = "Q_RES","I8": #LOCATION = "PR423" !CDS_LOCATION = "PR423" &SEC = "1" #&CDS_SEC = "1";
"A":   PN = "1"  !CDS_PN = "1";
"B":   PN = "2"  !CDS_PN = "2";
BODY = "Q_CAP","I10": #LOCATION = "PC125" !CDS_LOCATION = "PC125" &SEC = "1" #&CDS_SEC = "1";
"A":   PN = "1"  !CDS_PN = "1";
"B":   PN = "2"  !CDS_PN = "2";
BODY = "Q_RES","I12": #LOCATION = "PR422" !CDS_LOCATION = "PR422" &SEC = "1" #&CDS_SEC = "1";
"A":   PN = "1"  !CDS_PN = "1";
"B":   PN = "2"  !CDS_PN = "2";
BODY = "Q_CAP","I15": #LOCATION = "PC126_C0P1_6" !CDS_LOCATION = "PC126_C0P1_6" &SEC = "1" #&CDS_SEC = "1";
"A":   PN = "1"  !CDS_PN = "1";
"B":   PN = "2"  !CDS_PN = "2";
BODY = "ISL99390FRZTR5935","I18": #LOCATION = "PU29" !CDS_LOCATION = "PU29" &SEC = "1" #&CDS_SEC = "1";
"AGND":   PN = "2"  !CDS_PN = "2";
"BOOT":   PN = "33"  !CDS_PN = "33";
"DNC":   PN = "31"  !CDS_PN = "31";
"EN":   PN = "35"  !CDS_PN = "35";
"GL1":   PN = "6"  !CDS_PN = "6";
"GL2":   PN = "41"  !CDS_PN = "41";
"IOUT":   PN = "38"  !CDS_PN = "38";
"LSET":   PN = "37"  !CDS_PN = "37";
"PGND1":   PN = "5"  !CDS_PN = "5";
"PGND2":   PN = "7_9-20_24"  !CDS_PN = "7_9-20_24";
"PGND3":   PN = "40"  !CDS_PN = "40";
"PHASE":   PN = "32"  !CDS_PN = "32";
"PVCC":   PN = "4"  !CDS_PN = "4";
"PWM":   PN = "34"  !CDS_PN = "34";
"REFIN":   PN = "39"  !CDS_PN = "39";
"SW":   PN = "10_19"  !CDS_PN = "10_19";
"TOUT_FLT":   PN = "36"  !CDS_PN = "36";
"VCC":   PN = "3"  !CDS_PN = "3";
"VIN1":   PN = "25_29"  !CDS_PN = "25_29";
"VIN2":   PN = "30"  !CDS_PN = "30";
"VOS":   PN = "1"  !CDS_PN = "1";
BODY = "Q_RES","I21": #LOCATION = "PR524" !CDS_LOCATION = "PR524" &SEC = "1" #&CDS_SEC = "1";
"A":   PN = "1"  !CDS_PN = "1";
"B":   PN = "2"  !CDS_PN = "2";
BODY = "Q_RES","I22": #LOCATION = "PR425" !CDS_LOCATION = "PR425" &SEC = "1" #&CDS_SEC = "1";
"A":   PN = "1"  !CDS_PN = "1";
"B":   PN = "2"  !CDS_PN = "2";
BODY = "Q_CAP","I23": #LOCATION = "PC321" !CDS_LOCATION = "PC321" &SEC = "1" #&CDS_SEC = "1";
"A":   PN = "1"  !CDS_PN = "1";
"B":   PN = "2"  !CDS_PN = "2";
BODY = "Q_CAP","I25": #LOCATION = "PC127_6" !CDS_LOCATION = "PC127_6" &SEC = "1" #&CDS_SEC = "1";
"A":   PN = "1"  !CDS_PN = "1";
"B":   PN = "2"  !CDS_PN = "2";
BODY = "Q_CAP","I27": #LOCATION = "PC128_6" !CDS_LOCATION = "PC128_6" &SEC = "1" #&CDS_SEC = "1";
"A":   PN = "1"  !CDS_PN = "1";
"B":   PN = "2"  !CDS_PN = "2";
BODY = "Q_RES","I28": #LOCATION = "PR424" !CDS_LOCATION = "PR424" &SEC = "1" #&CDS_SEC = "1";
"A":   PN = "1"  !CDS_PN = "1";
"B":   PN = "2"  !CDS_PN = "2";
BODY = "Q_CAP","I29": #LOCATION = "PC129_6" !CDS_LOCATION = "PC129_6" &SEC = "1" #&CDS_SEC = "1";
"A":   PN = "1"  !CDS_PN = "1";
"B":   PN = "2"  !CDS_PN = "2";
BODY = "Q_CAP","I30": #LOCATION = "PC130_6" !CDS_LOCATION = "PC130_6" &SEC = "1" #&CDS_SEC = "1";
"A":   PN = "1"  !CDS_PN = "1";
"B":   PN = "2"  !CDS_PN = "2";
BODY = "Q_RES","I32": #LOCATION = "PR46" !CDS_LOCATION = "PR46" &SEC = "1" #&CDS_SEC = "1";
"A":   PN = "1"  !CDS_PN = "1";
"B":   PN = "2"  !CDS_PN = "2";
BODY = "Q_RES","I33": #LOCATION = "PR204" !CDS_LOCATION = "PR204" &SEC = "1" #&CDS_SEC = "1";
"A":   PN = "1"  !CDS_PN = "1";
"B":   PN = "2"  !CDS_PN = "2";
BODY = "Q_CAP","I34": #LOCATION = "PC306_5" !CDS_LOCATION = "PC306_5" &SEC = "1" #&CDS_SEC = "1";
"A":   PN = "1"  !CDS_PN = "1";
"B":   PN = "2"  !CDS_PN = "2";
BODY = "Q_RES","I37": #LOCATION = "PR202" !CDS_LOCATION = "PR202" &SEC = "1" #&CDS_SEC = "1";
"A":   PN = "1"  !CDS_PN = "1";
"B":   PN = "2"  !CDS_PN = "2";
BODY = "Q_CAP","I39": #LOCATION = "PC307" !CDS_LOCATION = "PC307" &SEC = "1" #&CDS_SEC = "1";
"A":   PN = "1"  !CDS_PN = "1";
"B":   PN = "2"  !CDS_PN = "2";
BODY = "Q_RES","I41": #LOCATION = "PR201" !CDS_LOCATION = "PR201" &SEC = "1" #&CDS_SEC = "1";
"A":   PN = "1"  !CDS_PN = "1";
"B":   PN = "2"  !CDS_PN = "2";
BODY = "Q_CAP","I43": #LOCATION = "PC308_C0P1_5" !CDS_LOCATION = "PC308_C0P1_5" &SEC = "1" #&CDS_SEC = "1";
"A":   PN = "1"  !CDS_PN = "1";
"B":   PN = "2"  !CDS_PN = "2";
BODY = "Q_CAP","I45": #LOCATION = "PC309_5" !CDS_LOCATION = "PC309_5" &SEC = "1" #&CDS_SEC = "1";
"A":   PN = "1"  !CDS_PN = "1";
"B":   PN = "2"  !CDS_PN = "2";
BODY = "Q_CAP","I46": #LOCATION = "PC318" !CDS_LOCATION = "PC318" &SEC = "1" #&CDS_SEC = "1";
"A":   PN = "1"  !CDS_PN = "1";
"B":   PN = "2"  !CDS_PN = "2";
BODY = "Q_RES","I47": #LOCATION = "PR203" !CDS_LOCATION = "PR203" &SEC = "1" #&CDS_SEC = "1";
"A":   PN = "1"  !CDS_PN = "1";
"B":   PN = "2"  !CDS_PN = "2";
BODY = "Q_CAP","I48": #LOCATION = "PC310_5" !CDS_LOCATION = "PC310_5" &SEC = "1" #&CDS_SEC = "1";
"A":   PN = "1"  !CDS_PN = "1";
"B":   PN = "2"  !CDS_PN = "2";
BODY = "Q_CAP","I49": #LOCATION = "PC311_5" !CDS_LOCATION = "PC311_5" &SEC = "1" #&CDS_SEC = "1";
"A":   PN = "1"  !CDS_PN = "1";
"B":   PN = "2"  !CDS_PN = "2";
BODY = "Q_CAP","I50": #LOCATION = "PC312_5" !CDS_LOCATION = "PC312_5" &SEC = "1" #&CDS_SEC = "1";
"A":   PN = "1"  !CDS_PN = "1";
"B":   PN = "2"  !CDS_PN = "2";
BODY = "Q_INDUCTOR","I51": #LOCATION = "PL27" !CDS_LOCATION = "PL27" &SEC = "1" #&CDS_SEC = "1";
"1":   PN = "1"  !CDS_PN = "1";
"2":   PN = "2"  !CDS_PN = "2";
BODY = "Q_CAP","I52": #LOCATION = "PC133" !CDS_LOCATION = "PC133" &SEC = "1" #&CDS_SEC = "1";
"A":   PN = "1"  !CDS_PN = "1";
"B":   PN = "2"  !CDS_PN = "2";
BODY = "Q_INDUCTOR4P_14","I53": #LOCATION = "PL8" !CDS_LOCATION = "PL8" &SEC = "1" #&CDS_SEC = "1";
"1":   PN = "1"  !CDS_PN = "1";
"2":   PN = "2"  !CDS_PN = "2";
"3":   PN = "3"  !CDS_PN = "3";
"4":   PN = "4"  !CDS_PN = "4";
BODY = "Q_CAP","I55": #LOCATION = "PC132_6" !CDS_LOCATION = "PC132_6" &SEC = "1" #&CDS_SEC = "1";
"A":   PN = "1"  !CDS_PN = "1";
"B":   PN = "2"  !CDS_PN = "2";
BODY = "Q_CAP","I58": #LOCATION = "PC134_6" !CDS_LOCATION = "PC134_6" &SEC = "1" #&CDS_SEC = "1";
"A":   PN = "1"  !CDS_PN = "1";
"B":   PN = "2"  !CDS_PN = "2";
BODY = "Q_CAP","I60": #LOCATION = "PC135_6" !CDS_LOCATION = "PC135_6" &SEC = "1" #&CDS_SEC = "1";
"A":   PN = "1"  !CDS_PN = "1";
"B":   PN = "2"  !CDS_PN = "2";
BODY = "Q_CAP","I63": #LOCATION = "PC314" !CDS_LOCATION = "PC314" &SEC = "1" #&CDS_SEC = "1";
"A":   PN = "1"  !CDS_PN = "1";
"B":   PN = "2"  !CDS_PN = "2";
BODY = "Q_INDUCTOR4P_14","I64": #LOCATION = "PL33" !CDS_LOCATION = "PL33" &SEC = "1" #&CDS_SEC = "1";
"1":   PN = "1"  !CDS_PN = "1";
"2":   PN = "2"  !CDS_PN = "2";
"3":   PN = "3"  !CDS_PN = "3";
"4":   PN = "4"  !CDS_PN = "4";
BODY = "Q_CAP","I66": #LOCATION = "PC313_5" !CDS_LOCATION = "PC313_5" &SEC = "1" #&CDS_SEC = "1";
"A":   PN = "1"  !CDS_PN = "1";
"B":   PN = "2"  !CDS_PN = "2";
BODY = "Q_CAP","I69": #LOCATION = "PC315_5" !CDS_LOCATION = "PC315_5" &SEC = "1" #&CDS_SEC = "1";
"A":   PN = "1"  !CDS_PN = "1";
"B":   PN = "2"  !CDS_PN = "2";
BODY = "Q_CAP","I71": #LOCATION = "PC316_5" !CDS_LOCATION = "PC316_5" &SEC = "1" #&CDS_SEC = "1";
"A":   PN = "1"  !CDS_PN = "1";
"B":   PN = "2"  !CDS_PN = "2";
BODY = "ISL99390FRZTR5935","I73": #LOCATION = "PU24" !CDS_LOCATION = "PU24" &SEC = "1" #&CDS_SEC = "1";
"AGND":   PN = "2"  !CDS_PN = "2";
"BOOT":   PN = "33"  !CDS_PN = "33";
"DNC":   PN = "31"  !CDS_PN = "31";
"EN":   PN = "35"  !CDS_PN = "35";
"GL1":   PN = "6"  !CDS_PN = "6";
"GL2":   PN = "41"  !CDS_PN = "41";
"IOUT":   PN = "38"  !CDS_PN = "38";
"LSET":   PN = "37"  !CDS_PN = "37";
"PGND1":   PN = "5"  !CDS_PN = "5";
"PGND2":   PN = "7_9-20_24"  !CDS_PN = "7_9-20_24";
"PGND3":   PN = "40"  !CDS_PN = "40";
"PHASE":   PN = "32"  !CDS_PN = "32";
"PVCC":   PN = "4"  !CDS_PN = "4";
"PWM":   PN = "34"  !CDS_PN = "34";
"REFIN":   PN = "39"  !CDS_PN = "39";
"SW":   PN = "10_19"  !CDS_PN = "10_19";
"TOUT_FLT":   PN = "36"  !CDS_PN = "36";
"VCC":   PN = "3"  !CDS_PN = "3";
"VIN1":   PN = "25_29"  !CDS_PN = "25_29";
"VIN2":   PN = "30"  !CDS_PN = "30";
"VOS":   PN = "1"  !CDS_PN = "1";
DRAWING = "@t6g_mb_lib.t6g(sch_1):page192";
BODY = "Q_RES","I2": #LOCATION = "R8224" !CDS_LOCATION = "R8224" &SEC = "1" #&CDS_SEC = "1";
"A":   PN = "1"  !CDS_PN = "1";
"B":   PN = "2"  !CDS_PN = "2";
BODY = "Q_CAP","I3": #LOCATION = "C8356" !CDS_LOCATION = "C8356" &SEC = "1" #&CDS_SEC = "1";
"A":   PN = "1"  !CDS_PN = "1";
"B":   PN = "2"  !CDS_PN = "2";
BODY = "MOSFET_N","I6": #LOCATION = "PQ16" !CDS_LOCATION = "PQ16" &SEC = "1" #&CDS_SEC = "1";
"DRAIN":   PN = "D"  !CDS_PN = "D";
"GATE":   PN = "G"  !CDS_PN = "G";
"SOURCE":   PN = "S"  !CDS_PN = "S";
BODY = "Q_RES","I8": #LOCATION = "PR231" !CDS_LOCATION = "PR231" &SEC = "1" #&CDS_SEC = "1";
"A":   PN = "1"  !CDS_PN = "1";
"B":   PN = "2"  !CDS_PN = "2";
BODY = "Q_RES","I9": #LOCATION = "PR230" !CDS_LOCATION = "PR230" &SEC = "1" #&CDS_SEC = "1";
"A":   PN = "1"  !CDS_PN = "1";
"B":   PN = "2"  !CDS_PN = "2";
BODY = "Q_RES","I12": #LOCATION = "PR244" !CDS_LOCATION = "PR244" &SEC = "1" #&CDS_SEC = "1";
"A":   PN = "1"  !CDS_PN = "1";
"B":   PN = "2"  !CDS_PN = "2";
BODY = "MOSFET_PCH_GDS_ESD_PROTECTED","I13": #LOCATION = "PQ12" !CDS_LOCATION = "PQ12" &SEC = "1" #&CDS_SEC = "1";
"D":   PN = "D"  !CDS_PN = "D";
"G":   PN = "G"  !CDS_PN = "G";
"S":   PN = "S"  !CDS_PN = "S";
BODY = "Q_RES","I17": #LOCATION = "PR232" !CDS_LOCATION = "PR232" &SEC = "1" #&CDS_SEC = "1";
"A":   PN = "1"  !CDS_PN = "1";
"B":   PN = "2"  !CDS_PN = "2";
BODY = "Q_RES","I19": #LOCATION = "PR460" !CDS_LOCATION = "PR460" &SEC = "1" #&CDS_SEC = "1";
"A":   PN = "1"  !CDS_PN = "1";
"B":   PN = "2"  !CDS_PN = "2";
BODY = "Q_RES","I22": #LOCATION = "PR227" !CDS_LOCATION = "PR227" &SEC = "1" #&CDS_SEC = "1";
"A":   PN = "1"  !CDS_PN = "1";
"B":   PN = "2"  !CDS_PN = "2";
BODY = "Q_RES","I23": #LOCATION = "PR226" !CDS_LOCATION = "PR226" &SEC = "1" #&CDS_SEC = "1";
"A":   PN = "1"  !CDS_PN = "1";
"B":   PN = "2"  !CDS_PN = "2";
BODY = "Q_RES","I29": #LOCATION = "PR217" !CDS_LOCATION = "PR217" &SEC = "1" #&CDS_SEC = "1";
"A":   PN = "1"  !CDS_PN = "1";
"B":   PN = "2"  !CDS_PN = "2";
BODY = "Q_RES","I30": #LOCATION = "R8219" !CDS_LOCATION = "R8219" &SEC = "1" #&CDS_SEC = "1";
"A":   PN = "1"  !CDS_PN = "1";
"B":   PN = "2"  !CDS_PN = "2";
BODY = "Q_CAP","I31": #LOCATION = "C308" !CDS_LOCATION = "C308" &SEC = "1" #&CDS_SEC = "1";
"A":   PN = "1"  !CDS_PN = "1";
"B":   PN = "2"  !CDS_PN = "2";
BODY = "Q_CAP","I32": #LOCATION = "C309" !CDS_LOCATION = "C309" &SEC = "1" #&CDS_SEC = "1";
"A":   PN = "1"  !CDS_PN = "1";
"B":   PN = "2"  !CDS_PN = "2";
BODY = "Q_CAP","I33": #LOCATION = "C310" !CDS_LOCATION = "C310" &SEC = "1" #&CDS_SEC = "1";
"A":   PN = "1"  !CDS_PN = "1";
"B":   PN = "2"  !CDS_PN = "2";
BODY = "Q_RES","I34": #LOCATION = "PR228" !CDS_LOCATION = "PR228" &SEC = "1" #&CDS_SEC = "1";
"A":   PN = "1"  !CDS_PN = "1";
"B":   PN = "2"  !CDS_PN = "2";
BODY = "Q_RES","I38": #LOCATION = "PR218" !CDS_LOCATION = "PR218" &SEC = "1" #&CDS_SEC = "1";
"A":   PN = "1"  !CDS_PN = "1";
"B":   PN = "2"  !CDS_PN = "2";
BODY = "Q_RES","I40": #LOCATION = "R8220" !CDS_LOCATION = "R8220" &SEC = "1" #&CDS_SEC = "1";
"A":   PN = "1"  !CDS_PN = "1";
"B":   PN = "2"  !CDS_PN = "2";
BODY = "Q_RES","I41": #LOCATION = "R8222" !CDS_LOCATION = "R8222" &SEC = "1" #&CDS_SEC = "1";
"A":   PN = "1"  !CDS_PN = "1";
"B":   PN = "2"  !CDS_PN = "2";
BODY = "Q_RES","I42": #LOCATION = "R8225" !CDS_LOCATION = "R8225" &SEC = "1" #&CDS_SEC = "1";
"A":   PN = "1"  !CDS_PN = "1";
"B":   PN = "2"  !CDS_PN = "2";
BODY = "Q_CAP","I47": #LOCATION = "PC357" !CDS_LOCATION = "PC357" &SEC = "1" #&CDS_SEC = "1";
"A":   PN = "1"  !CDS_PN = "1";
"B":   PN = "2"  !CDS_PN = "2";
BODY = "Q_RES","I49": #LOCATION = "PR251" !CDS_LOCATION = "PR251" &SEC = "1" #&CDS_SEC = "1";
"A":   PN = "1"  !CDS_PN = "1";
"B":   PN = "2"  !CDS_PN = "2";
BODY = "Q_RES","I50": #LOCATION = "R8243" !CDS_LOCATION = "R8243" &SEC = "1" #&CDS_SEC = "1";
"A":   PN = "1"  !CDS_PN = "1";
"B":   PN = "2"  !CDS_PN = "2";
BODY = "Q_RES","I51": #LOCATION = "R8242" !CDS_LOCATION = "R8242" &SEC = "1" #&CDS_SEC = "1";
"A":   PN = "1"  !CDS_PN = "1";
"B":   PN = "2"  !CDS_PN = "2";
BODY = "Q_CAP","I52": #LOCATION = "C8362" !CDS_LOCATION = "C8362" &SEC = "1" #&CDS_SEC = "1";
"A":   PN = "1"  !CDS_PN = "1";
"B":   PN = "2"  !CDS_PN = "2";
BODY = "Q_RES","I55": #LOCATION = "PR603" !CDS_LOCATION = "PR603" &SEC = "1" #&CDS_SEC = "1";
"A":   PN = "1"  !CDS_PN = "1";
"B":   PN = "2"  !CDS_PN = "2";
BODY = "Q_CAP","I56": #LOCATION = "PC364" !CDS_LOCATION = "PC364" &SEC = "1" #&CDS_SEC = "1";
"A":   PN = "1"  !CDS_PN = "1";
"B":   PN = "2"  !CDS_PN = "2";
BODY = "Q_CAP","I60": #LOCATION = "PC363" !CDS_LOCATION = "PC363" &SEC = "1" #&CDS_SEC = "1";
"A":   PN = "1"  !CDS_PN = "1";
"B":   PN = "2"  !CDS_PN = "2";
BODY = "Q_RES","I64": #LOCATION = "R8241" !CDS_LOCATION = "R8241" &SEC = "1" #&CDS_SEC = "1";
"A":   PN = "1"  !CDS_PN = "1";
"B":   PN = "2"  !CDS_PN = "2";
BODY = "Q_RES","I65": #LOCATION = "R240" !CDS_LOCATION = "R240" &SEC = "1" #&CDS_SEC = "1";
"A":   PN = "1"  !CDS_PN = "1";
"B":   PN = "2"  !CDS_PN = "2";
BODY = "Q_RES","I66": #LOCATION = "R8247" !CDS_LOCATION = "R8247" &SEC = "1" #&CDS_SEC = "1";
"A":   PN = "1"  !CDS_PN = "1";
"B":   PN = "2"  !CDS_PN = "2";
BODY = "Q_CAP","I67": #LOCATION = "PC361" !CDS_LOCATION = "PC361" &SEC = "1" #&CDS_SEC = "1";
"A":   PN = "1"  !CDS_PN = "1";
"B":   PN = "2"  !CDS_PN = "2";
BODY = "Q_RES","I69": #LOCATION = "PR246" !CDS_LOCATION = "PR246" &SEC = "1" #&CDS_SEC = "1";
"A":   PN = "1"  !CDS_PN = "1";
"B":   PN = "2"  !CDS_PN = "2";
BODY = "Q_RES","I71": #LOCATION = "R8252" !CDS_LOCATION = "R8252" &SEC = "1" #&CDS_SEC = "1";
"A":   PN = "1"  !CDS_PN = "1";
"B":   PN = "2"  !CDS_PN = "2";
BODY = "Q_CAP","I73": #LOCATION = "PC368" !CDS_LOCATION = "PC368" &SEC = "1" #&CDS_SEC = "1";
"A":   PN = "1"  !CDS_PN = "1";
"B":   PN = "2"  !CDS_PN = "2";
BODY = "Q_CAP","I75": #LOCATION = "PC367" !CDS_LOCATION = "PC367" &SEC = "1" #&CDS_SEC = "1";
"A":   PN = "1"  !CDS_PN = "1";
"B":   PN = "2"  !CDS_PN = "2";
BODY = "Q_RES","I76": #LOCATION = "PR533" !CDS_LOCATION = "PR533" &SEC = "1" #&CDS_SEC = "1";
"A":   PN = "1"  !CDS_PN = "1";
"B":   PN = "2"  !CDS_PN = "2";
BODY = "Q_RES","I77": #LOCATION = "PR245" !CDS_LOCATION = "PR245" &SEC = "1" #&CDS_SEC = "1";
"A":   PN = "1"  !CDS_PN = "1";
"B":   PN = "2"  !CDS_PN = "2";
BODY = "Q_CAP","I79": #LOCATION = "PC358" !CDS_LOCATION = "PC358" &SEC = "1" #&CDS_SEC = "1";
"A":   PN = "1"  !CDS_PN = "1";
"B":   PN = "2"  !CDS_PN = "2";
BODY = "Q_RES","I80": #LOCATION = "R8250" !CDS_LOCATION = "R8250" &SEC = "1" #&CDS_SEC = "1";
"A":   PN = "1"  !CDS_PN = "1";
"B":   PN = "2"  !CDS_PN = "2";
BODY = "Q_RES","I81": #LOCATION = "R8249" !CDS_LOCATION = "R8249" &SEC = "1" #&CDS_SEC = "1";
"A":   PN = "1"  !CDS_PN = "1";
"B":   PN = "2"  !CDS_PN = "2";
BODY = "Q_RES","I82": #LOCATION = "R8238" !CDS_LOCATION = "R8238" &SEC = "1" #&CDS_SEC = "1";
"A":   PN = "1"  !CDS_PN = "1";
"B":   PN = "2"  !CDS_PN = "2";
BODY = "Q_RES","I83": #LOCATION = "PR239" !CDS_LOCATION = "PR239" &SEC = "1" #&CDS_SEC = "1";
"A":   PN = "1"  !CDS_PN = "1";
"B":   PN = "2"  !CDS_PN = "2";
BODY = "Q_RES","I84": #LOCATION = "R8248" !CDS_LOCATION = "R8248" &SEC = "1" #&CDS_SEC = "1";
"A":   PN = "1"  !CDS_PN = "1";
"B":   PN = "2"  !CDS_PN = "2";
BODY = "Q_CAP","I85": #LOCATION = "C8359" !CDS_LOCATION = "C8359" &SEC = "1" #&CDS_SEC = "1";
"A":   PN = "1"  !CDS_PN = "1";
"B":   PN = "2"  !CDS_PN = "2";
BODY = "Q_RES","I87": #LOCATION = "R8235" !CDS_LOCATION = "R8235" &SEC = "1" #&CDS_SEC = "1";
"A":   PN = "1"  !CDS_PN = "1";
"B":   PN = "2"  !CDS_PN = "2";
BODY = "Q_RES","I88": #LOCATION = "R8234" !CDS_LOCATION = "R8234" &SEC = "1" #&CDS_SEC = "1";
"A":   PN = "1"  !CDS_PN = "1";
"B":   PN = "2"  !CDS_PN = "2";
BODY = "Q_RES","I89": #LOCATION = "R8233" !CDS_LOCATION = "R8233" &SEC = "1" #&CDS_SEC = "1";
"A":   PN = "1"  !CDS_PN = "1";
"B":   PN = "2"  !CDS_PN = "2";
BODY = "Q_CAP","I90": #LOCATION = "C8360" !CDS_LOCATION = "C8360" &SEC = "1" #&CDS_SEC = "1";
"A":   PN = "1"  !CDS_PN = "1";
"B":   PN = "2"  !CDS_PN = "2";
BODY = "Q_CAP","I93": #LOCATION = "PC93" !CDS_LOCATION = "PC93" &SEC = "1" #&CDS_SEC = "1";
"A":   PN = "1"  !CDS_PN = "1";
"B":   PN = "2"  !CDS_PN = "2";
BODY = "Q_CAP","I95": #LOCATION = "PC29" !CDS_LOCATION = "PC29" &SEC = "1" #&CDS_SEC = "1";
"A":   PN = "1"  !CDS_PN = "1";
"B":   PN = "2"  !CDS_PN = "2";
BODY = "Q_CAP","I97": #LOCATION = "PC366" !CDS_LOCATION = "PC366" &SEC = "1" #&CDS_SEC = "1";
"A":   PN = "1"  !CDS_PN = "1";
"B":   PN = "2"  !CDS_PN = "2";
BODY = "Q_CAP","I99": #LOCATION = "PC365" !CDS_LOCATION = "PC365" &SEC = "1" #&CDS_SEC = "1";
"A":   PN = "1"  !CDS_PN = "1";
"B":   PN = "2"  !CDS_PN = "2";
BODY = "Q_RES","I124": #LOCATION = "PR253" !CDS_LOCATION = "PR253" &SEC = "1" #&CDS_SEC = "1";
"A":   PN = "1"  !CDS_PN = "1";
"B":   PN = "2"  !CDS_PN = "2";
BODY = "Q_RES","I127": #LOCATION = "PR12" !CDS_LOCATION = "PR12" &SEC = "1" #&CDS_SEC = "1";
"A":   PN = "1"  !CDS_PN = "1";
"B":   PN = "2"  !CDS_PN = "2";
BODY = "RAA229620GNPHA0","I128": #LOCATION = "PU34" !CDS_LOCATION = "PU34" #SEC = "1" !CDS_SEC = "1";
"CS0":   PN = "38"  !CDS_PN = "38";
"CS1":   PN = "37"  !CDS_PN = "37";
"CS2":   PN = "36"  !CDS_PN = "36";
"CS3":   PN = "35"  !CDS_PN = "35";
"CS4":   PN = "34"  !CDS_PN = "34";
"CS5":   PN = "33"  !CDS_PN = "33";
"CS6":   PN = "32"  !CDS_PN = "32";
"CS7":   PN = "31"  !CDS_PN = "31";
"CS8":   PN = "30"  !CDS_PN = "30";
"CS9":   PN = "29"  !CDS_PN = "29";
"CS10":   PN = "28"  !CDS_PN = "28";
"CS11":   PN = "27"  !CDS_PN = "27";
"EN0":   PN = "17"  !CDS_PN = "17";
"EN1||ADDR_CFG":   PN = "42"  !CDS_PN = "42";
"NPMALERT":   PN = "15"  !CDS_PN = "15";
"OCP_L":   PN = "41"  !CDS_PN = "41";
"PG0":   PN = "16"  !CDS_PN = "16";
"PG1":   PN = "20"  !CDS_PN = "20";
"PMSCL":   PN = "14"  !CDS_PN = "14";
"PMSDA":   PN = "13"  !CDS_PN = "13";
"PWM0":   PN = "1"  !CDS_PN = "1";
"PWM1":   PN = "2"  !CDS_PN = "2";
"PWM2":   PN = "3"  !CDS_PN = "3";
"PWM3":   PN = "4"  !CDS_PN = "4";
"PWM4":   PN = "5"  !CDS_PN = "5";
"PWM5":   PN = "6"  !CDS_PN = "6";
"PWM6":   PN = "7"  !CDS_PN = "7";
"PWM7":   PN = "8"  !CDS_PN = "8";
"PWM8":   PN = "9"  !CDS_PN = "9";
"PWM9":   PN = "10"  !CDS_PN = "10";
"PWM10":   PN = "11"  !CDS_PN = "11";
"PWM11":   PN = "12"  !CDS_PN = "12";
"RESET_L":   PN = "18"  !CDS_PN = "18";
"RGND0":   PN = "26"  !CDS_PN = "26";
"RGND1":   PN = "39"  !CDS_PN = "39";
"SVC":   PN = "22"  !CDS_PN = "22";
"SVD":   PN = "21"  !CDS_PN = "21";
"SVTI":   PN = "24"  !CDS_PN = "24";
"SVTO":   PN = "23"  !CDS_PN = "23";
"TEMP0":   PN = "44"  !CDS_PN = "44";
"TEMP1":   PN = "43"  !CDS_PN = "43";
"TH_GND":   PN = "TH"  !CDS_PN = "TH";
"VCC":   PN = "47"  !CDS_PN = "47";
"VCCS":   PN = "48"  !CDS_PN = "48";
"VDDIO":   PN = "19"  !CDS_PN = "19";
"VINSEN":   PN = "46"  !CDS_PN = "46";
"VMON||IINSEN":   PN = "45"  !CDS_PN = "45";
"VSEN0":   PN = "25"  !CDS_PN = "25";
"VSEN1":   PN = "40"  !CDS_PN = "40";
BODY = "Q_RES","I130": #LOCATION = "R6088" !CDS_LOCATION = "R6088" &SEC = "1" #&CDS_SEC = "1";
"A":   PN = "1"  !CDS_PN = "1";
"B":   PN = "2"  !CDS_PN = "2";
BODY = "Q_CAP","I131": #LOCATION = "C5022" !CDS_LOCATION = "C5022" &SEC = "1" #&CDS_SEC = "1";
"A":   PN = "1"  !CDS_PN = "1";
"B":   PN = "2"  !CDS_PN = "2";
BODY = "Q_CAP","I133": #LOCATION = "C5020" !CDS_LOCATION = "C5020" &SEC = "1" #&CDS_SEC = "1";
"A":   PN = "1"  !CDS_PN = "1";
"B":   PN = "2"  !CDS_PN = "2";
BODY = "Q_CAP","I136": #LOCATION = "C5006" !CDS_LOCATION = "C5006" &SEC = "1" #&CDS_SEC = "1";
"A":   PN = "1"  !CDS_PN = "1";
"B":   PN = "2"  !CDS_PN = "2";
BODY = "Q_RES","I137": #LOCATION = "PR8011" !CDS_LOCATION = "PR8011" &SEC = "1" #&CDS_SEC = "1";
"A":   PN = "1"  !CDS_PN = "1";
"B":   PN = "2"  !CDS_PN = "2";
BODY = "Q_RES","I138": #LOCATION = "PR8012" !CDS_LOCATION = "PR8012" &SEC = "1" #&CDS_SEC = "1";
"A":   PN = "1"  !CDS_PN = "1";
"B":   PN = "2"  !CDS_PN = "2";
DRAWING = "@t6g_mb_lib.t6g(sch_1):page197";
BODY = "Q_CAP","I3": #LOCATION = "PC436_8" !CDS_LOCATION = "PC436_8" &SEC = "1" #&CDS_SEC = "1";
"A":   PN = "1"  !CDS_PN = "1";
"B":   PN = "2"  !CDS_PN = "2";
BODY = "Q_CAP","I4": #LOCATION = "PC435_7" !CDS_LOCATION = "PC435_7" &SEC = "1" #&CDS_SEC = "1";
"A":   PN = "1"  !CDS_PN = "1";
"B":   PN = "2"  !CDS_PN = "2";
BODY = "Q_RES","I6": #LOCATION = "PR274" !CDS_LOCATION = "PR274" &SEC = "1" #&CDS_SEC = "1";
"A":   PN = "1"  !CDS_PN = "1";
"B":   PN = "2"  !CDS_PN = "2";
BODY = "Q_CAP","I12": #LOCATION = "PC432" !CDS_LOCATION = "PC432" &SEC = "1" #&CDS_SEC = "1";
"A":   PN = "1"  !CDS_PN = "1";
"B":   PN = "2"  !CDS_PN = "2";
BODY = "Q_RES","I13": #LOCATION = "PR276" !CDS_LOCATION = "PR276" &SEC = "1" #&CDS_SEC = "1";
"A":   PN = "1"  !CDS_PN = "1";
"B":   PN = "2"  !CDS_PN = "2";
BODY = "Q_CAP","I16": #LOCATION = "PC434_IOP1_2" !CDS_LOCATION = "PC434_IOP1_2" &SEC = "1" #&CDS_SEC = "1";
"A":   PN = "1"  !CDS_PN = "1";
"B":   PN = "2"  !CDS_PN = "2";
BODY = "Q_RES","I19": #LOCATION = "PR489" !CDS_LOCATION = "PR489" &SEC = "1" #&CDS_SEC = "1";
"A":   PN = "1"  !CDS_PN = "1";
"B":   PN = "2"  !CDS_PN = "2";
BODY = "Q_CAP","I20": #LOCATION = "PC175" !CDS_LOCATION = "PC175" &SEC = "1" #&CDS_SEC = "1";
"A":   PN = "1"  !CDS_PN = "1";
"B":   PN = "2"  !CDS_PN = "2";
BODY = "Q_CAP","I21": #LOCATION = "PC439_2" !CDS_LOCATION = "PC439_2" &SEC = "1" #&CDS_SEC = "1";
"A":   PN = "1"  !CDS_PN = "1";
"B":   PN = "2"  !CDS_PN = "2";
BODY = "Q_RES","I22": #LOCATION = "PR278" !CDS_LOCATION = "PR278" &SEC = "1" #&CDS_SEC = "1";
"A":   PN = "1"  !CDS_PN = "1";
"B":   PN = "2"  !CDS_PN = "2";
BODY = "Q_CAP","I23": #LOCATION = "PC441_2" !CDS_LOCATION = "PC441_2" &SEC = "1" #&CDS_SEC = "1";
"A":   PN = "1"  !CDS_PN = "1";
"B":   PN = "2"  !CDS_PN = "2";
BODY = "Q_RES","I26": #LOCATION = "PR488" !CDS_LOCATION = "PR488" &SEC = "1" #&CDS_SEC = "1";
"A":   PN = "1"  !CDS_PN = "1";
"B":   PN = "2"  !CDS_PN = "2";
BODY = "Q_RES","I28": #LOCATION = "PR275" !CDS_LOCATION = "PR275" &SEC = "1" #&CDS_SEC = "1";
"A":   PN = "1"  !CDS_PN = "1";
"B":   PN = "2"  !CDS_PN = "2";
BODY = "Q_CAP","I34": #LOCATION = "PC433" !CDS_LOCATION = "PC433" &SEC = "1" #&CDS_SEC = "1";
"A":   PN = "1"  !CDS_PN = "1";
"B":   PN = "2"  !CDS_PN = "2";
BODY = "Q_RES","I35": #LOCATION = "PR277" !CDS_LOCATION = "PR277" &SEC = "1" #&CDS_SEC = "1";
"A":   PN = "1"  !CDS_PN = "1";
"B":   PN = "2"  !CDS_PN = "2";
BODY = "Q_CAP","I38": #LOCATION = "PC437_IOP1_1" !CDS_LOCATION = "PC437_IOP1_1" &SEC = "1" #&CDS_SEC = "1";
"A":   PN = "1"  !CDS_PN = "1";
"B":   PN = "2"  !CDS_PN = "2";
BODY = "ISL99390FRZTR5935","I39": #LOCATION = "PU39" !CDS_LOCATION = "PU39" &SEC = "1" #&CDS_SEC = "1";
"AGND":   PN = "2"  !CDS_PN = "2";
"BOOT":   PN = "33"  !CDS_PN = "33";
"DNC":   PN = "31"  !CDS_PN = "31";
"EN":   PN = "35"  !CDS_PN = "35";
"GL1":   PN = "6"  !CDS_PN = "6";
"GL2":   PN = "41"  !CDS_PN = "41";
"IOUT":   PN = "38"  !CDS_PN = "38";
"LSET":   PN = "37"  !CDS_PN = "37";
"PGND1":   PN = "5"  !CDS_PN = "5";
"PGND2":   PN = "7_9-20_24"  !CDS_PN = "7_9-20_24";
"PGND3":   PN = "40"  !CDS_PN = "40";
"PHASE":   PN = "32"  !CDS_PN = "32";
"PVCC":   PN = "4"  !CDS_PN = "4";
"PWM":   PN = "34"  !CDS_PN = "34";
"REFIN":   PN = "39"  !CDS_PN = "39";
"SW":   PN = "10_19"  !CDS_PN = "10_19";
"TOUT_FLT":   PN = "36"  !CDS_PN = "36";
"VCC":   PN = "3"  !CDS_PN = "3";
"VIN1":   PN = "25_29"  !CDS_PN = "25_29";
"VIN2":   PN = "30"  !CDS_PN = "30";
"VOS":   PN = "1"  !CDS_PN = "1";
BODY = "Q_CAP","I40": #LOCATION = "PC174" !CDS_LOCATION = "PC174" &SEC = "1" #&CDS_SEC = "1";
"A":   PN = "1"  !CDS_PN = "1";
"B":   PN = "2"  !CDS_PN = "2";
BODY = "Q_CAP","I41": #LOCATION = "PC438_1" !CDS_LOCATION = "PC438_1" &SEC = "1" #&CDS_SEC = "1";
"A":   PN = "1"  !CDS_PN = "1";
"B":   PN = "2"  !CDS_PN = "2";
BODY = "Q_CAP","I42": #LOCATION = "PC440_1" !CDS_LOCATION = "PC440_1" &SEC = "1" #&CDS_SEC = "1";
"A":   PN = "1"  !CDS_PN = "1";
"B":   PN = "2"  !CDS_PN = "2";
BODY = "Q_RES","I43": #LOCATION = "PR279" !CDS_LOCATION = "PR279" &SEC = "1" #&CDS_SEC = "1";
"A":   PN = "1"  !CDS_PN = "1";
"B":   PN = "2"  !CDS_PN = "2";
BODY = "Q_CAP","I44": #LOCATION = "PC442_1" !CDS_LOCATION = "PC442_1" &SEC = "1" #&CDS_SEC = "1";
"A":   PN = "1"  !CDS_PN = "1";
"B":   PN = "2"  !CDS_PN = "2";
BODY = "Q_RES","I45": #LOCATION = "PR281" !CDS_LOCATION = "PR281" &SEC = "1" #&CDS_SEC = "1";
"A":   PN = "1"  !CDS_PN = "1";
"B":   PN = "2"  !CDS_PN = "2";
BODY = "Q_CAP","I47": #LOCATION = "PC445" !CDS_LOCATION = "PC445" &SEC = "1" #&CDS_SEC = "1";
"A":   PN = "1"  !CDS_PN = "1";
"B":   PN = "2"  !CDS_PN = "2";
BODY = "Q_CAP","I48": #LOCATION = "PC443_2" !CDS_LOCATION = "PC443_2" &SEC = "1" #&CDS_SEC = "1";
"A":   PN = "1"  !CDS_PN = "1";
"B":   PN = "2"  !CDS_PN = "2";
BODY = "Q_CAP","I49": #LOCATION = "PC446_2" !CDS_LOCATION = "PC446_2" &SEC = "1" #&CDS_SEC = "1";
"A":   PN = "1"  !CDS_PN = "1";
"B":   PN = "2"  !CDS_PN = "2";
BODY = "Q_RES","I50": #LOCATION = "PR280" !CDS_LOCATION = "PR280" &SEC = "1" #&CDS_SEC = "1";
"A":   PN = "1"  !CDS_PN = "1";
"B":   PN = "2"  !CDS_PN = "2";
BODY = "Q_CAP","I52": #LOCATION = "PC449_2" !CDS_LOCATION = "PC449_2" &SEC = "1" #&CDS_SEC = "1";
"A":   PN = "1"  !CDS_PN = "1";
"B":   PN = "2"  !CDS_PN = "2";
BODY = "Q_CAP","I55": #LOCATION = "PC458_2" !CDS_LOCATION = "PC458_2" &SEC = "1" #&CDS_SEC = "1";
"A":   PN = "1"  !CDS_PN = "1";
"B":   PN = "2"  !CDS_PN = "2";
BODY = "Q_CAP","I57": #LOCATION = "PC460_2" !CDS_LOCATION = "PC460_2" &SEC = "1" #&CDS_SEC = "1";
"A":   PN = "1"  !CDS_PN = "1";
"B":   PN = "2"  !CDS_PN = "2";
BODY = "Q_CAPP","I58": #LOCATION = "PC450" !CDS_LOCATION = "PC450" &SEC = "1" #&CDS_SEC = "1";
"A":   PN = "1"  !CDS_PN = "1";
"B":   PN = "2"  !CDS_PN = "2";
BODY = "Q_CAPP","I59": #LOCATION = "PC452" !CDS_LOCATION = "PC452" &SEC = "1" #&CDS_SEC = "1";
"A":   PN = "1"  !CDS_PN = "1";
"B":   PN = "2"  !CDS_PN = "2";
BODY = "Q_CAPP","I62": #LOCATION = "PC455" !CDS_LOCATION = "PC455" &SEC = "1" #&CDS_SEC = "1";
"A":   PN = "1"  !CDS_PN = "1";
"B":   PN = "2"  !CDS_PN = "2";
BODY = "Q_CAP","I65": #LOCATION = "PC447" !CDS_LOCATION = "PC447" &SEC = "1" #&CDS_SEC = "1";
"A":   PN = "1"  !CDS_PN = "1";
"B":   PN = "2"  !CDS_PN = "2";
BODY = "Q_CAP","I66": #LOCATION = "PC444_1" !CDS_LOCATION = "PC444_1" &SEC = "1" #&CDS_SEC = "1";
"A":   PN = "1"  !CDS_PN = "1";
"B":   PN = "2"  !CDS_PN = "2";
BODY = "Q_CAP","I69": #LOCATION = "PC448_1" !CDS_LOCATION = "PC448_1" &SEC = "1" #&CDS_SEC = "1";
"A":   PN = "1"  !CDS_PN = "1";
"B":   PN = "2"  !CDS_PN = "2";
BODY = "Q_INDUCTOR4P_14","I71": #LOCATION = "PL47" !CDS_LOCATION = "PL47" &SEC = "1" #&CDS_SEC = "1";
"1":   PN = "1"  !CDS_PN = "1";
"2":   PN = "2"  !CDS_PN = "2";
"3":   PN = "3"  !CDS_PN = "3";
"4":   PN = "4"  !CDS_PN = "4";
BODY = "Q_INDUCTOR","I72": #LOCATION = "PL49" !CDS_LOCATION = "PL49" &SEC = "1" #&CDS_SEC = "1";
"1":   PN = "1"  !CDS_PN = "1";
"2":   PN = "2"  !CDS_PN = "2";
BODY = "Q_CAP","I74": #LOCATION = "PC438" !CDS_LOCATION = "PC438" &SEC = "1" #&CDS_SEC = "1";
"A":   PN = "1"  !CDS_PN = "1";
"B":   PN = "2"  !CDS_PN = "2";
BODY = "Q_CAP","I77": #LOCATION = "PC451" !CDS_LOCATION = "PC451" &SEC = "1" #&CDS_SEC = "1";
"A":   PN = "1"  !CDS_PN = "1";
"B":   PN = "2"  !CDS_PN = "2";
BODY = "Q_CAP","I78": #LOCATION = "PC456_1" !CDS_LOCATION = "PC456_1" &SEC = "1" #&CDS_SEC = "1";
"A":   PN = "1"  !CDS_PN = "1";
"B":   PN = "2"  !CDS_PN = "2";
BODY = "Q_CAP","I79": #LOCATION = "PC459_1" !CDS_LOCATION = "PC459_1" &SEC = "1" #&CDS_SEC = "1";
"A":   PN = "1"  !CDS_PN = "1";
"B":   PN = "2"  !CDS_PN = "2";
BODY = "Q_RES","I81": #LOCATION = "PR378" !CDS_LOCATION = "PR378" &SEC = "1" #&CDS_SEC = "1";
"A":   PN = "1"  !CDS_PN = "1";
"B":   PN = "2"  !CDS_PN = "2";
BODY = "Q_INDUCTOR4P_14","I83": #LOCATION = "PL48" !CDS_LOCATION = "PL48" &SEC = "1" #&CDS_SEC = "1";
"1":   PN = "1"  !CDS_PN = "1";
"2":   PN = "2"  !CDS_PN = "2";
"3":   PN = "3"  !CDS_PN = "3";
"4":   PN = "4"  !CDS_PN = "4";
BODY = "ISL99390FRZTR5935","I84": #LOCATION = "PU40" !CDS_LOCATION = "PU40" &SEC = "1" #&CDS_SEC = "1";
"AGND":   PN = "2"  !CDS_PN = "2";
"BOOT":   PN = "33"  !CDS_PN = "33";
"DNC":   PN = "31"  !CDS_PN = "31";
"EN":   PN = "35"  !CDS_PN = "35";
"GL1":   PN = "6"  !CDS_PN = "6";
"GL2":   PN = "41"  !CDS_PN = "41";
"IOUT":   PN = "38"  !CDS_PN = "38";
"LSET":   PN = "37"  !CDS_PN = "37";
"PGND1":   PN = "5"  !CDS_PN = "5";
"PGND2":   PN = "7_9-20_24"  !CDS_PN = "7_9-20_24";
"PGND3":   PN = "40"  !CDS_PN = "40";
"PHASE":   PN = "32"  !CDS_PN = "32";
"PVCC":   PN = "4"  !CDS_PN = "4";
"PWM":   PN = "34"  !CDS_PN = "34";
"REFIN":   PN = "39"  !CDS_PN = "39";
"SW":   PN = "10_19"  !CDS_PN = "10_19";
"TOUT_FLT":   PN = "36"  !CDS_PN = "36";
"VCC":   PN = "3"  !CDS_PN = "3";
"VIN1":   PN = "25_29"  !CDS_PN = "25_29";
"VIN2":   PN = "30"  !CDS_PN = "30";
"VOS":   PN = "1"  !CDS_PN = "1";
BODY = "Q_CAPP","I85": #LOCATION = "PC454" !CDS_LOCATION = "PC454" &SEC = "1" #&CDS_SEC = "1";
"A":   PN = "1"  !CDS_PN = "1";
"B":   PN = "2"  !CDS_PN = "2";
BODY = "Q_CAP","I86": #LOCATION = "PC7001" !CDS_LOCATION = "PC7001" &SEC = "1" #&CDS_SEC = "1";
"A":   PN = "1"  !CDS_PN = "1";
"B":   PN = "2"  !CDS_PN = "2";
DRAWING = "@t6g_mb_lib.t6g(sch_1):page199";
BODY = "Q_RES","I2": #LOCATION = "PR376" !CDS_LOCATION = "PR376" &SEC = "1" #&CDS_SEC = "1";
"A":   PN = "1"  !CDS_PN = "1";
"B":   PN = "2"  !CDS_PN = "2";
BODY = "Q_CAP","I4": #LOCATION = "PC638" !CDS_LOCATION = "PC638" &SEC = "1" #&CDS_SEC = "1";
"A":   PN = "1"  !CDS_PN = "1";
"B":   PN = "2"  !CDS_PN = "2";
BODY = "Q_RES","I6": #LOCATION = "PR6" !CDS_LOCATION = "PR6" #SEC = "1" !CDS_SEC = "1";
"A":   PN = "1"  !CDS_PN = "1";
"B":   PN = "2"  !CDS_PN = "2";
BODY = "Q_RES","I9": #LOCATION = "R8146" !CDS_LOCATION = "R8146" &SEC = "1" #&CDS_SEC = "1";
"A":   PN = "1"  !CDS_PN = "1";
"B":   PN = "2"  !CDS_PN = "2";
BODY = "Q_RES","I13": #LOCATION = "R8010" !CDS_LOCATION = "R8010" &SEC = "1" #&CDS_SEC = "1";
"A":   PN = "1"  !CDS_PN = "1";
"B":   PN = "2"  !CDS_PN = "2";
BODY = "Q_RES","I15": #LOCATION = "PR288" !CDS_LOCATION = "PR288" &SEC = "1" #&CDS_SEC = "1";
"A":   PN = "1"  !CDS_PN = "1";
"B":   PN = "2"  !CDS_PN = "2";
BODY = "Q_RES","I17": #LOCATION = "PR604" !CDS_LOCATION = "PR604" &SEC = "1" #&CDS_SEC = "1";
"A":   PN = "1"  !CDS_PN = "1";
"B":   PN = "2"  !CDS_PN = "2";
BODY = "Q_RES","I18": #LOCATION = "PR388" !CDS_LOCATION = "PR388" &SEC = "1" #&CDS_SEC = "1";
"A":   PN = "1"  !CDS_PN = "1";
"B":   PN = "2"  !CDS_PN = "2";
BODY = "Q_CAP","I20": #LOCATION = "PC8" !CDS_LOCATION = "PC8" #SEC = "1" !CDS_SEC = "1";
"A":   PN = "1"  !CDS_PN = "1";
"B":   PN = "2"  !CDS_PN = "2";
BODY = "Q_RES","I24": #LOCATION = "R8011" !CDS_LOCATION = "R8011" &SEC = "1" #&CDS_SEC = "1";
"A":   PN = "1"  !CDS_PN = "1";
"B":   PN = "2"  !CDS_PN = "2";
BODY = "Q_RES","I27": #LOCATION = "PR384" !CDS_LOCATION = "PR384" &SEC = "1" #&CDS_SEC = "1";
"A":   PN = "1"  !CDS_PN = "1";
"B":   PN = "2"  !CDS_PN = "2";
BODY = "Q_CAP","I28": #LOCATION = "PC639" !CDS_LOCATION = "PC639" &SEC = "1" #&CDS_SEC = "1";
"A":   PN = "1"  !CDS_PN = "1";
"B":   PN = "2"  !CDS_PN = "2";
BODY = "Q_RES","I29": #LOCATION = "PR229" !CDS_LOCATION = "PR229" &SEC = "1" #&CDS_SEC = "1";
"A":   PN = "1"  !CDS_PN = "1";
"B":   PN = "2"  !CDS_PN = "2";
BODY = "Q_RES","I37": #LOCATION = "R8380" !CDS_LOCATION = "R8380" &SEC = "1" #&CDS_SEC = "1";
"A":   PN = "1"  !CDS_PN = "1";
"B":   PN = "2"  !CDS_PN = "2";
BODY = "Q_RES","I38": #LOCATION = "R8383" !CDS_LOCATION = "R8383" &SEC = "1" #&CDS_SEC = "1";
"A":   PN = "1"  !CDS_PN = "1";
"B":   PN = "2"  !CDS_PN = "2";
BODY = "Q_RES","I39": #LOCATION = "R8382" !CDS_LOCATION = "R8382" &SEC = "1" #&CDS_SEC = "1";
"A":   PN = "1"  !CDS_PN = "1";
"B":   PN = "2"  !CDS_PN = "2";
BODY = "Q_RES","I40": #LOCATION = "R8381" !CDS_LOCATION = "R8381" &SEC = "1" #&CDS_SEC = "1";
"A":   PN = "1"  !CDS_PN = "1";
"B":   PN = "2"  !CDS_PN = "2";
BODY = "Q_RES","I42": #LOCATION = "R8386" !CDS_LOCATION = "R8386" &SEC = "1" #&CDS_SEC = "1";
"A":   PN = "1"  !CDS_PN = "1";
"B":   PN = "2"  !CDS_PN = "2";
BODY = "Q_RES","I43": #LOCATION = "R8385" !CDS_LOCATION = "R8385" &SEC = "1" #&CDS_SEC = "1";
"A":   PN = "1"  !CDS_PN = "1";
"B":   PN = "2"  !CDS_PN = "2";
BODY = "Q_CAP","I44": #LOCATION = "C642" !CDS_LOCATION = "C642" &SEC = "1" #&CDS_SEC = "1";
"A":   PN = "1"  !CDS_PN = "1";
"B":   PN = "2"  !CDS_PN = "2";
BODY = "Q_CAP","I46": #LOCATION = "C8641" !CDS_LOCATION = "C8641" &SEC = "1" #&CDS_SEC = "1";
"A":   PN = "1"  !CDS_PN = "1";
"B":   PN = "2"  !CDS_PN = "2";
BODY = "Q_CAP","I49": #LOCATION = "PC643" !CDS_LOCATION = "PC643" &SEC = "1" #&CDS_SEC = "1";
"A":   PN = "1"  !CDS_PN = "1";
"B":   PN = "2"  !CDS_PN = "2";
BODY = "Q_RES","I51": #LOCATION = "PR415" !CDS_LOCATION = "PR415" &SEC = "1" #&CDS_SEC = "1";
"A":   PN = "1"  !CDS_PN = "1";
"B":   PN = "2"  !CDS_PN = "2";
BODY = "Q_RES","I52": #LOCATION = "PR409" !CDS_LOCATION = "PR409" &SEC = "1" #&CDS_SEC = "1";
"A":   PN = "1"  !CDS_PN = "1";
"B":   PN = "2"  !CDS_PN = "2";
BODY = "Q_RES","I56": #LOCATION = "PR390" !CDS_LOCATION = "PR390" &SEC = "1" #&CDS_SEC = "1";
"A":   PN = "1"  !CDS_PN = "1";
"B":   PN = "2"  !CDS_PN = "2";
BODY = "Q_RES","I57": #LOCATION = "PR408" !CDS_LOCATION = "PR408" &SEC = "1" #&CDS_SEC = "1";
"A":   PN = "1"  !CDS_PN = "1";
"B":   PN = "2"  !CDS_PN = "2";
BODY = "Q_RES","I58": #LOCATION = "PR14" !CDS_LOCATION = "PR14" &SEC = "1" #&CDS_SEC = "1";
"A":   PN = "1"  !CDS_PN = "1";
"B":   PN = "2"  !CDS_PN = "2";
BODY = "Q_RES","I59": #LOCATION = "PR13" !CDS_LOCATION = "PR13" &SEC = "1" #&CDS_SEC = "1";
"A":   PN = "1"  !CDS_PN = "1";
"B":   PN = "2"  !CDS_PN = "2";
BODY = "Q_RES","I60": #LOCATION = "PR407" !CDS_LOCATION = "PR407" &SEC = "1" #&CDS_SEC = "1";
"A":   PN = "1"  !CDS_PN = "1";
"B":   PN = "2"  !CDS_PN = "2";
BODY = "Q_RES","I66": #LOCATION = "PR392" !CDS_LOCATION = "PR392" &SEC = "1" #&CDS_SEC = "1";
"A":   PN = "1"  !CDS_PN = "1";
"B":   PN = "2"  !CDS_PN = "2";
BODY = "Q_RES","I67": #LOCATION = "PR391" !CDS_LOCATION = "PR391" &SEC = "1" #&CDS_SEC = "1";
"A":   PN = "1"  !CDS_PN = "1";
"B":   PN = "2"  !CDS_PN = "2";
BODY = "Q_RES","I70": #LOCATION = "PR406" !CDS_LOCATION = "PR406" &SEC = "1" #&CDS_SEC = "1";
"A":   PN = "1"  !CDS_PN = "1";
"B":   PN = "2"  !CDS_PN = "2";
BODY = "Q_CAP","I72": #LOCATION = "PC96" !CDS_LOCATION = "PC96" &SEC = "1" #&CDS_SEC = "1";
"A":   PN = "1"  !CDS_PN = "1";
"B":   PN = "2"  !CDS_PN = "2";
BODY = "Q_CAP","I73": #LOCATION = "PC95" !CDS_LOCATION = "PC95" &SEC = "1" #&CDS_SEC = "1";
"A":   PN = "1"  !CDS_PN = "1";
"B":   PN = "2"  !CDS_PN = "2";
BODY = "Q_CAP","I80": #LOCATION = "PC644" !CDS_LOCATION = "PC644" &SEC = "1" #&CDS_SEC = "1";
"A":   PN = "1"  !CDS_PN = "1";
"B":   PN = "2"  !CDS_PN = "2";
BODY = "Q_CAP","I81": #LOCATION = "PC645" !CDS_LOCATION = "PC645" &SEC = "1" #&CDS_SEC = "1";
"A":   PN = "1"  !CDS_PN = "1";
"B":   PN = "2"  !CDS_PN = "2";
BODY = "Q_RES","I84": #LOCATION = "PR393" !CDS_LOCATION = "PR393" &SEC = "1" #&CDS_SEC = "1";
"A":   PN = "1"  !CDS_PN = "1";
"B":   PN = "2"  !CDS_PN = "2";
BODY = "RAA229621GNPHA0","I86": #LOCATION = "PU54" !CDS_LOCATION = "PU54" &SEC = "1" #&CDS_SEC = "1";
"CS0":   PN = "30"  !CDS_PN = "30";
"CS1":   PN = "29"  !CDS_PN = "29";
"CS2":   PN = "28"  !CDS_PN = "28";
"CS3":   PN = "27"  !CDS_PN = "27";
"CS4":   PN = "26"  !CDS_PN = "26";
"CS5":   PN = "25"  !CDS_PN = "25";
"CS6":   PN = "24"  !CDS_PN = "24";
"CS7":   PN = "23"  !CDS_PN = "23";
"EN0":   PN = "13"  !CDS_PN = "13";
"EN1||ADDR_CFG":   PN = "34"  !CDS_PN = "34";
"NPMALERT":   PN = "11"  !CDS_PN = "11";
"OCP_L":   PN = "33"  !CDS_PN = "33";
"PG0":   PN = "12"  !CDS_PN = "12";
"PG1":   PN = "16"  !CDS_PN = "16";
"PMSCL":   PN = "10"  !CDS_PN = "10";
"PMSDA":   PN = "9"  !CDS_PN = "9";
"PWM0":   PN = "1"  !CDS_PN = "1";
"PWM1":   PN = "2"  !CDS_PN = "2";
"PWM2":   PN = "3"  !CDS_PN = "3";
"PWM3":   PN = "4"  !CDS_PN = "4";
"PWM4":   PN = "5"  !CDS_PN = "5";
"PWM5":   PN = "6"  !CDS_PN = "6";
"PWM6":   PN = "7"  !CDS_PN = "7";
"PWM7":   PN = "8"  !CDS_PN = "8";
"RESET_L":   PN = "14"  !CDS_PN = "14";
"RGND0":   PN = "22"  !CDS_PN = "22";
"RGND1":   PN = "31"  !CDS_PN = "31";
"SVC":   PN = "18"  !CDS_PN = "18";
"SVD":   PN = "17"  !CDS_PN = "17";
"SVTI":   PN = "20"  !CDS_PN = "20";
"SVTO":   PN = "19"  !CDS_PN = "19";
"TEMP0":   PN = "36"  !CDS_PN = "36";
"TEMP1":   PN = "35"  !CDS_PN = "35";
"TH_GND":   PN = "TH"  !CDS_PN = "TH";
"VCC":   PN = "39"  !CDS_PN = "39";
"VCCS":   PN = "40"  !CDS_PN = "40";
"VDDIO":   PN = "15"  !CDS_PN = "15";
"VINSEN":   PN = "38"  !CDS_PN = "38";
"VMON||IINSEN":   PN = "37"  !CDS_PN = "37";
"VSEN0":   PN = "21"  !CDS_PN = "21";
"VSEN1":   PN = "32"  !CDS_PN = "32";
BODY = "Q_CAP","I88": #LOCATION = "C5010" !CDS_LOCATION = "C5010" &SEC = "1" #&CDS_SEC = "1";
"A":   PN = "1"  !CDS_PN = "1";
"B":   PN = "2"  !CDS_PN = "2";
BODY = "Q_RES","I89": #LOCATION = "PR464" !CDS_LOCATION = "PR464" &SEC = "1" #&CDS_SEC = "1";
"A":   PN = "1"  !CDS_PN = "1";
"B":   PN = "2"  !CDS_PN = "2";
DRAWING = "@t6g_mb_lib.t6g(sch_1):page369";
BODY = "Q_RES","I6": #LOCATION = "R1799" !CDS_LOCATION = "R1799" &SEC = "1" #&CDS_SEC = "1";
"A":   PN = "1"  !CDS_PN = "1";
"B":   PN = "2"  !CDS_PN = "2";
BODY = "Q_RES","I7": #LOCATION = "R4568" !CDS_LOCATION = "R4568" &SEC = "1" #&CDS_SEC = "1";
"A":   PN = "1"  !CDS_PN = "1";
"B":   PN = "2"  !CDS_PN = "2";
BODY = "Q_RES","I8": #LOCATION = "R4567" !CDS_LOCATION = "R4567" &SEC = "1" #&CDS_SEC = "1";
"A":   PN = "1"  !CDS_PN = "1";
"B":   PN = "2"  !CDS_PN = "2";
BODY = "Q_RES","I9": #LOCATION = "R3680" !CDS_LOCATION = "R3680" &SEC = "1" #&CDS_SEC = "1";
"A":   PN = "1"  !CDS_PN = "1";
"B":   PN = "2"  !CDS_PN = "2";
BODY = "Q_RES","I10": #LOCATION = "R3679" !CDS_LOCATION = "R3679" &SEC = "1" #&CDS_SEC = "1";
"A":   PN = "1"  !CDS_PN = "1";
"B":   PN = "2"  !CDS_PN = "2";
BODY = "Q_RES","I14": #LOCATION = "R1791" !CDS_LOCATION = "R1791" &SEC = "1" #&CDS_SEC = "1";
"A":   PN = "1"  !CDS_PN = "1";
"B":   PN = "2"  !CDS_PN = "2";
BODY = "Q_RES","I15": #LOCATION = "R3005" !CDS_LOCATION = "R3005" &SEC = "1" #&CDS_SEC = "1";
"A":   PN = "1"  !CDS_PN = "1";
"B":   PN = "2"  !CDS_PN = "2";
BODY = "Q_RES","I16": #LOCATION = "R3686" !CDS_LOCATION = "R3686" &SEC = "1" #&CDS_SEC = "1";
"A":   PN = "1"  !CDS_PN = "1";
"B":   PN = "2"  !CDS_PN = "2";
BODY = "Q_CAP","I17": #LOCATION = "C2049" !CDS_LOCATION = "C2049" &SEC = "1" #&CDS_SEC = "1";
"A":   PN = "1"  !CDS_PN = "1";
"B":   PN = "2"  !CDS_PN = "2";
BODY = "Q_RES","I18": #LOCATION = "R3685" !CDS_LOCATION = "R3685" &SEC = "1" #&CDS_SEC = "1";
"A":   PN = "1"  !CDS_PN = "1";
"B":   PN = "2"  !CDS_PN = "2";
BODY = "Q_RES","I20": #LOCATION = "R2843" !CDS_LOCATION = "R2843" &SEC = "1" #&CDS_SEC = "1";
"A":   PN = "1"  !CDS_PN = "1";
"B":   PN = "2"  !CDS_PN = "2";
BODY = "Q_RES","I21": #LOCATION = "R2908" !CDS_LOCATION = "R2908" &SEC = "1" #&CDS_SEC = "1";
"A":   PN = "1"  !CDS_PN = "1";
"B":   PN = "2"  !CDS_PN = "2";
BODY = "Q_RES","I22": #LOCATION = "R3684" !CDS_LOCATION = "R3684" &SEC = "1" #&CDS_SEC = "1";
"A":   PN = "1"  !CDS_PN = "1";
"B":   PN = "2"  !CDS_PN = "2";
BODY = "Q_RES","I23": #LOCATION = "R3683" !CDS_LOCATION = "R3683" &SEC = "1" #&CDS_SEC = "1";
"A":   PN = "1"  !CDS_PN = "1";
"B":   PN = "2"  !CDS_PN = "2";
BODY = "Q_RES","I26": #LOCATION = "R1785" !CDS_LOCATION = "R1785" &SEC = "1" #&CDS_SEC = "1";
"A":   PN = "1"  !CDS_PN = "1";
"B":   PN = "2"  !CDS_PN = "2";
BODY = "Q_RES","I27": #LOCATION = "R3682" !CDS_LOCATION = "R3682" &SEC = "1" #&CDS_SEC = "1";
"A":   PN = "1"  !CDS_PN = "1";
"B":   PN = "2"  !CDS_PN = "2";
BODY = "Q_RES","I28": #LOCATION = "R2907" !CDS_LOCATION = "R2907" &SEC = "1" #&CDS_SEC = "1";
"A":   PN = "1"  !CDS_PN = "1";
"B":   PN = "2"  !CDS_PN = "2";
BODY = "Q_RES","I30": #LOCATION = "R3681" !CDS_LOCATION = "R3681" &SEC = "1" #&CDS_SEC = "1";
"A":   PN = "1"  !CDS_PN = "1";
"B":   PN = "2"  !CDS_PN = "2";
BODY = "Q_CAP","I32": #LOCATION = "C2048" !CDS_LOCATION = "C2048" &SEC = "1" #&CDS_SEC = "1";
"A":   PN = "1"  !CDS_PN = "1";
"B":   PN = "2"  !CDS_PN = "2";
BODY = "Q_CAP","I34": #LOCATION = "C2050" !CDS_LOCATION = "C2050" &SEC = "1" #&CDS_SEC = "1";
"A":   PN = "1"  !CDS_PN = "1";
"B":   PN = "2"  !CDS_PN = "2";
BODY = "Q_CAP","I36": #LOCATION = "C2045" !CDS_LOCATION = "C2045" &SEC = "1" #&CDS_SEC = "1";
"A":   PN = "1"  !CDS_PN = "1";
"B":   PN = "2"  !CDS_PN = "2";
BODY = "Q_RES","I38": #LOCATION = "R3668" !CDS_LOCATION = "R3668" &SEC = "1" #&CDS_SEC = "1";
"A":   PN = "1"  !CDS_PN = "1";
"B":   PN = "2"  !CDS_PN = "2";
BODY = "Q_RES","I40": #LOCATION = "R3670" !CDS_LOCATION = "R3670" &SEC = "1" #&CDS_SEC = "1";
"A":   PN = "1"  !CDS_PN = "1";
"B":   PN = "2"  !CDS_PN = "2";
BODY = "Q_RES","I41": #LOCATION = "R3688" !CDS_LOCATION = "R3688" &SEC = "1" #&CDS_SEC = "1";
"A":   PN = "1"  !CDS_PN = "1";
"B":   PN = "2"  !CDS_PN = "2";
BODY = "Q_RES","I42": #LOCATION = "R3687" !CDS_LOCATION = "R3687" &SEC = "1" #&CDS_SEC = "1";
"A":   PN = "1"  !CDS_PN = "1";
"B":   PN = "2"  !CDS_PN = "2";
BODY = "Q_CAP","I44": #LOCATION = "C2046" !CDS_LOCATION = "C2046" &SEC = "1" #&CDS_SEC = "1";
"A":   PN = "1"  !CDS_PN = "1";
"B":   PN = "2"  !CDS_PN = "2";
BODY = "Q_CAP","I46": #LOCATION = "C1344" !CDS_LOCATION = "C1344" &SEC = "1" #&CDS_SEC = "1";
"A":   PN = "1"  !CDS_PN = "1";
"B":   PN = "2"  !CDS_PN = "2";
BODY = "Q_CAP","I52": #LOCATION = "C2044" !CDS_LOCATION = "C2044" &SEC = "1" #&CDS_SEC = "1";
"A":   PN = "1"  !CDS_PN = "1";
"B":   PN = "2"  !CDS_PN = "2";
BODY = "Q_CAP","I55": #LOCATION = "C2043" !CDS_LOCATION = "C2043" &SEC = "1" #&CDS_SEC = "1";
"A":   PN = "1"  !CDS_PN = "1";
"B":   PN = "2"  !CDS_PN = "2";
BODY = "Q_RES","I66": #LOCATION = "R3667" !CDS_LOCATION = "R3667" &SEC = "1" #&CDS_SEC = "1";
"A":   PN = "1"  !CDS_PN = "1";
"B":   PN = "2"  !CDS_PN = "2";
BODY = "Q_RES","I68": #LOCATION = "R3669" !CDS_LOCATION = "R3669" &SEC = "1" #&CDS_SEC = "1";
"A":   PN = "1"  !CDS_PN = "1";
"B":   PN = "2"  !CDS_PN = "2";
BODY = "Q_INDUCTOR","I69": #LOCATION = "L16" !CDS_LOCATION = "L16" &SEC = "1" #&CDS_SEC = "1";
"1":   PN = "1"  !CDS_PN = "1";
"2":   PN = "2"  !CDS_PN = "2";
BODY = "Q_CAP","I71": #LOCATION = "C2051" !CDS_LOCATION = "C2051" &SEC = "1" #&CDS_SEC = "1";
"A":   PN = "1"  !CDS_PN = "1";
"B":   PN = "2"  !CDS_PN = "2";
BODY = "Q_CAP","I72": #LOCATION = "C2052" !CDS_LOCATION = "C2052" &SEC = "1" #&CDS_SEC = "1";
"A":   PN = "1"  !CDS_PN = "1";
"B":   PN = "2"  !CDS_PN = "2";
BODY = "Q_RES","I73": #LOCATION = "R3942" !CDS_LOCATION = "R3942" &SEC = "1" #&CDS_SEC = "1";
"A":   PN = "1"  !CDS_PN = "1";
"B":   PN = "2"  !CDS_PN = "2";
BODY = "Q_RES","I74": #LOCATION = "R3941" !CDS_LOCATION = "R3941" &SEC = "1" #&CDS_SEC = "1";
"A":   PN = "1"  !CDS_PN = "1";
"B":   PN = "2"  !CDS_PN = "2";
BODY = "Q_CAP","I76": #LOCATION = "C2194" !CDS_LOCATION = "C2194" &SEC = "1" #&CDS_SEC = "1";
"A":   PN = "1"  !CDS_PN = "1";
"B":   PN = "2"  !CDS_PN = "2";
BODY = "Q_CAP","I78": #LOCATION = "C35" !CDS_LOCATION = "C35" &SEC = "1" #&CDS_SEC = "1";
"A":   PN = "1"  !CDS_PN = "1";
"B":   PN = "2"  !CDS_PN = "2";
BODY = "Q_RES","I79": #LOCATION = "R3940" !CDS_LOCATION = "R3940" &SEC = "1" #&CDS_SEC = "1";
"A":   PN = "1"  !CDS_PN = "1";
"B":   PN = "2"  !CDS_PN = "2";
BODY = "Q_RES","I80": #LOCATION = "R3939" !CDS_LOCATION = "R3939" &SEC = "1" #&CDS_SEC = "1";
"A":   PN = "1"  !CDS_PN = "1";
"B":   PN = "2"  !CDS_PN = "2";
BODY = "Q_RES","I81": #LOCATION = "R3862" !CDS_LOCATION = "R3862" &SEC = "1" #&CDS_SEC = "1";
"A":   PN = "1"  !CDS_PN = "1";
"B":   PN = "2"  !CDS_PN = "2";
BODY = "Q_RES","I82": #LOCATION = "R3861" !CDS_LOCATION = "R3861" &SEC = "1" #&CDS_SEC = "1";
"A":   PN = "1"  !CDS_PN = "1";
"B":   PN = "2"  !CDS_PN = "2";
BODY = "Q_RES","I83": #LOCATION = "R3860" !CDS_LOCATION = "R3860" &SEC = "1" #&CDS_SEC = "1";
"A":   PN = "1"  !CDS_PN = "1";
"B":   PN = "2"  !CDS_PN = "2";
BODY = "Q_CAP","I84": #LOCATION = "C33" !CDS_LOCATION = "C33" &SEC = "1" #&CDS_SEC = "1";
"A":   PN = "1"  !CDS_PN = "1";
"B":   PN = "2"  !CDS_PN = "2";
BODY = "Q_CAP","I87": #LOCATION = "C59" !CDS_LOCATION = "C59" &SEC = "1" #&CDS_SEC = "1";
"A":   PN = "1"  !CDS_PN = "1";
"B":   PN = "2"  !CDS_PN = "2";
BODY = "Q_CAP","I98": #LOCATION = "C2047" !CDS_LOCATION = "C2047" &SEC = "1" #&CDS_SEC = "1";
"A":   PN = "1"  !CDS_PN = "1";
"B":   PN = "2"  !CDS_PN = "2";
BODY = "Q_CAP","I99": #LOCATION = "C2042" !CDS_LOCATION = "C2042" &SEC = "1" #&CDS_SEC = "1";
"A":   PN = "1"  !CDS_PN = "1";
"B":   PN = "2"  !CDS_PN = "2";
BODY = "Q_RES","I107": #LOCATION = "R3859" !CDS_LOCATION = "R3859" &SEC = "1" #&CDS_SEC = "1";
"A":   PN = "1"  !CDS_PN = "1";
"B":   PN = "2"  !CDS_PN = "2";
BODY = "Q_RES","I108": #LOCATION = "R3866" !CDS_LOCATION = "R3866" &SEC = "1" #&CDS_SEC = "1";
"A":   PN = "1"  !CDS_PN = "1";
"B":   PN = "2"  !CDS_PN = "2";
BODY = "Q_RES","I109": #LOCATION = "R3865" !CDS_LOCATION = "R3865" &SEC = "1" #&CDS_SEC = "1";
"A":   PN = "1"  !CDS_PN = "1";
"B":   PN = "2"  !CDS_PN = "2";
BODY = "Q_RES","I110": #LOCATION = "R3864" !CDS_LOCATION = "R3864" &SEC = "1" #&CDS_SEC = "1";
"A":   PN = "1"  !CDS_PN = "1";
"B":   PN = "2"  !CDS_PN = "2";
BODY = "Q_CAP","I112": #LOCATION = "C37" !CDS_LOCATION = "C37" &SEC = "1" #&CDS_SEC = "1";
"A":   PN = "1"  !CDS_PN = "1";
"B":   PN = "2"  !CDS_PN = "2";
BODY = "Q_CAP","I114": #LOCATION = "C2176" !CDS_LOCATION = "C2176" &SEC = "1" #&CDS_SEC = "1";
"A":   PN = "1"  !CDS_PN = "1";
"B":   PN = "2"  !CDS_PN = "2";
BODY = "Q_RES","I115": #LOCATION = "R3863" !CDS_LOCATION = "R3863" &SEC = "1" #&CDS_SEC = "1";
"A":   PN = "1"  !CDS_PN = "1";
"B":   PN = "2"  !CDS_PN = "2";
BODY = "Q_CAP","I119": #LOCATION = "C1347" !CDS_LOCATION = "C1347" &SEC = "1" #&CDS_SEC = "1";
"A":   PN = "1"  !CDS_PN = "1";
"B":   PN = "2"  !CDS_PN = "2";
BODY = "Q_CAP","I121": #LOCATION = "C1767" !CDS_LOCATION = "C1767" &SEC = "1" #&CDS_SEC = "1";
"A":   PN = "1"  !CDS_PN = "1";
"B":   PN = "2"  !CDS_PN = "2";
BODY = "Q_RES","I130": #LOCATION = "R3690" !CDS_LOCATION = "R3690" &SEC = "1" #&CDS_SEC = "1";
"A":   PN = "1"  !CDS_PN = "1";
"B":   PN = "2"  !CDS_PN = "2";
BODY = "Q_RES","I131": #LOCATION = "R3689" !CDS_LOCATION = "R3689" &SEC = "1" #&CDS_SEC = "1";
"A":   PN = "1"  !CDS_PN = "1";
"B":   PN = "2"  !CDS_PN = "2";
BODY = "ADC128D818CIMTXNOPB","I142": #LOCATION = "U269" !CDS_LOCATION = "U269" &SEC = "1" #&CDS_SEC = "1";
"A0":   PN = "7"  !CDS_PN = "7";
"A1":   PN = "8"  !CDS_PN = "8";
"GND":   PN = "4"  !CDS_PN = "4";
"IN0":   PN = "16"  !CDS_PN = "16";
"IN1":   PN = "15"  !CDS_PN = "15";
"IN2":   PN = "14"  !CDS_PN = "14";
"IN3":   PN = "13"  !CDS_PN = "13";
"IN4":   PN = "12"  !CDS_PN = "12";
"IN5":   PN = "11"  !CDS_PN = "11";
"IN6":   PN = "10"  !CDS_PN = "10";
"IN7":   PN = "9"  !CDS_PN = "9";
"INT#":   PN = "6"  !CDS_PN = "6";
"SCL":   PN = "3"  !CDS_PN = "3";
"SDA":   PN = "2"  !CDS_PN = "2";
"V+":   PN = "5"  !CDS_PN = "5";
"VREF":   PN = "1"  !CDS_PN = "1";
BODY = "Q_RES","I146": #LOCATION = "R1792" !CDS_LOCATION = "R1792" &SEC = "1" #&CDS_SEC = "1";
"A":   PN = "1"  !CDS_PN = "1";
"B":   PN = "2"  !CDS_PN = "2";
BODY = "Q_RES","I147": #LOCATION = "R1793" !CDS_LOCATION = "R1793" &SEC = "1" #&CDS_SEC = "1";
"A":   PN = "1"  !CDS_PN = "1";
"B":   PN = "2"  !CDS_PN = "2";
BODY = "Q_RES","I149": #LOCATION = "R3671" !CDS_LOCATION = "R3671" &SEC = "1" #&CDS_SEC = "1";
"A":   PN = "1"  !CDS_PN = "1";
"B":   PN = "2"  !CDS_PN = "2";
BODY = "Q_RES","I150": #LOCATION = "R3672" !CDS_LOCATION = "R3672" &SEC = "1" #&CDS_SEC = "1";
"A":   PN = "1"  !CDS_PN = "1";
"B":   PN = "2"  !CDS_PN = "2";
BODY = "Q_RES","I160": #LOCATION = "R2900" !CDS_LOCATION = "R2900" &SEC = "1" #&CDS_SEC = "1";
"A":   PN = "1"  !CDS_PN = "1";
"B":   PN = "2"  !CDS_PN = "2";
BODY = "Q_CAP","I162": #LOCATION = "C1757" !CDS_LOCATION = "C1757" &SEC = "1" #&CDS_SEC = "1";
"A":   PN = "1"  !CDS_PN = "1";
"B":   PN = "2"  !CDS_PN = "2";
BODY = "Q_CAP","I166": #LOCATION = "C1768" !CDS_LOCATION = "C1768" &SEC = "1" #&CDS_SEC = "1";
"A":   PN = "1"  !CDS_PN = "1";
"B":   PN = "2"  !CDS_PN = "2";
BODY = "Q_INDUCTOR","I167": #LOCATION = "L15" !CDS_LOCATION = "L15" &SEC = "1" #&CDS_SEC = "1";
"1":   PN = "1"  !CDS_PN = "1";
"2":   PN = "2"  !CDS_PN = "2";
BODY = "MAX11617EEET","I169": #LOCATION = "U193" !CDS_LOCATION = "U193" #SEC = "1" !CDS_SEC = "1";
"AIN0":   PN = "5"  !CDS_PN = "5";
"AIN1":   PN = "6"  !CDS_PN = "6";
"AIN2":   PN = "7"  !CDS_PN = "7";
"AIN3":   PN = "8"  !CDS_PN = "8";
"AIN4":   PN = "9"  !CDS_PN = "9";
"AIN5":   PN = "10"  !CDS_PN = "10";
"AIN6":   PN = "11"  !CDS_PN = "11";
"AIN7":   PN = "12"  !CDS_PN = "12";
"AIN8":   PN = "4"  !CDS_PN = "4";
"AIN9":   PN = "3"  !CDS_PN = "3";
"AIN10":   PN = "2"  !CDS_PN = "2";
"AIN11||REF":   PN = "1"  !CDS_PN = "1";
"GND":   PN = "15"  !CDS_PN = "15";
"SCL":   PN = "13"  !CDS_PN = "13";
"SDA":   PN = "14"  !CDS_PN = "14";
"VDD":   PN = "16"  !CDS_PN = "16";
BODY = "Q_RES","I170": #LOCATION = "R1800" !CDS_LOCATION = "R1800" #SEC = "1" !CDS_SEC = "1";
"A":   PN = "1"  !CDS_PN = "1";
"B":   PN = "2"  !CDS_PN = "2";
DRAWING = "@t6g_mb_lib.t6g(sch_1):page212";
BODY = "HOLE","I4": #LOCATION = "H53" !CDS_LOCATION = "H53" &SEC = "1" #&CDS_SEC = "1";
"1":   PN = "1"  !CDS_PN = "1";
BODY = "HOLE","I5": #LOCATION = "H21" !CDS_LOCATION = "H21" &SEC = "1" #&CDS_SEC = "1";
"1":   PN = "1"  !CDS_PN = "1";
BODY = "HOLE","I7": #LOCATION = "H8027" !CDS_LOCATION = "H8027" &SEC = "1" #&CDS_SEC = "1";
"1":   PN = "1"  !CDS_PN = "1";
BODY = "HOLE","I10": #LOCATION = "H76" !CDS_LOCATION = "H76" &SEC = "1" #&CDS_SEC = "1";
"1":   PN = "1"  !CDS_PN = "1";
BODY = "HOLE","I12": #LOCATION = "H77" !CDS_LOCATION = "H77" &SEC = "1" #&CDS_SEC = "1";
"1":   PN = "1"  !CDS_PN = "1";
BODY = "GND_HOLE","I25": #LOCATION = "H113" !CDS_LOCATION = "H113" &SEC = "1" #&CDS_SEC = "1";
"GND2":   PN = "2"  !CDS_PN = "2";
"GND3":   PN = "3"  !CDS_PN = "3";
"GND4":   PN = "4"  !CDS_PN = "4";
"GND5":   PN = "5"  !CDS_PN = "5";
"GND6":   PN = "6"  !CDS_PN = "6";
"GND7":   PN = "7"  !CDS_PN = "7";
"GND8":   PN = "8"  !CDS_PN = "8";
"GND9":   PN = "9"  !CDS_PN = "9";
BODY = "HOLE","I26": #LOCATION = "H22" !CDS_LOCATION = "H22" &SEC = "1" #&CDS_SEC = "1";
"1":   PN = "1"  !CDS_PN = "1";
BODY = "HOLE","I27": #LOCATION = "H8028" !CDS_LOCATION = "H8028" &SEC = "1" #&CDS_SEC = "1";
"1":   PN = "1"  !CDS_PN = "1";
BODY = "GND_HOLE","I30": #LOCATION = "H114" !CDS_LOCATION = "H114" &SEC = "1" #&CDS_SEC = "1";
"GND2":   PN = "2"  !CDS_PN = "2";
"GND3":   PN = "3"  !CDS_PN = "3";
"GND4":   PN = "4"  !CDS_PN = "4";
"GND5":   PN = "5"  !CDS_PN = "5";
"GND6":   PN = "6"  !CDS_PN = "6";
"GND7":   PN = "7"  !CDS_PN = "7";
"GND8":   PN = "8"  !CDS_PN = "8";
"GND9":   PN = "9"  !CDS_PN = "9";
BODY = "HOLE","I31": #LOCATION = "H34" !CDS_LOCATION = "H34" &SEC = "1" #&CDS_SEC = "1";
"1":   PN = "1"  !CDS_PN = "1";
BODY = "HOLE","I33": #LOCATION = "H38" !CDS_LOCATION = "H38" &SEC = "1" #&CDS_SEC = "1";
"1":   PN = "1"  !CDS_PN = "1";
BODY = "HOLE","I36": #LOCATION = "H33" !CDS_LOCATION = "H33" &SEC = "1" #&CDS_SEC = "1";
"1":   PN = "1"  !CDS_PN = "1";
BODY = "HOLE","I38": #LOCATION = "H37" !CDS_LOCATION = "H37" &SEC = "1" #&CDS_SEC = "1";
"1":   PN = "1"  !CDS_PN = "1";
BODY = "HOLE","I40": #LOCATION = "H43" !CDS_LOCATION = "H43" &SEC = "1" #&CDS_SEC = "1";
"1":   PN = "1"  !CDS_PN = "1";
BODY = "HOLE","I41": #LOCATION = "H27" !CDS_LOCATION = "H27" &SEC = "1" #&CDS_SEC = "1";
"1":   PN = "1"  !CDS_PN = "1";
BODY = "GND_HOLE","I43": #LOCATION = "H115" !CDS_LOCATION = "H115" &SEC = "1" #&CDS_SEC = "1";
"GND2":   PN = "2"  !CDS_PN = "2";
"GND3":   PN = "3"  !CDS_PN = "3";
"GND4":   PN = "4"  !CDS_PN = "4";
"GND5":   PN = "5"  !CDS_PN = "5";
"GND6":   PN = "6"  !CDS_PN = "6";
"GND7":   PN = "7"  !CDS_PN = "7";
"GND8":   PN = "8"  !CDS_PN = "8";
"GND9":   PN = "9"  !CDS_PN = "9";
BODY = "HOLE","I45": #LOCATION = "H44" !CDS_LOCATION = "H44" &SEC = "1" #&CDS_SEC = "1";
"1":   PN = "1"  !CDS_PN = "1";
BODY = "HOLE","I46": #LOCATION = "H49" !CDS_LOCATION = "H49" &SEC = "1" #&CDS_SEC = "1";
"1":   PN = "1"  !CDS_PN = "1";
BODY = "HOLE","I49": #LOCATION = "H50" !CDS_LOCATION = "H50" &SEC = "1" #&CDS_SEC = "1";
"1":   PN = "1"  !CDS_PN = "1";
BODY = "HOLE","I50": #LOCATION = "H28" !CDS_LOCATION = "H28" &SEC = "1" #&CDS_SEC = "1";
"1":   PN = "1"  !CDS_PN = "1";
BODY = "HOLE","I51": #LOCATION = "H29" !CDS_LOCATION = "H29" &SEC = "1" #&CDS_SEC = "1";
"1":   PN = "1"  !CDS_PN = "1";
BODY = "HOLE","I52": #LOCATION = "H54" !CDS_LOCATION = "H54" &SEC = "1" #&CDS_SEC = "1";
"1":   PN = "1"  !CDS_PN = "1";
BODY = "HOLE","I55": #LOCATION = "H13" !CDS_LOCATION = "H13" &SEC = "1" #&CDS_SEC = "1";
"1":   PN = "1"  !CDS_PN = "1";
BODY = "HOLE","I56": #LOCATION = "H30" !CDS_LOCATION = "H30" &SEC = "1" #&CDS_SEC = "1";
"1":   PN = "1"  !CDS_PN = "1";
BODY = "HOLE","I84": #LOCATION = "H124" !CDS_LOCATION = "H124" &SEC = "1" #&CDS_SEC = "1";
"1":   PN = "1"  !CDS_PN = "1";
BODY = "HOLE","I85": #LOCATION = "H125" !CDS_LOCATION = "H125" &SEC = "1" #&CDS_SEC = "1";
"1":   PN = "1"  !CDS_PN = "1";
BODY = "HOLE","I87": #LOCATION = "H11" !CDS_LOCATION = "H11" &SEC = "1" #&CDS_SEC = "1";
"1":   PN = "1"  !CDS_PN = "1";
BODY = "HOLE","I88": #LOCATION = "H74" !CDS_LOCATION = "H74" &SEC = "1" #&CDS_SEC = "1";
"1":   PN = "1"  !CDS_PN = "1";
BODY = "HOLE","I89": #LOCATION = "H75" !CDS_LOCATION = "H75" &SEC = "1" #&CDS_SEC = "1";
"1":   PN = "1"  !CDS_PN = "1";
BODY = "HOLE","I91": #LOCATION = "H31" !CDS_LOCATION = "H31" &SEC = "1" #&CDS_SEC = "1";
"1":   PN = "1"  !CDS_PN = "1";
BODY = "HOLE","I93": #LOCATION = "H32" !CDS_LOCATION = "H32" &SEC = "1" #&CDS_SEC = "1";
"1":   PN = "1"  !CDS_PN = "1";
BODY = "HOLE","I94": #LOCATION = "H127" !CDS_LOCATION = "H127" &SEC = "1" #&CDS_SEC = "1";
"1":   PN = "1"  !CDS_PN = "1";
BODY = "CONN1_10165288101LF","I101": #LOCATION = "J122" !CDS_LOCATION = "J122" &SEC = "1" #&CDS_SEC = "1";
"NC1":   PN = "SCR_H1"  !CDS_PN = "SCR_H1";
BODY = "CONN1_10165288101LF","I106": #LOCATION = "J123" !CDS_LOCATION = "J123" &SEC = "1" #&CDS_SEC = "1";
"NC1":   PN = "SCR_H1"  !CDS_PN = "SCR_H1";
BODY = "HOLE","I111": #LOCATION = "H126" !CDS_LOCATION = "H126" &SEC = "1" #&CDS_SEC = "1";
"1":   PN = "1"  !CDS_PN = "1";
BODY = "HOLE","I113": #LOCATION = "H6000" !CDS_LOCATION = "H6000" &SEC = "1" #&CDS_SEC = "1";
"1":   PN = "1"  !CDS_PN = "1";
BODY = "HOLE","I116": #LOCATION = "H6001" !CDS_LOCATION = "H6001" &SEC = "1" #&CDS_SEC = "1";
"1":   PN = "1"  !CDS_PN = "1";
BODY = "GND_HOLE","I120": #LOCATION = "H111" !CDS_LOCATION = "H111" #SEC = "1" !CDS_SEC = "1";
"GND2":   PN = "2"  !CDS_PN = "2";
"GND3":   PN = "3"  !CDS_PN = "3";
"GND4":   PN = "4"  !CDS_PN = "4";
"GND5":   PN = "5"  !CDS_PN = "5";
"GND6":   PN = "6"  !CDS_PN = "6";
"GND7":   PN = "7"  !CDS_PN = "7";
"GND8":   PN = "8"  !CDS_PN = "8";
"GND9":   PN = "9"  !CDS_PN = "9";
BODY = "GND_HOLE","I123": #LOCATION = "H112" !CDS_LOCATION = "H112" #SEC = "1" !CDS_SEC = "1";
"GND2":   PN = "2"  !CDS_PN = "2";
"GND3":   PN = "3"  !CDS_PN = "3";
"GND4":   PN = "4"  !CDS_PN = "4";
"GND5":   PN = "5"  !CDS_PN = "5";
"GND6":   PN = "6"  !CDS_PN = "6";
"GND7":   PN = "7"  !CDS_PN = "7";
"GND8":   PN = "8"  !CDS_PN = "8";
"GND9":   PN = "9"  !CDS_PN = "9";
BODY = "HOLE","I125": #LOCATION = "H86" !CDS_LOCATION = "H86" &SEC = "1" #&CDS_SEC = "1";
"1":   PN = "1"  !CDS_PN = "1";
BODY = "HOLE","I127": #LOCATION = "H87" !CDS_LOCATION = "H87" &SEC = "1" #&CDS_SEC = "1";
"1":   PN = "1"  !CDS_PN = "1";
BODY = "HOLE","I129": #LOCATION = "H88" !CDS_LOCATION = "H88" &SEC = "1" #&CDS_SEC = "1";
"1":   PN = "1"  !CDS_PN = "1";
BODY = "HOLE","I132": #LOCATION = "H89" !CDS_LOCATION = "H89" &SEC = "1" #&CDS_SEC = "1";
"1":   PN = "1"  !CDS_PN = "1";
BODY = "HOLE","I133": #LOCATION = "H91" !CDS_LOCATION = "H91" &SEC = "1" #&CDS_SEC = "1";
"1":   PN = "1"  !CDS_PN = "1";
BODY = "HOLE","I135": #LOCATION = "H92" !CDS_LOCATION = "H92" &SEC = "1" #&CDS_SEC = "1";
"1":   PN = "1"  !CDS_PN = "1";
BODY = "HOLE","I138": #LOCATION = "H93" !CDS_LOCATION = "H93" &SEC = "1" #&CDS_SEC = "1";
"1":   PN = "1"  !CDS_PN = "1";
BODY = "HOLE","I140": #LOCATION = "H94" !CDS_LOCATION = "H94" &SEC = "1" #&CDS_SEC = "1";
"1":   PN = "1"  !CDS_PN = "1";
BODY = "HOLE","I141": #LOCATION = "H95" !CDS_LOCATION = "H95" &SEC = "1" #&CDS_SEC = "1";
"1":   PN = "1"  !CDS_PN = "1";
BODY = "HOLE","I142": #LOCATION = "H96" !CDS_LOCATION = "H96" &SEC = "1" #&CDS_SEC = "1";
"1":   PN = "1"  !CDS_PN = "1";
BODY = "HOLE","I145": #LOCATION = "H97" !CDS_LOCATION = "H97" &SEC = "1" #&CDS_SEC = "1";
"1":   PN = "1"  !CDS_PN = "1";
BODY = "HOLE","I147": #LOCATION = "H98" !CDS_LOCATION = "H98" &SEC = "1" #&CDS_SEC = "1";
"1":   PN = "1"  !CDS_PN = "1";
BODY = "HOLE","I149": #LOCATION = "H99" !CDS_LOCATION = "H99" &SEC = "1" #&CDS_SEC = "1";
"1":   PN = "1"  !CDS_PN = "1";
BODY = "HOLE","I152": #LOCATION = "H100" !CDS_LOCATION = "H100" &SEC = "1" #&CDS_SEC = "1";
"1":   PN = "1"  !CDS_PN = "1";
BODY = "HOLE","I153": #LOCATION = "H101" !CDS_LOCATION = "H101" &SEC = "1" #&CDS_SEC = "1";
"1":   PN = "1"  !CDS_PN = "1";
BODY = "HOLE","I156": #LOCATION = "H102" !CDS_LOCATION = "H102" &SEC = "1" #&CDS_SEC = "1";
"1":   PN = "1"  !CDS_PN = "1";
BODY = "HOLE","I157": #LOCATION = "H103" !CDS_LOCATION = "H103" &SEC = "1" #&CDS_SEC = "1";
"1":   PN = "1"  !CDS_PN = "1";
BODY = "HOLE","I159": #LOCATION = "H104" !CDS_LOCATION = "H104" &SEC = "1" #&CDS_SEC = "1";
"1":   PN = "1"  !CDS_PN = "1";
BODY = "HOLE","I161": #LOCATION = "H105" !CDS_LOCATION = "H105" &SEC = "1" #&CDS_SEC = "1";
"1":   PN = "1"  !CDS_PN = "1";
BODY = "HOLE","I163": #LOCATION = "H106" !CDS_LOCATION = "H106" &SEC = "1" #&CDS_SEC = "1";
"1":   PN = "1"  !CDS_PN = "1";
BODY = "HOLE","I166": #LOCATION = "H128" !CDS_LOCATION = "H128" &SEC = "1" #&CDS_SEC = "1";
"1":   PN = "1"  !CDS_PN = "1";
BODY = "HOLE","I167": #LOCATION = "H90" !CDS_LOCATION = "H90" &SEC = "1" #&CDS_SEC = "1";
"1":   PN = "1"  !CDS_PN = "1";
BODY = "HOLE","I168": #LOCATION = "H6002" !CDS_LOCATION = "H6002" &SEC = "1" #&CDS_SEC = "1";
"1":   PN = "1"  !CDS_PN = "1";
BODY = "HOLE","I170": #LOCATION = "H2" !CDS_LOCATION = "H2" &SEC = "1" #&CDS_SEC = "1";
"1":   PN = "1"  !CDS_PN = "1";
BODY = "HOLE","I176": #LOCATION = "H8" !CDS_LOCATION = "H8" &SEC = "1" #&CDS_SEC = "1";
"1":   PN = "1"  !CDS_PN = "1";
BODY = "HOLE","I178": #LOCATION = "H10" !CDS_LOCATION = "H10" &SEC = "1" #&CDS_SEC = "1";
"1":   PN = "1"  !CDS_PN = "1";
BODY = "HOLE","I187": #LOCATION = "H12" !CDS_LOCATION = "H12" &SEC = "1" #&CDS_SEC = "1";
"1":   PN = "1"  !CDS_PN = "1";
BODY = "HOLE","I193": #LOCATION = "H5" !CDS_LOCATION = "H5" &SEC = "1" #&CDS_SEC = "1";
"1":   PN = "1"  !CDS_PN = "1";
BODY = "HOLE","I195": #LOCATION = "H3" !CDS_LOCATION = "H3" &SEC = "1" #&CDS_SEC = "1";
"1":   PN = "1"  !CDS_PN = "1";
DRAWING = "@t6g_mb_lib.t6g(sch_1):page374";
BODY = "MOSFET_NCH_DUAL","I3": #LOCATION = "Q80" !CDS_LOCATION = "Q80" #SEC = "2" !CDS_SEC = "2";
"D2":   PN = "3"  !CDS_PN = "3";
"G2":   PN = "5"  !CDS_PN = "5";
"S2":   PN = "4"  !CDS_PN = "4";
BODY = "MOSFET_NCH_DUAL","I6": #LOCATION = "Q80" !CDS_LOCATION = "Q80" &SEC = "1" #&CDS_SEC = "1";
"D1":   PN = "6"  !CDS_PN = "6";
"G1":   PN = "2"  !CDS_PN = "2";
"S1":   PN = "1"  !CDS_PN = "1";
BODY = "MOSFET_NCH_DUAL","I8": #LOCATION = "Q79" !CDS_LOCATION = "Q79" #SEC = "2" !CDS_SEC = "2";
"D2":   PN = "3"  !CDS_PN = "3";
"G2":   PN = "5"  !CDS_PN = "5";
"S2":   PN = "4"  !CDS_PN = "4";
BODY = "Q_LED","I11": #LOCATION = "D76" !CDS_LOCATION = "D76" &SEC = "1" #&CDS_SEC = "1";
"A":   PN = "A"  !CDS_PN = "A";
"C":   PN = "C"  !CDS_PN = "C";
BODY = "Q_RES","I12": #LOCATION = "R3088" !CDS_LOCATION = "R3088" &SEC = "1" #&CDS_SEC = "1";
"A":   PN = "1"  !CDS_PN = "1";
"B":   PN = "2"  !CDS_PN = "2";
BODY = "Q_LED","I13": #LOCATION = "D75" !CDS_LOCATION = "D75" &SEC = "1" #&CDS_SEC = "1";
"A":   PN = "A"  !CDS_PN = "A";
"C":   PN = "C"  !CDS_PN = "C";
BODY = "Q_LED","I14": #LOCATION = "D74" !CDS_LOCATION = "D74" &SEC = "1" #&CDS_SEC = "1";
"A":   PN = "A"  !CDS_PN = "A";
"C":   PN = "C"  !CDS_PN = "C";
BODY = "Q_RES","I15": #LOCATION = "R3089" !CDS_LOCATION = "R3089" &SEC = "1" #&CDS_SEC = "1";
"A":   PN = "1"  !CDS_PN = "1";
"B":   PN = "2"  !CDS_PN = "2";
BODY = "Q_RES","I16": #LOCATION = "R3087" !CDS_LOCATION = "R3087" &SEC = "1" #&CDS_SEC = "1";
"A":   PN = "1"  !CDS_PN = "1";
"B":   PN = "2"  !CDS_PN = "2";
BODY = "MOSFET_NCH_DUAL","I18": #LOCATION = "Q79" !CDS_LOCATION = "Q79" &SEC = "1" #&CDS_SEC = "1";
"D1":   PN = "6"  !CDS_PN = "6";
"G1":   PN = "2"  !CDS_PN = "2";
"S1":   PN = "1"  !CDS_PN = "1";
BODY = "Q_LED","I19": #LOCATION = "D73" !CDS_LOCATION = "D73" &SEC = "1" #&CDS_SEC = "1";
"A":   PN = "A"  !CDS_PN = "A";
"C":   PN = "C"  !CDS_PN = "C";
BODY = "Q_RES","I20": #LOCATION = "R3086" !CDS_LOCATION = "R3086" &SEC = "1" #&CDS_SEC = "1";
"A":   PN = "1"  !CDS_PN = "1";
"B":   PN = "2"  !CDS_PN = "2";
BODY = "MOSFET_NCH_DUAL","I23": #LOCATION = "Q83" !CDS_LOCATION = "Q83" &SEC = "1" #&CDS_SEC = "1";
"D1":   PN = "6"  !CDS_PN = "6";
"G1":   PN = "2"  !CDS_PN = "2";
"S1":   PN = "1"  !CDS_PN = "1";
BODY = "MOSFET_NCH_DUAL","I27": #LOCATION = "Q81" !CDS_LOCATION = "Q81" #SEC = "2" !CDS_SEC = "2";
"D2":   PN = "3"  !CDS_PN = "3";
"G2":   PN = "5"  !CDS_PN = "5";
"S2":   PN = "4"  !CDS_PN = "4";
BODY = "Q_LED","I30": #LOCATION = "D79" !CDS_LOCATION = "D79" &SEC = "1" #&CDS_SEC = "1";
"A":   PN = "A"  !CDS_PN = "A";
"C":   PN = "C"  !CDS_PN = "C";
BODY = "Q_LED","I32": #LOCATION = "D78" !CDS_LOCATION = "D78" &SEC = "1" #&CDS_SEC = "1";
"A":   PN = "A"  !CDS_PN = "A";
"C":   PN = "C"  !CDS_PN = "C";
BODY = "MOSFET_NCH_DUAL","I35": #LOCATION = "Q81" !CDS_LOCATION = "Q81" &SEC = "1" #&CDS_SEC = "1";
"D1":   PN = "6"  !CDS_PN = "6";
"G1":   PN = "2"  !CDS_PN = "2";
"S1":   PN = "1"  !CDS_PN = "1";
BODY = "Q_LED","I36": #LOCATION = "D77" !CDS_LOCATION = "D77" &SEC = "1" #&CDS_SEC = "1";
"A":   PN = "A"  !CDS_PN = "A";
"C":   PN = "C"  !CDS_PN = "C";
BODY = "Q_RES","I37": #LOCATION = "R3091" !CDS_LOCATION = "R3091" &SEC = "1" #&CDS_SEC = "1";
"A":   PN = "1"  !CDS_PN = "1";
"B":   PN = "2"  !CDS_PN = "2";
BODY = "Q_RES","I38": #LOCATION = "R3090" !CDS_LOCATION = "R3090" &SEC = "1" #&CDS_SEC = "1";
"A":   PN = "1"  !CDS_PN = "1";
"B":   PN = "2"  !CDS_PN = "2";
BODY = "Q_RES","I41": #LOCATION = "R3092" !CDS_LOCATION = "R3092" &SEC = "1" #&CDS_SEC = "1";
"A":   PN = "1"  !CDS_PN = "1";
"B":   PN = "2"  !CDS_PN = "2";
BODY = "MOSFET_NCH_DUAL","I43": #LOCATION = "Q83" !CDS_LOCATION = "Q83" &SEC = "2" #&CDS_SEC = "2";
"D2":   PN = "3"  !CDS_PN = "3";
"G2":   PN = "5"  !CDS_PN = "5";
"S2":   PN = "4"  !CDS_PN = "4";
DRAWING = "@t6g_mb_lib.t6g(sch_1):page375";
BODY = "MOSFET_NCH_DUAL","I2": #LOCATION = "Q85" !CDS_LOCATION = "Q85" #SEC = "2" !CDS_SEC = "2";
"D2":   PN = "3"  !CDS_PN = "3";
"G2":   PN = "5"  !CDS_PN = "5";
"S2":   PN = "4"  !CDS_PN = "4";
BODY = "MOSFET_NCH_DUAL","I7": #LOCATION = "Q85" !CDS_LOCATION = "Q85" &SEC = "1" #&CDS_SEC = "1";
"D1":   PN = "6"  !CDS_PN = "6";
"G1":   PN = "2"  !CDS_PN = "2";
"S1":   PN = "1"  !CDS_PN = "1";
BODY = "MOSFET_NCH_DUAL","I10": #LOCATION = "Q84" !CDS_LOCATION = "Q84" #SEC = "2" !CDS_SEC = "2";
"D2":   PN = "3"  !CDS_PN = "3";
"G2":   PN = "5"  !CDS_PN = "5";
"S2":   PN = "4"  !CDS_PN = "4";
BODY = "MOSFET_NCH_DUAL","I11": #LOCATION = "Q84" !CDS_LOCATION = "Q84" &SEC = "1" #&CDS_SEC = "1";
"D1":   PN = "6"  !CDS_PN = "6";
"G1":   PN = "2"  !CDS_PN = "2";
"S1":   PN = "1"  !CDS_PN = "1";
BODY = "Q_LED","I13": #LOCATION = "D83" !CDS_LOCATION = "D83" &SEC = "1" #&CDS_SEC = "1";
"A":   PN = "A"  !CDS_PN = "A";
"C":   PN = "C"  !CDS_PN = "C";
BODY = "Q_LED","I14": #LOCATION = "D82" !CDS_LOCATION = "D82" &SEC = "1" #&CDS_SEC = "1";
"A":   PN = "A"  !CDS_PN = "A";
"C":   PN = "C"  !CDS_PN = "C";
BODY = "Q_RES","I15": #LOCATION = "R3095" !CDS_LOCATION = "R3095" &SEC = "1" #&CDS_SEC = "1";
"A":   PN = "1"  !CDS_PN = "1";
"B":   PN = "2"  !CDS_PN = "2";
BODY = "Q_RES","I16": #LOCATION = "R3096" !CDS_LOCATION = "R3096" &SEC = "1" #&CDS_SEC = "1";
"A":   PN = "1"  !CDS_PN = "1";
"B":   PN = "2"  !CDS_PN = "2";
BODY = "Q_LED","I17": #LOCATION = "D81" !CDS_LOCATION = "D81" &SEC = "1" #&CDS_SEC = "1";
"A":   PN = "A"  !CDS_PN = "A";
"C":   PN = "C"  !CDS_PN = "C";
BODY = "Q_RES","I18": #LOCATION = "R3094" !CDS_LOCATION = "R3094" &SEC = "1" #&CDS_SEC = "1";
"A":   PN = "1"  !CDS_PN = "1";
"B":   PN = "2"  !CDS_PN = "2";
BODY = "Q_LED","I19": #LOCATION = "D80" !CDS_LOCATION = "D80" &SEC = "1" #&CDS_SEC = "1";
"A":   PN = "A"  !CDS_PN = "A";
"C":   PN = "C"  !CDS_PN = "C";
BODY = "Q_RES","I20": #LOCATION = "R3093" !CDS_LOCATION = "R3093" &SEC = "1" #&CDS_SEC = "1";
"A":   PN = "1"  !CDS_PN = "1";
"B":   PN = "2"  !CDS_PN = "2";
BODY = "MOSFET_NCH_DUAL","I29": #LOCATION = "Q86" !CDS_LOCATION = "Q86" #SEC = "2" !CDS_SEC = "2";
"D2":   PN = "3"  !CDS_PN = "3";
"G2":   PN = "5"  !CDS_PN = "5";
"S2":   PN = "4"  !CDS_PN = "4";
BODY = "MOSFET_NCH_DUAL","I30": #LOCATION = "Q86" !CDS_LOCATION = "Q86" &SEC = "1" #&CDS_SEC = "1";
"D1":   PN = "6"  !CDS_PN = "6";
"G1":   PN = "2"  !CDS_PN = "2";
"S1":   PN = "1"  !CDS_PN = "1";
BODY = "Q_LED","I33": #LOCATION = "D85" !CDS_LOCATION = "D85" &SEC = "1" #&CDS_SEC = "1";
"A":   PN = "A"  !CDS_PN = "A";
"C":   PN = "C"  !CDS_PN = "C";
BODY = "Q_LED","I35": #LOCATION = "D84" !CDS_LOCATION = "D84" &SEC = "1" #&CDS_SEC = "1";
"A":   PN = "A"  !CDS_PN = "A";
"C":   PN = "C"  !CDS_PN = "C";
BODY = "Q_RES","I38": #LOCATION = "R3097" !CDS_LOCATION = "R3097" &SEC = "1" #&CDS_SEC = "1";
"A":   PN = "1"  !CDS_PN = "1";
"B":   PN = "2"  !CDS_PN = "2";
BODY = "Q_RES","I40": #LOCATION = "R3099" !CDS_LOCATION = "R3099" &SEC = "1" #&CDS_SEC = "1";
"A":   PN = "1"  !CDS_PN = "1";
"B":   PN = "2"  !CDS_PN = "2";
BODY = "Q_LED","I42": #LOCATION = "D8000" !CDS_LOCATION = "D8000" #SEC = "1" !CDS_SEC = "1";
"A":   PN = "A"  !CDS_PN = "A";
"C":   PN = "C"  !CDS_PN = "C";
BODY = "Q_RES","I44": #LOCATION = "R8022" !CDS_LOCATION = "R8022" #SEC = "1" !CDS_SEC = "1";
"A":   PN = "1"  !CDS_PN = "1";
"B":   PN = "2"  !CDS_PN = "2";
BODY = "Q_RES","I45": #LOCATION = "R8023" !CDS_LOCATION = "R8023" #SEC = "1" !CDS_SEC = "1";
"A":   PN = "1"  !CDS_PN = "1";
"B":   PN = "2"  !CDS_PN = "2";
BODY = "Q_RES","I46": #LOCATION = "R8024" !CDS_LOCATION = "R8024" #SEC = "1" !CDS_SEC = "1";
"A":   PN = "1"  !CDS_PN = "1";
"B":   PN = "2"  !CDS_PN = "2";
BODY = "Q_RES","I49": #LOCATION = "R8027" !CDS_LOCATION = "R8027" #SEC = "1" !CDS_SEC = "1";
"A":   PN = "1"  !CDS_PN = "1";
"B":   PN = "2"  !CDS_PN = "2";
BODY = "Q_RES","I50": #LOCATION = "R8026" !CDS_LOCATION = "R8026" #SEC = "1" !CDS_SEC = "1";
"A":   PN = "1"  !CDS_PN = "1";
"B":   PN = "2"  !CDS_PN = "2";
BODY = "Q_RES","I51": #LOCATION = "R8025" !CDS_LOCATION = "R8025" #SEC = "1" !CDS_SEC = "1";
"A":   PN = "1"  !CDS_PN = "1";
"B":   PN = "2"  !CDS_PN = "2";
BODY = "Q_LED","I52": #LOCATION = "D8001" !CDS_LOCATION = "D8001" #SEC = "1" !CDS_SEC = "1";
"A":   PN = "A"  !CDS_PN = "A";
"C":   PN = "C"  !CDS_PN = "C";
BODY = "Q_RES","I55": #LOCATION = "R8029" !CDS_LOCATION = "R8029" #SEC = "1" !CDS_SEC = "1";
"A":   PN = "1"  !CDS_PN = "1";
"B":   PN = "2"  !CDS_PN = "2";
BODY = "Q_LED","I56": #LOCATION = "D8002" !CDS_LOCATION = "D8002" #SEC = "1" !CDS_SEC = "1";
"A":   PN = "A"  !CDS_PN = "A";
"C":   PN = "C"  !CDS_PN = "C";
BODY = "MOSFET_NCH_DUAL","I57": #LOCATION = "Q8001" !CDS_LOCATION = "Q8001" #SEC = "1" !CDS_SEC = "1";
"D1":   PN = "6"  !CDS_PN = "6";
"G1":   PN = "2"  !CDS_PN = "2";
"S1":   PN = "1"  !CDS_PN = "1";
BODY = "MOSFET_NCH_DUAL","I58": #LOCATION = "Q8001" !CDS_LOCATION = "Q8001" #SEC = "2" !CDS_SEC = "2";
"D2":   PN = "3"  !CDS_PN = "3";
"G2":   PN = "5"  !CDS_PN = "5";
"S2":   PN = "4"  !CDS_PN = "4";
BODY = "Q_RES","I62": #LOCATION = "R8028" !CDS_LOCATION = "R8028" &SEC = "1" #&CDS_SEC = "1";
"A":   PN = "1"  !CDS_PN = "1";
"B":   PN = "2"  !CDS_PN = "2";
DRAWING = "@t6g_mb_lib.t6g(sch_1):page111";
BODY = "DS125BR111RTWR","I1": #LOCATION = "U6000" !CDS_LOCATION = "U6000" #SEC = "1" !CDS_SEC = "1";
"ENSMB":   PN = "3"  !CDS_PN = "3";
"EQA0||AD0":   PN = "10"  !CDS_PN = "10";
"EQA1||AD1":   PN = "9"  !CDS_PN = "9";
"EQB0||AD3":   PN = "1"  !CDS_PN = "1";
"EQB1||AD2":   PN = "2"  !CDS_PN = "2";
"INA+":   PN = "24"  !CDS_PN = "24";
"INA-":   PN = "23"  !CDS_PN = "23";
"INB+":   PN = "11"  !CDS_PN = "11";
"INB-":   PN = "12"  !CDS_PN = "12";
"OUTA+":   PN = "7"  !CDS_PN = "7";
"OUTA-":   PN = "8"  !CDS_PN = "8";
"OUTB+":   PN = "20"  !CDS_PN = "20";
"OUTB-":   PN = "19"  !CDS_PN = "19";
"PWDN":   PN = "6"  !CDS_PN = "6";
"RES":   PN = "13"  !CDS_PN = "13";
"RXDET||DONE#":   PN = "18"  !CDS_PN = "18";
"SCL||VODB_DB":   PN = "5"  !CDS_PN = "5";
"SD_TH":   PN = "14"  !CDS_PN = "14";
"SDA||VODA_DB":   PN = "4"  !CDS_PN = "4";
"TH_GND":   PN = "25"  !CDS_PN = "25";
"VDD_21":   PN = "21"  !CDS_PN = "21";
"VDD_22":   PN = "22"  !CDS_PN = "22";
"VDD_SEL":   PN = "16"  !CDS_PN = "16";
"VIN":   PN = "15"  !CDS_PN = "15";
"VOD_SEL||READEN#":   PN = "17"  !CDS_PN = "17";
BODY = "Q_CAP","I3": #LOCATION = "C6009" !CDS_LOCATION = "C6009" &SEC = "1" #&CDS_SEC = "1";
"A":   PN = "1"  !CDS_PN = "1";
"B":   PN = "2"  !CDS_PN = "2";
BODY = "Q_CAP","I5": #LOCATION = "C6010" !CDS_LOCATION = "C6010" &SEC = "1" #&CDS_SEC = "1";
"A":   PN = "1"  !CDS_PN = "1";
"B":   PN = "2"  !CDS_PN = "2";
BODY = "Q_CAP","I6": #LOCATION = "C6011" !CDS_LOCATION = "C6011" &SEC = "1" #&CDS_SEC = "1";
"A":   PN = "1"  !CDS_PN = "1";
"B":   PN = "2"  !CDS_PN = "2";
BODY = "Q_CAP","I7": #LOCATION = "C6012" !CDS_LOCATION = "C6012" &SEC = "1" #&CDS_SEC = "1";
"A":   PN = "1"  !CDS_PN = "1";
"B":   PN = "2"  !CDS_PN = "2";
BODY = "Q_RES","I12": #LOCATION = "R6160" !CDS_LOCATION = "R6160" &SEC = "1" #&CDS_SEC = "1";
"A":   PN = "1"  !CDS_PN = "1";
"B":   PN = "2"  !CDS_PN = "2";
BODY = "Q_RES","I23": #LOCATION = "R6162" !CDS_LOCATION = "R6162" &SEC = "1" #&CDS_SEC = "1";
"A":   PN = "1"  !CDS_PN = "1";
"B":   PN = "2"  !CDS_PN = "2";
BODY = "Q_RES","I32": #LOCATION = "R6164" !CDS_LOCATION = "R6164" &SEC = "1" #&CDS_SEC = "1";
"A":   PN = "1"  !CDS_PN = "1";
"B":   PN = "2"  !CDS_PN = "2";
BODY = "Q_RES","I39": #LOCATION = "R6163" !CDS_LOCATION = "R6163" &SEC = "1" #&CDS_SEC = "1";
"A":   PN = "1"  !CDS_PN = "1";
"B":   PN = "2"  !CDS_PN = "2";
BODY = "Q_RES","I40": #LOCATION = "R6166" !CDS_LOCATION = "R6166" &SEC = "1" #&CDS_SEC = "1";
"A":   PN = "1"  !CDS_PN = "1";
"B":   PN = "2"  !CDS_PN = "2";
BODY = "Q_RES","I41": #LOCATION = "R6165" !CDS_LOCATION = "R6165" &SEC = "1" #&CDS_SEC = "1";
"A":   PN = "1"  !CDS_PN = "1";
"B":   PN = "2"  !CDS_PN = "2";
BODY = "Q_RES","I44": #LOCATION = "R6173" !CDS_LOCATION = "R6173" &SEC = "1" #&CDS_SEC = "1";
"A":   PN = "1"  !CDS_PN = "1";
"B":   PN = "2"  !CDS_PN = "2";
BODY = "Q_RES","I45": #LOCATION = "R6174" !CDS_LOCATION = "R6174" &SEC = "1" #&CDS_SEC = "1";
"A":   PN = "1"  !CDS_PN = "1";
"B":   PN = "2"  !CDS_PN = "2";
BODY = "Q_RES","I48": #LOCATION = "R6171" !CDS_LOCATION = "R6171" &SEC = "1" #&CDS_SEC = "1";
"A":   PN = "1"  !CDS_PN = "1";
"B":   PN = "2"  !CDS_PN = "2";
BODY = "Q_RES","I49": #LOCATION = "R6172" !CDS_LOCATION = "R6172" &SEC = "1" #&CDS_SEC = "1";
"A":   PN = "1"  !CDS_PN = "1";
"B":   PN = "2"  !CDS_PN = "2";
BODY = "Q_RES","I53": #LOCATION = "R6169" !CDS_LOCATION = "R6169" &SEC = "1" #&CDS_SEC = "1";
"A":   PN = "1"  !CDS_PN = "1";
"B":   PN = "2"  !CDS_PN = "2";
BODY = "Q_RES","I57": #LOCATION = "R6167" !CDS_LOCATION = "R6167" &SEC = "1" #&CDS_SEC = "1";
"A":   PN = "1"  !CDS_PN = "1";
"B":   PN = "2"  !CDS_PN = "2";
BODY = "Q_RES","I58": #LOCATION = "R6168" !CDS_LOCATION = "R6168" &SEC = "1" #&CDS_SEC = "1";
"A":   PN = "1"  !CDS_PN = "1";
"B":   PN = "2"  !CDS_PN = "2";
BODY = "Q_RES","I60": #LOCATION = "R6170" !CDS_LOCATION = "R6170" &SEC = "1" #&CDS_SEC = "1";
"A":   PN = "1"  !CDS_PN = "1";
"B":   PN = "2"  !CDS_PN = "2";
BODY = "Q_RES","I63": #LOCATION = "R6175" !CDS_LOCATION = "R6175" &SEC = "1" #&CDS_SEC = "1";
"A":   PN = "1"  !CDS_PN = "1";
"B":   PN = "2"  !CDS_PN = "2";
BODY = "Q_RES","I64": #LOCATION = "R6176" !CDS_LOCATION = "R6176" &SEC = "1" #&CDS_SEC = "1";
"A":   PN = "1"  !CDS_PN = "1";
"B":   PN = "2"  !CDS_PN = "2";
BODY = "Q_RES","I68": #LOCATION = "R6178" !CDS_LOCATION = "R6178" &SEC = "1" #&CDS_SEC = "1";
"A":   PN = "1"  !CDS_PN = "1";
"B":   PN = "2"  !CDS_PN = "2";
BODY = "Q_RES","I73": #LOCATION = "R6180" !CDS_LOCATION = "R6180" &SEC = "1" #&CDS_SEC = "1";
"A":   PN = "1"  !CDS_PN = "1";
"B":   PN = "2"  !CDS_PN = "2";
BODY = "Q_RES","I77": #LOCATION = "R6177" !CDS_LOCATION = "R6177" &SEC = "1" #&CDS_SEC = "1";
"A":   PN = "1"  !CDS_PN = "1";
"B":   PN = "2"  !CDS_PN = "2";
BODY = "Q_RES","I78": #LOCATION = "R6179" !CDS_LOCATION = "R6179" &SEC = "1" #&CDS_SEC = "1";
"A":   PN = "1"  !CDS_PN = "1";
"B":   PN = "2"  !CDS_PN = "2";
DRAWING = "@t6g_mb_lib.t6g(sch_1):page112";
BODY = "Q_RES","I1": #LOCATION = "R6154" !CDS_LOCATION = "R6154" &SEC = "1" #&CDS_SEC = "1";
"A":   PN = "1"  !CDS_PN = "1";
"B":   PN = "2"  !CDS_PN = "2";
BODY = "Q_RES","I2": #LOCATION = "R6155" !CDS_LOCATION = "R6155" &SEC = "1" #&CDS_SEC = "1";
"A":   PN = "1"  !CDS_PN = "1";
"B":   PN = "2"  !CDS_PN = "2";
BODY = "Q_RES","I3": #LOCATION = "R6153" !CDS_LOCATION = "R6153" &SEC = "1" #&CDS_SEC = "1";
"A":   PN = "1"  !CDS_PN = "1";
"B":   PN = "2"  !CDS_PN = "2";
BODY = "Q_RES","I8": #LOCATION = "R6152" !CDS_LOCATION = "R6152" &SEC = "1" #&CDS_SEC = "1";
"A":   PN = "1"  !CDS_PN = "1";
"B":   PN = "2"  !CDS_PN = "2";
BODY = "Q_CAP","I11": #LOCATION = "C1868" !CDS_LOCATION = "C1868" &SEC = "1" #&CDS_SEC = "1";
"A":   PN = "1"  !CDS_PN = "1";
"B":   PN = "2"  !CDS_PN = "2";
BODY = "Q_CAP","I12": #LOCATION = "C1869" !CDS_LOCATION = "C1869" &SEC = "1" #&CDS_SEC = "1";
"A":   PN = "1"  !CDS_PN = "1";
"B":   PN = "2"  !CDS_PN = "2";
BODY = "Q_CAP","I13": #LOCATION = "C1870" !CDS_LOCATION = "C1870" &SEC = "1" #&CDS_SEC = "1";
"A":   PN = "1"  !CDS_PN = "1";
"B":   PN = "2"  !CDS_PN = "2";
BODY = "Q_CAP","I14": #LOCATION = "C1871" !CDS_LOCATION = "C1871" &SEC = "1" #&CDS_SEC = "1";
"A":   PN = "1"  !CDS_PN = "1";
"B":   PN = "2"  !CDS_PN = "2";
BODY = "Q_RES","I21": #LOCATION = "R6156" !CDS_LOCATION = "R6156" &SEC = "1" #&CDS_SEC = "1";
"A":   PN = "1"  !CDS_PN = "1";
"B":   PN = "2"  !CDS_PN = "2";
BODY = "Q_RES","I22": #LOCATION = "R6157" !CDS_LOCATION = "R6157" &SEC = "1" #&CDS_SEC = "1";
"A":   PN = "1"  !CDS_PN = "1";
"B":   PN = "2"  !CDS_PN = "2";
BODY = "Q_RES","I23": #LOCATION = "R6159" !CDS_LOCATION = "R6159" &SEC = "1" #&CDS_SEC = "1";
"A":   PN = "1"  !CDS_PN = "1";
"B":   PN = "2"  !CDS_PN = "2";
BODY = "Q_RES","I24": #LOCATION = "R6158" !CDS_LOCATION = "R6158" &SEC = "1" #&CDS_SEC = "1";
"A":   PN = "1"  !CDS_PN = "1";
"B":   PN = "2"  !CDS_PN = "2";
BODY = "Q_CAP","I35": #LOCATION = "C6006" !CDS_LOCATION = "C6006" &SEC = "1" #&CDS_SEC = "1";
"A":   PN = "1"  !CDS_PN = "1";
"B":   PN = "2"  !CDS_PN = "2";
BODY = "Q_CAP","I36": #LOCATION = "C6005" !CDS_LOCATION = "C6005" &SEC = "1" #&CDS_SEC = "1";
"A":   PN = "1"  !CDS_PN = "1";
"B":   PN = "2"  !CDS_PN = "2";
BODY = "Q_CAP","I43": #LOCATION = "C6007" !CDS_LOCATION = "C6007" &SEC = "1" #&CDS_SEC = "1";
"A":   PN = "1"  !CDS_PN = "1";
"B":   PN = "2"  !CDS_PN = "2";
BODY = "Q_CAP","I44": #LOCATION = "C6008" !CDS_LOCATION = "C6008" &SEC = "1" #&CDS_SEC = "1";
"A":   PN = "1"  !CDS_PN = "1";
"B":   PN = "2"  !CDS_PN = "2";
DRAWING = "@t6g_mb_lib.t6g(sch_1):page267";
BODY = "Q_RES","I22": #LOCATION = "R1117" !CDS_LOCATION = "R1117" &SEC = "1" #&CDS_SEC = "1";
"A":   PN = "1"  !CDS_PN = "1";
"B":   PN = "2"  !CDS_PN = "2";
BODY = "Q_RES","I24": #LOCATION = "R3924" !CDS_LOCATION = "R3924" &SEC = "1" #&CDS_SEC = "1";
"A":   PN = "1"  !CDS_PN = "1";
"B":   PN = "2"  !CDS_PN = "2";
BODY = "Q_CAP","I27": #LOCATION = "PC2186" !CDS_LOCATION = "PC2186" &SEC = "1" #&CDS_SEC = "1";
"A":   PN = "1"  !CDS_PN = "1";
"B":   PN = "2"  !CDS_PN = "2";
BODY = "Q_CAP","I30": #LOCATION = "PC2187" !CDS_LOCATION = "PC2187" &SEC = "1" #&CDS_SEC = "1";
"A":   PN = "1"  !CDS_PN = "1";
"B":   PN = "2"  !CDS_PN = "2";
BODY = "Q_RES","I34": #LOCATION = "R3925" !CDS_LOCATION = "R3925" &SEC = "1" #&CDS_SEC = "1";
"A":   PN = "1"  !CDS_PN = "1";
"B":   PN = "2"  !CDS_PN = "2";
BODY = "Q_RES","I36": #LOCATION = "R1714" !CDS_LOCATION = "R1714" &SEC = "1" #&CDS_SEC = "1";
"A":   PN = "1"  !CDS_PN = "1";
"B":   PN = "2"  !CDS_PN = "2";
BODY = "Q_RES","I37": #LOCATION = "R3909" !CDS_LOCATION = "R3909" &SEC = "1" #&CDS_SEC = "1";
"A":   PN = "1"  !CDS_PN = "1";
"B":   PN = "2"  !CDS_PN = "2";
BODY = "Q_RES","I39": #LOCATION = "PR2149" !CDS_LOCATION = "PR2149" &SEC = "1" #&CDS_SEC = "1";
"A":   PN = "1"  !CDS_PN = "1";
"B":   PN = "2"  !CDS_PN = "2";
BODY = "Q_CAP","I46": #LOCATION = "PC2188" !CDS_LOCATION = "PC2188" &SEC = "1" #&CDS_SEC = "1";
"A":   PN = "1"  !CDS_PN = "1";
"B":   PN = "2"  !CDS_PN = "2";
BODY = "Q_RES","I47": #LOCATION = "PR3927" !CDS_LOCATION = "PR3927" &SEC = "1" #&CDS_SEC = "1";
"A":   PN = "1"  !CDS_PN = "1";
"B":   PN = "2"  !CDS_PN = "2";
BODY = "Q_RES","I48": #LOCATION = "PR3926" !CDS_LOCATION = "PR3926" &SEC = "1" #&CDS_SEC = "1";
"A":   PN = "1"  !CDS_PN = "1";
"B":   PN = "2"  !CDS_PN = "2";
BODY = "Q_CAP","I50": #LOCATION = "PC2103" !CDS_LOCATION = "PC2103" &SEC = "1" #&CDS_SEC = "1";
"A":   PN = "1"  !CDS_PN = "1";
"B":   PN = "2"  !CDS_PN = "2";
BODY = "Q_RES","I51": #LOCATION = "PR3928" !CDS_LOCATION = "PR3928" &SEC = "1" #&CDS_SEC = "1";
"A":   PN = "1"  !CDS_PN = "1";
"B":   PN = "2"  !CDS_PN = "2";
BODY = "Q_RES","I52": #LOCATION = "PR3930" !CDS_LOCATION = "PR3930" &SEC = "1" #&CDS_SEC = "1";
"A":   PN = "1"  !CDS_PN = "1";
"B":   PN = "2"  !CDS_PN = "2";
BODY = "Q_RES","I53": #LOCATION = "PR3929" !CDS_LOCATION = "PR3929" &SEC = "1" #&CDS_SEC = "1";
"A":   PN = "1"  !CDS_PN = "1";
"B":   PN = "2"  !CDS_PN = "2";
BODY = "Q_RES","I54": #LOCATION = "R2586" !CDS_LOCATION = "R2586" &SEC = "1" #&CDS_SEC = "1";
"A":   PN = "1"  !CDS_PN = "1";
"B":   PN = "2"  !CDS_PN = "2";
BODY = "Q_RES","I56": #LOCATION = "PR2106" !CDS_LOCATION = "PR2106" &SEC = "1" #&CDS_SEC = "1";
"A":   PN = "1"  !CDS_PN = "1";
"B":   PN = "2"  !CDS_PN = "2";
BODY = "MP5990GMA1111Z","I58": #LOCATION = "PU289" !CDS_LOCATION = "PU289" &SEC = "1" #&CDS_SEC = "1";
"ADDR":   PN = "23"  !CDS_PN = "23";
"ALT#":   PN = "10"  !CDS_PN = "10";
"CS":   PN = "20"  !CDS_PN = "20";
"D_OC":   PN = "37"  !CDS_PN = "37";
"EN":   PN = "26"  !CDS_PN = "26";
"FLT_TYPE":   PN = "40"  !CDS_PN = "40";
"GND1":   PN = "18"  !CDS_PN = "18";
"GND2":   PN = "44"  !CDS_PN = "44";
"GOK":   PN = "39"  !CDS_PN = "39";
"IMON":   PN = "21"  !CDS_PN = "21";
"MODE":   PN = "41"  !CDS_PN = "41";
"OCREF":   PN = "22"  !CDS_PN = "22";
"ON":   PN = "38"  !CDS_PN = "38";
"PG||OCW#":   PN = "13"  !CDS_PN = "13";
"SCL":   PN = "11"  !CDS_PN = "11";
"SCREF_OCWREF":   PN = "25"  !CDS_PN = "25";
"SDA":   PN = "12"  !CDS_PN = "12";
"SS":   PN = "16"  !CDS_PN = "16";
"VDD18":   PN = "19"  !CDS_PN = "19";
"VDD33_1":   PN = "17"  !CDS_PN = "17";
"VDD33_2":   PN = "45"  !CDS_PN = "45";
"VIN1":   PN = "1"  !CDS_PN = "1";
"VIN2":   PN = "2"  !CDS_PN = "2";
"VIN3":   PN = "3"  !CDS_PN = "3";
"VIN4":   PN = "4"  !CDS_PN = "4";
"VIN5":   PN = "5"  !CDS_PN = "5";
"VIN6":   PN = "6"  !CDS_PN = "6";
"VIN7":   PN = "7"  !CDS_PN = "7";
"VIN8":   PN = "8"  !CDS_PN = "8";
"VIN9":   PN = "42"  !CDS_PN = "42";
"VIN10":   PN = "43"  !CDS_PN = "43";
"VIN_UVW#":   PN = "14"  !CDS_PN = "14";
"VINSEN":   PN = "9"  !CDS_PN = "9";
"VOSEN":   PN = "24"  !CDS_PN = "24";
"VOUT1":   PN = "27"  !CDS_PN = "27";
"VOUT2":   PN = "28"  !CDS_PN = "28";
"VOUT3":   PN = "29"  !CDS_PN = "29";
"VOUT4":   PN = "30"  !CDS_PN = "30";
"VOUT5":   PN = "31"  !CDS_PN = "31";
"VOUT6":   PN = "32"  !CDS_PN = "32";
"VOUT7":   PN = "33"  !CDS_PN = "33";
"VOUT8":   PN = "34"  !CDS_PN = "34";
"VOUT9":   PN = "35"  !CDS_PN = "35";
"VOUT10":   PN = "36"  !CDS_PN = "36";
"VTEMP":   PN = "15"  !CDS_PN = "15";
BODY = "Q_CAP","I59": #LOCATION = "PC2189" !CDS_LOCATION = "PC2189" &SEC = "1" #&CDS_SEC = "1";
"A":   PN = "1"  !CDS_PN = "1";
"B":   PN = "2"  !CDS_PN = "2";
BODY = "Q_RES","I63": #LOCATION = "R3933" !CDS_LOCATION = "R3933" &SEC = "1" #&CDS_SEC = "1";
"A":   PN = "1"  !CDS_PN = "1";
"B":   PN = "2"  !CDS_PN = "2";
BODY = "Q_RES","I65": #LOCATION = "PR1131" !CDS_LOCATION = "PR1131" &SEC = "1" #&CDS_SEC = "1";
"A":   PN = "1"  !CDS_PN = "1";
"B":   PN = "2"  !CDS_PN = "2";
BODY = "Q_RES","I70": #LOCATION = "PR3932" !CDS_LOCATION = "PR3932" &SEC = "1" #&CDS_SEC = "1";
"A":   PN = "1"  !CDS_PN = "1";
"B":   PN = "2"  !CDS_PN = "2";
BODY = "Q_RES","I71": #LOCATION = "PR3931" !CDS_LOCATION = "PR3931" &SEC = "1" #&CDS_SEC = "1";
"A":   PN = "1"  !CDS_PN = "1";
"B":   PN = "2"  !CDS_PN = "2";
BODY = "Q_CAP","I72": #LOCATION = "PC2190" !CDS_LOCATION = "PC2190" &SEC = "1" #&CDS_SEC = "1";
"A":   PN = "1"  !CDS_PN = "1";
"B":   PN = "2"  !CDS_PN = "2";
BODY = "Q_CAP","I75": #LOCATION = "PC2191" !CDS_LOCATION = "PC2191" &SEC = "1" #&CDS_SEC = "1";
"A":   PN = "1"  !CDS_PN = "1";
"B":   PN = "2"  !CDS_PN = "2";
BODY = "Q_CAP","I78": #LOCATION = "PC2192" !CDS_LOCATION = "PC2192" &SEC = "1" #&CDS_SEC = "1";
"A":   PN = "1"  !CDS_PN = "1";
"B":   PN = "2"  !CDS_PN = "2";
BODY = "Q_RES","I79": #LOCATION = "R2588" !CDS_LOCATION = "R2588" &SEC = "1" #&CDS_SEC = "1";
"A":   PN = "1"  !CDS_PN = "1";
"B":   PN = "2"  !CDS_PN = "2";
BODY = "Q_RES","I80": #LOCATION = "R3934" !CDS_LOCATION = "R3934" &SEC = "1" #&CDS_SEC = "1";
"A":   PN = "1"  !CDS_PN = "1";
"B":   PN = "2"  !CDS_PN = "2";
BODY = "Q_RES","I81": #LOCATION = "PR3935" !CDS_LOCATION = "PR3935" &SEC = "1" #&CDS_SEC = "1";
"A":   PN = "1"  !CDS_PN = "1";
"B":   PN = "2"  !CDS_PN = "2";
BODY = "Q_CAP","I84": #LOCATION = "PC2193" !CDS_LOCATION = "PC2193" &SEC = "1" #&CDS_SEC = "1";
"A":   PN = "1"  !CDS_PN = "1";
"B":   PN = "2"  !CDS_PN = "2";
BODY = "Q_RES","I85": #LOCATION = "PR3937" !CDS_LOCATION = "PR3937" &SEC = "1" #&CDS_SEC = "1";
"A":   PN = "1"  !CDS_PN = "1";
"B":   PN = "2"  !CDS_PN = "2";
BODY = "Q_RES","I86": #LOCATION = "PR1133" !CDS_LOCATION = "PR1133" &SEC = "1" #&CDS_SEC = "1";
"A":   PN = "1"  !CDS_PN = "1";
"B":   PN = "2"  !CDS_PN = "2";
BODY = "SS15P3SM386A","I89": #LOCATION = "PD111" !CDS_LOCATION = "PD111" &SEC = "1" #&CDS_SEC = "1";
"ANODE_1":   PN = "1"  !CDS_PN = "1";
"ANODE_2":   PN = "2"  !CDS_PN = "2";
"CATHODE":   PN = "K"  !CDS_PN = "K";
BODY = "Q_RES","I91": #LOCATION = "R3936" !CDS_LOCATION = "R3936" &SEC = "1" #&CDS_SEC = "1";
"A":   PN = "1"  !CDS_PN = "1";
"B":   PN = "2"  !CDS_PN = "2";
BODY = "Q_RES","I99": #LOCATION = "R2587" !CDS_LOCATION = "R2587" &SEC = "1" #&CDS_SEC = "1";
"A":   PN = "1"  !CDS_PN = "1";
"B":   PN = "2"  !CDS_PN = "2";
DRAWING = "@t6g_mb_lib.t6g(sch_1):page372";
BODY = "ZENER_AC","I1": #LOCATION = "PD15" !CDS_LOCATION = "PD15" &SEC = "1" #&CDS_SEC = "1";
"A":   PN = "A"  !CDS_PN = "A";
"C":   PN = "C"  !CDS_PN = "C";
BODY = "ZENER_AC","I3": #LOCATION = "PD13" !CDS_LOCATION = "PD13" &SEC = "1" #&CDS_SEC = "1";
"A":   PN = "A"  !CDS_PN = "A";
"C":   PN = "C"  !CDS_PN = "C";
BODY = "Q_FUSE","I6": #LOCATION = "FS1" !CDS_LOCATION = "FS1" &SEC = "1" #&CDS_SEC = "1";
"1":   PN = "1"  !CDS_PN = "1";
"2":   PN = "2"  !CDS_PN = "2";
BODY = "Q_CAP","I9": #LOCATION = "C1797" !CDS_LOCATION = "C1797" &SEC = "1" #&CDS_SEC = "1";
"A":   PN = "1"  !CDS_PN = "1";
"B":   PN = "2"  !CDS_PN = "2";
BODY = "Q_RES","I10": #LOCATION = "R3907" !CDS_LOCATION = "R3907" &SEC = "1" #&CDS_SEC = "1";
"A":   PN = "1"  !CDS_PN = "1";
"B":   PN = "2"  !CDS_PN = "2";
BODY = "MOSFET_NCH_GDS_ESD_PROTECTED","I11": #LOCATION = "U290" !CDS_LOCATION = "U290" &SEC = "1" #&CDS_SEC = "1";
"D":   PN = "D"  !CDS_PN = "D";
"G":   PN = "G"  !CDS_PN = "G";
"S":   PN = "S"  !CDS_PN = "S";
BODY = "Q_RES","I13": #LOCATION = "R2585" !CDS_LOCATION = "R2585" &SEC = "1" #&CDS_SEC = "1";
"A":   PN = "1"  !CDS_PN = "1";
"B":   PN = "2"  !CDS_PN = "2";
BODY = "Q_RES","I16": #LOCATION = "R3923" !CDS_LOCATION = "R3923" &SEC = "1" #&CDS_SEC = "1";
"A":   PN = "1"  !CDS_PN = "1";
"B":   PN = "2"  !CDS_PN = "2";
BODY = "CONN3_210HP1030BR1","I18": #LOCATION = "JP4003" !CDS_LOCATION = "JP4003" &SEC = "1" #&CDS_SEC = "1";
"1":   PN = "1"  !CDS_PN = "1";
"2":   PN = "2"  !CDS_PN = "2";
"3":   PN = "3"  !CDS_PN = "3";
BODY = "Q_RES","I19": #LOCATION = "R4901" !CDS_LOCATION = "R4901" &SEC = "1" #&CDS_SEC = "1";
"A":   PN = "1"  !CDS_PN = "1";
"B":   PN = "2"  !CDS_PN = "2";
BODY = "Q_CAP","I22": #LOCATION = "C2179" !CDS_LOCATION = "C2179" #SEC = "1" !CDS_SEC = "1";
"A":   PN = "1"  !CDS_PN = "1";
"B":   PN = "2"  !CDS_PN = "2";
BODY = "Q_RES","I27": #LOCATION = "PR3002" !CDS_LOCATION = "PR3002" &SEC = "1" #&CDS_SEC = "1";
"A":   PN = "1"  !CDS_PN = "1";
"B":   PN = "2"  !CDS_PN = "2";
BODY = "Q_RES","I29": #LOCATION = "R2227" !CDS_LOCATION = "R2227" &SEC = "1" #&CDS_SEC = "1";
"A":   PN = "1"  !CDS_PN = "1";
"B":   PN = "2"  !CDS_PN = "2";
BODY = "Q_RES","I30": #LOCATION = "R2219" !CDS_LOCATION = "R2219" &SEC = "1" #&CDS_SEC = "1";
"A":   PN = "1"  !CDS_PN = "1";
"B":   PN = "2"  !CDS_PN = "2";
BODY = "Q_RES","I33": #LOCATION = "R2222" !CDS_LOCATION = "R2222" &SEC = "1" #&CDS_SEC = "1";
"A":   PN = "1"  !CDS_PN = "1";
"B":   PN = "2"  !CDS_PN = "2";
BODY = "Q_RES","I35": #LOCATION = "R2221" !CDS_LOCATION = "R2221" &SEC = "1" #&CDS_SEC = "1";
"A":   PN = "1"  !CDS_PN = "1";
"B":   PN = "2"  !CDS_PN = "2";
BODY = "MOSFET_N","I42": #LOCATION = "U325" !CDS_LOCATION = "U325" &SEC = "1" #&CDS_SEC = "1";
"DRAIN":   PN = "D"  !CDS_PN = "D";
"GATE":   PN = "G"  !CDS_PN = "G";
"SOURCE":   PN = "S"  !CDS_PN = "S";
BODY = "Q_RES","I43": #LOCATION = "R2230" !CDS_LOCATION = "R2230" &SEC = "1" #&CDS_SEC = "1";
"A":   PN = "1"  !CDS_PN = "1";
"B":   PN = "2"  !CDS_PN = "2";
BODY = "Q_RES","I45": #LOCATION = "R2233" !CDS_LOCATION = "R2233" &SEC = "1" #&CDS_SEC = "1";
"A":   PN = "1"  !CDS_PN = "1";
"B":   PN = "2"  !CDS_PN = "2";
BODY = "Q_RES","I46": #LOCATION = "R4620" !CDS_LOCATION = "R4620" &SEC = "1" #&CDS_SEC = "1";
"A":   PN = "1"  !CDS_PN = "1";
"B":   PN = "2"  !CDS_PN = "2";
BODY = "LT6700CS61TRPBF","I49": #LOCATION = "U206" !CDS_LOCATION = "U206" &SEC = "1" #&CDS_SEC = "1";
"GND":   PN = "2"  !CDS_PN = "2";
"INA+":   PN = "3"  !CDS_PN = "3";
"INB-":   PN = "4"  !CDS_PN = "4";
"OUTA":   PN = "1"  !CDS_PN = "1";
"OUTB":   PN = "6"  !CDS_PN = "6";
"VS":   PN = "5"  !CDS_PN = "5";
BODY = "LM4040AIM3X25NOPB","I51": #LOCATION = "U8007" !CDS_LOCATION = "U8007" &SEC = "1" #&CDS_SEC = "1";
"1+":   PN = "1"  !CDS_PN = "1";
"2-":   PN = "2"  !CDS_PN = "2";
"3":   PN = "3"  !CDS_PN = "3";
BODY = "Q_RES","I52": #LOCATION = "R8113" !CDS_LOCATION = "R8113" &SEC = "1" #&CDS_SEC = "1";
"A":   PN = "1"  !CDS_PN = "1";
"B":   PN = "2"  !CDS_PN = "2";
BODY = "Q_RES","I55": #LOCATION = "R8115" !CDS_LOCATION = "R8115" &SEC = "1" #&CDS_SEC = "1";
"A":   PN = "1"  !CDS_PN = "1";
"B":   PN = "2"  !CDS_PN = "2";
BODY = "Q_RES","I56": #LOCATION = "R8114" !CDS_LOCATION = "R8114" &SEC = "1" #&CDS_SEC = "1";
"A":   PN = "1"  !CDS_PN = "1";
"B":   PN = "2"  !CDS_PN = "2";
BODY = "Q_CAP","I59": #LOCATION = "C8017" !CDS_LOCATION = "C8017" &SEC = "1" #&CDS_SEC = "1";
"A":   PN = "1"  !CDS_PN = "1";
"B":   PN = "2"  !CDS_PN = "2";
BODY = "Q_CAP","I61": #LOCATION = "C8018" !CDS_LOCATION = "C8018" &SEC = "1" #&CDS_SEC = "1";
"A":   PN = "1"  !CDS_PN = "1";
"B":   PN = "2"  !CDS_PN = "2";
BODY = "Q_RES","I63": #LOCATION = "R8117" !CDS_LOCATION = "R8117" &SEC = "1" #&CDS_SEC = "1";
"A":   PN = "1"  !CDS_PN = "1";
"B":   PN = "2"  !CDS_PN = "2";
BODY = "Q_CAP","I66": #LOCATION = "C8019" !CDS_LOCATION = "C8019" &SEC = "1" #&CDS_SEC = "1";
"A":   PN = "1"  !CDS_PN = "1";
"B":   PN = "2"  !CDS_PN = "2";
BODY = "Q_RES","I67": #LOCATION = "R8118" !CDS_LOCATION = "R8118" &SEC = "1" #&CDS_SEC = "1";
"A":   PN = "1"  !CDS_PN = "1";
"B":   PN = "2"  !CDS_PN = "2";
BODY = "Q_RES","I69": #LOCATION = "R8119" !CDS_LOCATION = "R8119" &SEC = "1" #&CDS_SEC = "1";
"A":   PN = "1"  !CDS_PN = "1";
"B":   PN = "2"  !CDS_PN = "2";
BODY = "AP331AWG7","I71": #LOCATION = "U8008" !CDS_LOCATION = "U8008" &SEC = "1" #&CDS_SEC = "1";
"GND":   PN = "2"  !CDS_PN = "2";
"IN+":   PN = "3"  !CDS_PN = "3";
"IN-":   PN = "1"  !CDS_PN = "1";
"OUTPUT":   PN = "4"  !CDS_PN = "4";
"VCC":   PN = "5"  !CDS_PN = "5";
BODY = "Q_RES","I72": #LOCATION = "R8120" !CDS_LOCATION = "R8120" &SEC = "1" #&CDS_SEC = "1";
"A":   PN = "1"  !CDS_PN = "1";
"B":   PN = "2"  !CDS_PN = "2";
BODY = "Q_RES","I75": #LOCATION = "R8122" !CDS_LOCATION = "R8122" &SEC = "1" #&CDS_SEC = "1";
"A":   PN = "1"  !CDS_PN = "1";
"B":   PN = "2"  !CDS_PN = "2";
BODY = "Q_RES","I76": #LOCATION = "R8121" !CDS_LOCATION = "R8121" &SEC = "1" #&CDS_SEC = "1";
"A":   PN = "1"  !CDS_PN = "1";
"B":   PN = "2"  !CDS_PN = "2";
BODY = "Q_CAP","I79": #LOCATION = "C8020" !CDS_LOCATION = "C8020" &SEC = "1" #&CDS_SEC = "1";
"A":   PN = "1"  !CDS_PN = "1";
"B":   PN = "2"  !CDS_PN = "2";
BODY = "AP331AWG7","I80": #LOCATION = "U8010" !CDS_LOCATION = "U8010" &SEC = "1" #&CDS_SEC = "1";
"GND":   PN = "2"  !CDS_PN = "2";
"IN+":   PN = "3"  !CDS_PN = "3";
"IN-":   PN = "1"  !CDS_PN = "1";
"OUTPUT":   PN = "4"  !CDS_PN = "4";
"VCC":   PN = "5"  !CDS_PN = "5";
BODY = "Q_RES","I81": #LOCATION = "R8123" !CDS_LOCATION = "R8123" &SEC = "1" #&CDS_SEC = "1";
"A":   PN = "1"  !CDS_PN = "1";
"B":   PN = "2"  !CDS_PN = "2";
BODY = "Q_CAP","I84": #LOCATION = "C8022" !CDS_LOCATION = "C8022" &SEC = "1" #&CDS_SEC = "1";
"A":   PN = "1"  !CDS_PN = "1";
"B":   PN = "2"  !CDS_PN = "2";
BODY = "Q_RES","I85": #LOCATION = "R8124" !CDS_LOCATION = "R8124" &SEC = "1" #&CDS_SEC = "1";
"A":   PN = "1"  !CDS_PN = "1";
"B":   PN = "2"  !CDS_PN = "2";
BODY = "Q_CAP","I92": #LOCATION = "C8021" !CDS_LOCATION = "C8021" &SEC = "1" #&CDS_SEC = "1";
"A":   PN = "1"  !CDS_PN = "1";
"B":   PN = "2"  !CDS_PN = "2";
BODY = "LM4040AIM3X25NOPB","I93": #LOCATION = "U8009" !CDS_LOCATION = "U8009" &SEC = "1" #&CDS_SEC = "1";
"1+":   PN = "1"  !CDS_PN = "1";
"2-":   PN = "2"  !CDS_PN = "2";
"3":   PN = "3"  !CDS_PN = "3";
BODY = "Q_CAP","I96": #LOCATION = "C1561" !CDS_LOCATION = "C1561" &SEC = "1" #&CDS_SEC = "1";
"A":   PN = "1"  !CDS_PN = "1";
"B":   PN = "2"  !CDS_PN = "2";
BODY = "Q_RES","I97": #LOCATION = "R9021" !CDS_LOCATION = "R9021" &SEC = "1" #&CDS_SEC = "1";
"A":   PN = "1"  !CDS_PN = "1";
"B":   PN = "2"  !CDS_PN = "2";
BODY = "Q_CAP","I99": #LOCATION = "C9004" !CDS_LOCATION = "C9004" &SEC = "1" #&CDS_SEC = "1";
"A":   PN = "1"  !CDS_PN = "1";
"B":   PN = "2"  !CDS_PN = "2";
BODY = "CONN3_210HP1030BR1","I103": #LOCATION = "JP10" !CDS_LOCATION = "JP10" &SEC = "1" #&CDS_SEC = "1";
"1":   PN = "1"  !CDS_PN = "1";
"2":   PN = "2"  !CDS_PN = "2";
"3":   PN = "3"  !CDS_PN = "3";
BODY = "Q_RES","I104": #LOCATION = "R8125" !CDS_LOCATION = "R8125" &SEC = "1" #&CDS_SEC = "1";
"A":   PN = "1"  !CDS_PN = "1";
"B":   PN = "2"  !CDS_PN = "2";
DRAWING = "@t6g_mb_lib.t6g(sch_1):page302";
BODY = "Q_RES","I5": #LOCATION = "PR2523" !CDS_LOCATION = "PR2523" &SEC = "1" #&CDS_SEC = "1";
"A":   PN = "1"  !CDS_PN = "1";
"B":   PN = "2"  !CDS_PN = "2";
BODY = "Q_RES","I6": #LOCATION = "PR2521" !CDS_LOCATION = "PR2521" &SEC = "1" #&CDS_SEC = "1";
"A":   PN = "1"  !CDS_PN = "1";
"B":   PN = "2"  !CDS_PN = "2";
BODY = "Q_RES","I7": #LOCATION = "PR2522" !CDS_LOCATION = "PR2522" &SEC = "1" #&CDS_SEC = "1";
"A":   PN = "1"  !CDS_PN = "1";
"B":   PN = "2"  !CDS_PN = "2";
BODY = "Q_RES","I8": #LOCATION = "PR2520" !CDS_LOCATION = "PR2520" &SEC = "1" #&CDS_SEC = "1";
"A":   PN = "1"  !CDS_PN = "1";
"B":   PN = "2"  !CDS_PN = "2";
BODY = "Q_RES","I15": #LOCATION = "PR2513" !CDS_LOCATION = "PR2513" &SEC = "1" #&CDS_SEC = "1";
"A":   PN = "1"  !CDS_PN = "1";
"B":   PN = "2"  !CDS_PN = "2";
BODY = "Q_RES","I16": #LOCATION = "PR2512" !CDS_LOCATION = "PR2512" &SEC = "1" #&CDS_SEC = "1";
"A":   PN = "1"  !CDS_PN = "1";
"B":   PN = "2"  !CDS_PN = "2";
BODY = "Q_RES","I17": #LOCATION = "PR2511" !CDS_LOCATION = "PR2511" &SEC = "1" #&CDS_SEC = "1";
"A":   PN = "1"  !CDS_PN = "1";
"B":   PN = "2"  !CDS_PN = "2";
BODY = "Q_RES","I18": #LOCATION = "PR2510" !CDS_LOCATION = "PR2510" &SEC = "1" #&CDS_SEC = "1";
"A":   PN = "1"  !CDS_PN = "1";
"B":   PN = "2"  !CDS_PN = "2";
BODY = "Q_RES","I27": #LOCATION = "PR2528" !CDS_LOCATION = "PR2528" &SEC = "1" #&CDS_SEC = "1";
"A":   PN = "1"  !CDS_PN = "1";
"B":   PN = "2"  !CDS_PN = "2";
BODY = "Q_RES","I28": #LOCATION = "PR2529" !CDS_LOCATION = "PR2529" &SEC = "1" #&CDS_SEC = "1";
"A":   PN = "1"  !CDS_PN = "1";
"B":   PN = "2"  !CDS_PN = "2";
BODY = "MOSFET_NCH_1D3S","I29": #LOCATION = "PPQ5" !CDS_LOCATION = "PPQ5" &SEC = "1" #&CDS_SEC = "1";
"1":   PN = "1"  !CDS_PN = "1";
"2":   PN = "2"  !CDS_PN = "2";
"3":   PN = "3"  !CDS_PN = "3";
"4":   PN = "4"  !CDS_PN = "4";
"5":   PN = "5"  !CDS_PN = "5";
BODY = "Q_RES","I45": #LOCATION = "PR2530" !CDS_LOCATION = "PR2530" &SEC = "1" #&CDS_SEC = "1";
"A":   PN = "1"  !CDS_PN = "1";
"B":   PN = "2"  !CDS_PN = "2";
BODY = "MOSFET_NCH_1D3S","I46": #LOCATION = "PPQ6" !CDS_LOCATION = "PPQ6" &SEC = "1" #&CDS_SEC = "1";
"1":   PN = "1"  !CDS_PN = "1";
"2":   PN = "2"  !CDS_PN = "2";
"3":   PN = "3"  !CDS_PN = "3";
"4":   PN = "4"  !CDS_PN = "4";
"5":   PN = "5"  !CDS_PN = "5";
BODY = "Q_RES","I47": #LOCATION = "PR2531" !CDS_LOCATION = "PR2531" &SEC = "1" #&CDS_SEC = "1";
"A":   PN = "1"  !CDS_PN = "1";
"B":   PN = "2"  !CDS_PN = "2";
BODY = "Q_SP_RES4P","I52": #LOCATION = "PR2534" !CDS_LOCATION = "PR2534" &SEC = "1" #&CDS_SEC = "1";
"1A":   PN = "1A"  !CDS_PN = "1A";
"1B":   PN = "1B"  !CDS_PN = "1B";
"2A":   PN = "2A"  !CDS_PN = "2A";
"2B":   PN = "2B"  !CDS_PN = "2B";
BODY = "Q_SP_RES4P","I53": #LOCATION = "PR2533" !CDS_LOCATION = "PR2533" &SEC = "1" #&CDS_SEC = "1";
"1A":   PN = "1A"  !CDS_PN = "1A";
"1B":   PN = "1B"  !CDS_PN = "1B";
"2A":   PN = "2A"  !CDS_PN = "2A";
"2B":   PN = "2B"  !CDS_PN = "2B";
BODY = "Q_SP_RES4P","I54": #LOCATION = "PR2532" !CDS_LOCATION = "PR2532" &SEC = "1" #&CDS_SEC = "1";
"1A":   PN = "1A"  !CDS_PN = "1A";
"1B":   PN = "1B"  !CDS_PN = "1B";
"2A":   PN = "2A"  !CDS_PN = "2A";
"2B":   PN = "2B"  !CDS_PN = "2B";
BODY = "Q_SP_RES4P","I55": #LOCATION = "PR6001" !CDS_LOCATION = "PR6001" #SEC = "1" !CDS_SEC = "1";
"1A":   PN = "1A"  !CDS_PN = "1A";
"1B":   PN = "1B"  !CDS_PN = "1B";
"2A":   PN = "2A"  !CDS_PN = "2A";
"2B":   PN = "2B"  !CDS_PN = "2B";
BODY = "Q_RES","I60": #LOCATION = "PR2535" !CDS_LOCATION = "PR2535" &SEC = "1" #&CDS_SEC = "1";
"A":   PN = "1"  !CDS_PN = "1";
"B":   PN = "2"  !CDS_PN = "2";
BODY = "MOSFET_NCH_1D3S","I61": #LOCATION = "PPQ1" !CDS_LOCATION = "PPQ1" #SEC = "1" !CDS_SEC = "1";
"1":   PN = "1"  !CDS_PN = "1";
"2":   PN = "2"  !CDS_PN = "2";
"3":   PN = "3"  !CDS_PN = "3";
"4":   PN = "4"  !CDS_PN = "4";
"5":   PN = "5"  !CDS_PN = "5";
BODY = "Q_RES","I62": #LOCATION = "PR2536" !CDS_LOCATION = "PR2536" &SEC = "1" #&CDS_SEC = "1";
"A":   PN = "1"  !CDS_PN = "1";
"B":   PN = "2"  !CDS_PN = "2";
BODY = "Q_CAP","I63": #LOCATION = "PC1750" !CDS_LOCATION = "PC1750" &SEC = "1" #&CDS_SEC = "1";
"A":   PN = "1"  !CDS_PN = "1";
"B":   PN = "2"  !CDS_PN = "2";
BODY = "MOSFET_NCH_1D3S","I64": #LOCATION = "PPQ2" !CDS_LOCATION = "PPQ2" #SEC = "1" !CDS_SEC = "1";
"1":   PN = "1"  !CDS_PN = "1";
"2":   PN = "2"  !CDS_PN = "2";
"3":   PN = "3"  !CDS_PN = "3";
"4":   PN = "4"  !CDS_PN = "4";
"5":   PN = "5"  !CDS_PN = "5";
BODY = "Q_CAP","I70": #LOCATION = "PC1751" !CDS_LOCATION = "PC1751" &SEC = "1" #&CDS_SEC = "1";
"A":   PN = "1"  !CDS_PN = "1";
"B":   PN = "2"  !CDS_PN = "2";
BODY = "Q_RES","I71": #LOCATION = "PR2537" !CDS_LOCATION = "PR2537" &SEC = "1" #&CDS_SEC = "1";
"A":   PN = "1"  !CDS_PN = "1";
"B":   PN = "2"  !CDS_PN = "2";
BODY = "SS15P3SM386A","I72": #LOCATION = "PD17" !CDS_LOCATION = "PD17" &SEC = "1" #&CDS_SEC = "1";
"ANODE_1":   PN = "1"  !CDS_PN = "1";
"ANODE_2":   PN = "2"  !CDS_PN = "2";
"CATHODE":   PN = "K"  !CDS_PN = "K";
BODY = "Q_RES","I74": #LOCATION = "PR2538" !CDS_LOCATION = "PR2538" &SEC = "1" #&CDS_SEC = "1";
"A":   PN = "1"  !CDS_PN = "1";
"B":   PN = "2"  !CDS_PN = "2";
BODY = "MOSFET_NCH_1D3S","I75": #LOCATION = "PPQ9" !CDS_LOCATION = "PPQ9" &SEC = "1" #&CDS_SEC = "1";
"1":   PN = "1"  !CDS_PN = "1";
"2":   PN = "2"  !CDS_PN = "2";
"3":   PN = "3"  !CDS_PN = "3";
"4":   PN = "4"  !CDS_PN = "4";
"5":   PN = "5"  !CDS_PN = "5";
BODY = "MOSFET_NCH_1D3S","I79": #LOCATION = "PPQ8" !CDS_LOCATION = "PPQ8" &SEC = "1" #&CDS_SEC = "1";
"1":   PN = "1"  !CDS_PN = "1";
"2":   PN = "2"  !CDS_PN = "2";
"3":   PN = "3"  !CDS_PN = "3";
"4":   PN = "4"  !CDS_PN = "4";
"5":   PN = "5"  !CDS_PN = "5";
BODY = "MOSFET_NCH_1D3S","I80": #LOCATION = "PPQ7" !CDS_LOCATION = "PPQ7" &SEC = "1" #&CDS_SEC = "1";
"1":   PN = "1"  !CDS_PN = "1";
"2":   PN = "2"  !CDS_PN = "2";
"3":   PN = "3"  !CDS_PN = "3";
"4":   PN = "4"  !CDS_PN = "4";
"5":   PN = "5"  !CDS_PN = "5";
BODY = "Q_SP_RES4P","I81": #LOCATION = "PR6002" !CDS_LOCATION = "PR6002" #SEC = "1" !CDS_SEC = "1";
"1A":   PN = "1A"  !CDS_PN = "1A";
"1B":   PN = "1B"  !CDS_PN = "1B";
"2A":   PN = "2A"  !CDS_PN = "2A";
"2B":   PN = "2B"  !CDS_PN = "2B";
BODY = "Q_RES","I82": #LOCATION = "PR2514" !CDS_LOCATION = "PR2514" &SEC = "1" #&CDS_SEC = "1";
"A":   PN = "1"  !CDS_PN = "1";
"B":   PN = "2"  !CDS_PN = "2";
BODY = "Q_RES","I83": #LOCATION = "PR2515" !CDS_LOCATION = "PR2515" &SEC = "1" #&CDS_SEC = "1";
"A":   PN = "1"  !CDS_PN = "1";
"B":   PN = "2"  !CDS_PN = "2";
BODY = "Q_RES","I84": #LOCATION = "PR2516" !CDS_LOCATION = "PR2516" &SEC = "1" #&CDS_SEC = "1";
"A":   PN = "1"  !CDS_PN = "1";
"B":   PN = "2"  !CDS_PN = "2";
BODY = "Q_RES","I85": #LOCATION = "PR2517" !CDS_LOCATION = "PR2517" &SEC = "1" #&CDS_SEC = "1";
"A":   PN = "1"  !CDS_PN = "1";
"B":   PN = "2"  !CDS_PN = "2";
BODY = "Q_RES","I86": #LOCATION = "PR2518" !CDS_LOCATION = "PR2518" &SEC = "1" #&CDS_SEC = "1";
"A":   PN = "1"  !CDS_PN = "1";
"B":   PN = "2"  !CDS_PN = "2";
BODY = "Q_RES","I87": #LOCATION = "PR2519" !CDS_LOCATION = "PR2519" &SEC = "1" #&CDS_SEC = "1";
"A":   PN = "1"  !CDS_PN = "1";
"B":   PN = "2"  !CDS_PN = "2";
BODY = "Q_RES","I88": #LOCATION = "PR2524" !CDS_LOCATION = "PR2524" &SEC = "1" #&CDS_SEC = "1";
"A":   PN = "1"  !CDS_PN = "1";
"B":   PN = "2"  !CDS_PN = "2";
BODY = "Q_RES","I89": #LOCATION = "PR2525" !CDS_LOCATION = "PR2525" &SEC = "1" #&CDS_SEC = "1";
"A":   PN = "1"  !CDS_PN = "1";
"B":   PN = "2"  !CDS_PN = "2";
BODY = "Q_RES","I90": #LOCATION = "PR2526" !CDS_LOCATION = "PR2526" &SEC = "1" #&CDS_SEC = "1";
"A":   PN = "1"  !CDS_PN = "1";
"B":   PN = "2"  !CDS_PN = "2";
BODY = "Q_RES","I91": #LOCATION = "PR2527" !CDS_LOCATION = "PR2527" &SEC = "1" #&CDS_SEC = "1";
"A":   PN = "1"  !CDS_PN = "1";
"B":   PN = "2"  !CDS_PN = "2";
DRAWING = "@t6g_mb_lib.t6g(sch_1):page371";
BODY = "METR3904G","I1": #LOCATION = "Q6001" !CDS_LOCATION = "Q6001" &SEC = "1" #&CDS_SEC = "1";
"1":   PN = "B"  !CDS_PN = "B";
"2":   PN = "E"  !CDS_PN = "E";
"3":   PN = "C"  !CDS_PN = "C";
BODY = "Q_RES","I2": #LOCATION = "R2624" !CDS_LOCATION = "R2624" &SEC = "1" #&CDS_SEC = "1";
"A":   PN = "1"  !CDS_PN = "1";
"B":   PN = "2"  !CDS_PN = "2";
BODY = "Q_RES","I3": #LOCATION = "R2625" !CDS_LOCATION = "R2625" &SEC = "1" #&CDS_SEC = "1";
"A":   PN = "1"  !CDS_PN = "1";
"B":   PN = "2"  !CDS_PN = "2";
BODY = "Q_CAP","I4": #LOCATION = "C1786" !CDS_LOCATION = "C1786" &SEC = "1" #&CDS_SEC = "1";
"A":   PN = "1"  !CDS_PN = "1";
"B":   PN = "2"  !CDS_PN = "2";
BODY = "Q_CAP","I6": #LOCATION = "C1787" !CDS_LOCATION = "C1787" &SEC = "1" #&CDS_SEC = "1";
"A":   PN = "1"  !CDS_PN = "1";
"B":   PN = "2"  !CDS_PN = "2";
BODY = "NCT7718W","I8": #LOCATION = "U143" !CDS_LOCATION = "U143" &SEC = "1" #&CDS_SEC = "1";
"ALERT#":   PN = "6"  !CDS_PN = "6";
"D+":   PN = "2"  !CDS_PN = "2";
"D-":   PN = "3"  !CDS_PN = "3";
"GND":   PN = "5"  !CDS_PN = "5";
"SCL":   PN = "8"  !CDS_PN = "8";
"SDA":   PN = "7"  !CDS_PN = "7";
"T_CRIT#":   PN = "4"  !CDS_PN = "4";
"VDD":   PN = "1"  !CDS_PN = "1";
BODY = "Q_RES","I10": #LOCATION = "R2628" !CDS_LOCATION = "R2628" &SEC = "1" #&CDS_SEC = "1";
"A":   PN = "1"  !CDS_PN = "1";
"B":   PN = "2"  !CDS_PN = "2";
BODY = "Q_CAP","I28": #LOCATION = "PC1789" !CDS_LOCATION = "PC1789" &SEC = "1" #&CDS_SEC = "1";
"A":   PN = "1"  !CDS_PN = "1";
"B":   PN = "2"  !CDS_PN = "2";
BODY = "Q_RES","I39": #LOCATION = "R2627" !CDS_LOCATION = "R2627" &SEC = "1" #&CDS_SEC = "1";
"A":   PN = "1"  !CDS_PN = "1";
"B":   PN = "2"  !CDS_PN = "2";
BODY = "Q_RES","I40": #LOCATION = "R2626" !CDS_LOCATION = "R2626" &SEC = "1" #&CDS_SEC = "1";
"A":   PN = "1"  !CDS_PN = "1";
"B":   PN = "2"  !CDS_PN = "2";
BODY = "SCONN21_9193031121LF","I42": #LOCATION = "PJ38" !CDS_LOCATION = "PJ38" #SEC = "1" !CDS_SEC = "1";
"1":   PN = "1"  !CDS_PN = "1";
"2":   PN = "2"  !CDS_PN = "2";
"3":   PN = "3"  !CDS_PN = "3";
"4":   PN = "4"  !CDS_PN = "4";
"5":   PN = "5"  !CDS_PN = "5";
"6":   PN = "6"  !CDS_PN = "6";
"7":   PN = "7"  !CDS_PN = "7";
"8":   PN = "8"  !CDS_PN = "8";
"9":   PN = "9"  !CDS_PN = "9";
"10":   PN = "10"  !CDS_PN = "10";
"11":   PN = "11"  !CDS_PN = "11";
"12":   PN = "12"  !CDS_PN = "12";
"13":   PN = "13"  !CDS_PN = "13";
"14":   PN = "14"  !CDS_PN = "14";
"15":   PN = "15"  !CDS_PN = "15";
"16":   PN = "16"  !CDS_PN = "16";
"17":   PN = "17"  !CDS_PN = "17";
"18":   PN = "18"  !CDS_PN = "18";
"19":   PN = "19"  !CDS_PN = "19";
"20":   PN = "20"  !CDS_PN = "20";
"21":   PN = "21"  !CDS_PN = "21";
"G1":   PN = "G1"  !CDS_PN = "G1";
"G2":   PN = "G2"  !CDS_PN = "G2";
BODY = "Q_RES","I45": #LOCATION = "R6230" !CDS_LOCATION = "R6230" &SEC = "1" #&CDS_SEC = "1";
"A":   PN = "1"  !CDS_PN = "1";
"B":   PN = "2"  !CDS_PN = "2";
BODY = "Q_RES","I46": #LOCATION = "R6231" !CDS_LOCATION = "R6231" &SEC = "1" #&CDS_SEC = "1";
"A":   PN = "1"  !CDS_PN = "1";
"B":   PN = "2"  !CDS_PN = "2";
BODY = "LT6700CS61TRPBF","I50": #LOCATION = "U142" !CDS_LOCATION = "U142" #SEC = "1" !CDS_SEC = "1";
"GND":   PN = "2"  !CDS_PN = "2";
"INA+":   PN = "3"  !CDS_PN = "3";
"INB-":   PN = "4"  !CDS_PN = "4";
"OUTA":   PN = "1"  !CDS_PN = "1";
"OUTB":   PN = "6"  !CDS_PN = "6";
"VS":   PN = "5"  !CDS_PN = "5";
BODY = "Q_RES","I55": #LOCATION = "R6234" !CDS_LOCATION = "R6234" &SEC = "1" #&CDS_SEC = "1";
"A":   PN = "1"  !CDS_PN = "1";
"B":   PN = "2"  !CDS_PN = "2";
BODY = "Q_RES","I56": #LOCATION = "R6232" !CDS_LOCATION = "R6232" &SEC = "1" #&CDS_SEC = "1";
"A":   PN = "1"  !CDS_PN = "1";
"B":   PN = "2"  !CDS_PN = "2";
BODY = "Q_RES","I57": #LOCATION = "R6233" !CDS_LOCATION = "R6233" &SEC = "1" #&CDS_SEC = "1";
"A":   PN = "1"  !CDS_PN = "1";
"B":   PN = "2"  !CDS_PN = "2";
BODY = "Q_RES","I58": #LOCATION = "R6235" !CDS_LOCATION = "R6235" &SEC = "1" #&CDS_SEC = "1";
"A":   PN = "1"  !CDS_PN = "1";
"B":   PN = "2"  !CDS_PN = "2";
BODY = "Q_RES","I63": #LOCATION = "R6236" !CDS_LOCATION = "R6236" &SEC = "1" #&CDS_SEC = "1";
"A":   PN = "1"  !CDS_PN = "1";
"B":   PN = "2"  !CDS_PN = "2";
BODY = "Q_RES","I66": #LOCATION = "R6237" !CDS_LOCATION = "R6237" &SEC = "1" #&CDS_SEC = "1";
"A":   PN = "1"  !CDS_PN = "1";
"B":   PN = "2"  !CDS_PN = "2";
BODY = "MOSFET_NCH_GDS_ESD_PROTECTED","I68": #LOCATION = "U6004" !CDS_LOCATION = "U6004" &SEC = "1" #&CDS_SEC = "1";
"D":   PN = "D"  !CDS_PN = "D";
"G":   PN = "G"  !CDS_PN = "G";
"S":   PN = "S"  !CDS_PN = "S";
BODY = "Q_RES","I70": #LOCATION = "R6239" !CDS_LOCATION = "R6239" &SEC = "1" #&CDS_SEC = "1";
"A":   PN = "1"  !CDS_PN = "1";
"B":   PN = "2"  !CDS_PN = "2";
BODY = "Q_RES","I72": #LOCATION = "R6238" !CDS_LOCATION = "R6238" &SEC = "1" #&CDS_SEC = "1";
"A":   PN = "1"  !CDS_PN = "1";
"B":   PN = "2"  !CDS_PN = "2";
BODY = "Q_RES","I73": #LOCATION = "R6210" !CDS_LOCATION = "R6210" &SEC = "1" #&CDS_SEC = "1";
"A":   PN = "1"  !CDS_PN = "1";
"B":   PN = "2"  !CDS_PN = "2";
BODY = "Q_RES","I74": #LOCATION = "R353" !CDS_LOCATION = "R353" &SEC = "1" #&CDS_SEC = "1";
"A":   PN = "1"  !CDS_PN = "1";
"B":   PN = "2"  !CDS_PN = "2";
BODY = "Q_RES","I76": #LOCATION = "R354" !CDS_LOCATION = "R354" &SEC = "1" #&CDS_SEC = "1";
"A":   PN = "1"  !CDS_PN = "1";
"B":   PN = "2"  !CDS_PN = "2";
BODY = "Q_RES","I79": #LOCATION = "R355" !CDS_LOCATION = "R355" &SEC = "1" #&CDS_SEC = "1";
"A":   PN = "1"  !CDS_PN = "1";
"B":   PN = "2"  !CDS_PN = "2";
BODY = "Q_RES","I81": #LOCATION = "R8107" !CDS_LOCATION = "R8107" &SEC = "1" #&CDS_SEC = "1";
"A":   PN = "1"  !CDS_PN = "1";
"B":   PN = "2"  !CDS_PN = "2";
BODY = "Q_RES","I82": #LOCATION = "R8109" !CDS_LOCATION = "R8109" &SEC = "1" #&CDS_SEC = "1";
"A":   PN = "1"  !CDS_PN = "1";
"B":   PN = "2"  !CDS_PN = "2";
BODY = "Q_RES","I84": #LOCATION = "R8108" !CDS_LOCATION = "R8108" &SEC = "1" #&CDS_SEC = "1";
"A":   PN = "1"  !CDS_PN = "1";
"B":   PN = "2"  !CDS_PN = "2";
BODY = "Q_CAP","I87": #LOCATION = "C8014" !CDS_LOCATION = "C8014" &SEC = "1" #&CDS_SEC = "1";
"A":   PN = "1"  !CDS_PN = "1";
"B":   PN = "2"  !CDS_PN = "2";
BODY = "Q_CAP","I89": #LOCATION = "C8015" !CDS_LOCATION = "C8015" &SEC = "1" #&CDS_SEC = "1";
"A":   PN = "1"  !CDS_PN = "1";
"B":   PN = "2"  !CDS_PN = "2";
BODY = "Q_CAP","I95": #LOCATION = "C8016" !CDS_LOCATION = "C8016" &SEC = "1" #&CDS_SEC = "1";
"A":   PN = "1"  !CDS_PN = "1";
"B":   PN = "2"  !CDS_PN = "2";
BODY = "Q_RES","I96": #LOCATION = "R8110" !CDS_LOCATION = "R8110" &SEC = "1" #&CDS_SEC = "1";
"A":   PN = "1"  !CDS_PN = "1";
"B":   PN = "2"  !CDS_PN = "2";
BODY = "Q_RES","I98": #LOCATION = "R8111" !CDS_LOCATION = "R8111" &SEC = "1" #&CDS_SEC = "1";
"A":   PN = "1"  !CDS_PN = "1";
"B":   PN = "2"  !CDS_PN = "2";
BODY = "LM4040AIM3X25NOPB","I101": #LOCATION = "U8005" !CDS_LOCATION = "U8005" &SEC = "1" #&CDS_SEC = "1";
"1+":   PN = "1"  !CDS_PN = "1";
"2-":   PN = "2"  !CDS_PN = "2";
"3":   PN = "3"  !CDS_PN = "3";
BODY = "Q_RES","I103": #LOCATION = "R8112" !CDS_LOCATION = "R8112" &SEC = "1" #&CDS_SEC = "1";
"A":   PN = "1"  !CDS_PN = "1";
"B":   PN = "2"  !CDS_PN = "2";
BODY = "AP331AWG7","I104": #LOCATION = "U8006" !CDS_LOCATION = "U8006" &SEC = "1" #&CDS_SEC = "1";
"GND":   PN = "2"  !CDS_PN = "2";
"IN+":   PN = "3"  !CDS_PN = "3";
"IN-":   PN = "1"  !CDS_PN = "1";
"OUTPUT":   PN = "4"  !CDS_PN = "4";
"VCC":   PN = "5"  !CDS_PN = "5";
BODY = "Q_CAP","I107": #LOCATION = "C6084" !CDS_LOCATION = "C6084" &SEC = "1" #&CDS_SEC = "1";
"A":   PN = "1"  !CDS_PN = "1";
"B":   PN = "2"  !CDS_PN = "2";
BODY = "Q_RES","I108": #LOCATION = "R9020" !CDS_LOCATION = "R9020" &SEC = "1" #&CDS_SEC = "1";
"A":   PN = "1"  !CDS_PN = "1";
"B":   PN = "2"  !CDS_PN = "2";
BODY = "Q_CAP","I110": #LOCATION = "C9003" !CDS_LOCATION = "C9003" &SEC = "1" #&CDS_SEC = "1";
"A":   PN = "1"  !CDS_PN = "1";
"B":   PN = "2"  !CDS_PN = "2";
BODY = "Q_RES","I113": #LOCATION = "R9024" !CDS_LOCATION = "R9024" #SEC = "1" !CDS_SEC = "1";
"A":   PN = "1"  !CDS_PN = "1";
"B":   PN = "2"  !CDS_PN = "2";
DRAWING = "@t6g_mb_lib.t6g(sch_1):page264";
BODY = "Q_RES","I5": #LOCATION = "R1459" !CDS_LOCATION = "R1459" &SEC = "1" #&CDS_SEC = "1";
"A":   PN = "1"  !CDS_PN = "1";
"B":   PN = "2"  !CDS_PN = "2";
BODY = "Q_RES","I6": #LOCATION = "R1458" !CDS_LOCATION = "R1458" &SEC = "1" #&CDS_SEC = "1";
"A":   PN = "1"  !CDS_PN = "1";
"B":   PN = "2"  !CDS_PN = "2";
BODY = "SN74LVC1G11DCKR","I8": #LOCATION = "U38" !CDS_LOCATION = "U38" &SEC = "1" #&CDS_SEC = "1";
"A":   PN = "1"  !CDS_PN = "1";
"B":   PN = "3"  !CDS_PN = "3";
"C":   PN = "6"  !CDS_PN = "6";
"GND":   PN = "2"  !CDS_PN = "2";
"VCC":   PN = "5"  !CDS_PN = "5";
"Y":   PN = "4"  !CDS_PN = "4";
BODY = "Q_RES","I17": #LOCATION = "R1363" !CDS_LOCATION = "R1363" &SEC = "1" #&CDS_SEC = "1";
"A":   PN = "1"  !CDS_PN = "1";
"B":   PN = "2"  !CDS_PN = "2";
BODY = "Q_RES","I24": #LOCATION = "R1441" !CDS_LOCATION = "R1441" &SEC = "1" #&CDS_SEC = "1";
"A":   PN = "1"  !CDS_PN = "1";
"B":   PN = "2"  !CDS_PN = "2";
BODY = "Q_RES","I25": #LOCATION = "R1440" !CDS_LOCATION = "R1440" &SEC = "1" #&CDS_SEC = "1";
"A":   PN = "1"  !CDS_PN = "1";
"B":   PN = "2"  !CDS_PN = "2";
BODY = "Q_RES","I26": #LOCATION = "R1449" !CDS_LOCATION = "R1449" &SEC = "1" #&CDS_SEC = "1";
"A":   PN = "1"  !CDS_PN = "1";
"B":   PN = "2"  !CDS_PN = "2";
BODY = "Q_RES","I27": #LOCATION = "R1443" !CDS_LOCATION = "R1443" &SEC = "1" #&CDS_SEC = "1";
"A":   PN = "1"  !CDS_PN = "1";
"B":   PN = "2"  !CDS_PN = "2";
BODY = "Q_RES","I30": #LOCATION = "R1442" !CDS_LOCATION = "R1442" &SEC = "1" #&CDS_SEC = "1";
"A":   PN = "1"  !CDS_PN = "1";
"B":   PN = "2"  !CDS_PN = "2";
BODY = "BSS138DW7F","I33": #LOCATION = "Q19" !CDS_LOCATION = "Q19" &SEC = "1" #&CDS_SEC = "1";
"D1":   PN = "6"  !CDS_PN = "6";
"D2":   PN = "3"  !CDS_PN = "3";
"G1":   PN = "2"  !CDS_PN = "2";
"G2":   PN = "5"  !CDS_PN = "5";
"S1":   PN = "1"  !CDS_PN = "1";
"S2":   PN = "4"  !CDS_PN = "4";
BODY = "BSS138DW7F","I36": #LOCATION = "Q18" !CDS_LOCATION = "Q18" &SEC = "1" #&CDS_SEC = "1";
"D1":   PN = "6"  !CDS_PN = "6";
"D2":   PN = "3"  !CDS_PN = "3";
"G1":   PN = "2"  !CDS_PN = "2";
"G2":   PN = "5"  !CDS_PN = "5";
"S1":   PN = "1"  !CDS_PN = "1";
"S2":   PN = "4"  !CDS_PN = "4";
BODY = "Q_RES","I39": #LOCATION = "R1450" !CDS_LOCATION = "R1450" &SEC = "1" #&CDS_SEC = "1";
"A":   PN = "1"  !CDS_PN = "1";
"B":   PN = "2"  !CDS_PN = "2";
BODY = "Q_RES","I41": #LOCATION = "R1457" !CDS_LOCATION = "R1457" &SEC = "1" #&CDS_SEC = "1";
"A":   PN = "1"  !CDS_PN = "1";
"B":   PN = "2"  !CDS_PN = "2";
BODY = "Q_RES","I43": #LOCATION = "R1452" !CDS_LOCATION = "R1452" &SEC = "1" #&CDS_SEC = "1";
"A":   PN = "1"  !CDS_PN = "1";
"B":   PN = "2"  !CDS_PN = "2";
BODY = "Q_CAP","I47": #LOCATION = "C347" !CDS_LOCATION = "C347" &SEC = "1" #&CDS_SEC = "1";
"A":   PN = "1"  !CDS_PN = "1";
"B":   PN = "2"  !CDS_PN = "2";
BODY = "Q_CAP","I49": #LOCATION = "C5014" !CDS_LOCATION = "C5014" &SEC = "1" #&CDS_SEC = "1";
"A":   PN = "1"  !CDS_PN = "1";
"B":   PN = "2"  !CDS_PN = "2";
BODY = "Q_RES","I51": #LOCATION = "R6504" !CDS_LOCATION = "R6504" &SEC = "1" #&CDS_SEC = "1";
"A":   PN = "1"  !CDS_PN = "1";
"B":   PN = "2"  !CDS_PN = "2";
BODY = "Q_RES_4P_12","I54": #LOCATION = "R1837" !CDS_LOCATION = "R1837" &SEC = "1" #&CDS_SEC = "1";
"1":   PN = "1"  !CDS_PN = "1";
"2":   PN = "2"  !CDS_PN = "2";
"3":   PN = "3"  !CDS_PN = "3";
"4":   PN = "4"  !CDS_PN = "4";
BODY = "Q_RES_4P_12","I58": #LOCATION = "R1838" !CDS_LOCATION = "R1838" &SEC = "1" #&CDS_SEC = "1";
"1":   PN = "1"  !CDS_PN = "1";
"2":   PN = "2"  !CDS_PN = "2";
"3":   PN = "3"  !CDS_PN = "3";
"4":   PN = "4"  !CDS_PN = "4";
DRAWING = "@t6g_mb_lib.t6g(sch_1):page265";
BODY = "TDR_3P","I2": #LOCATION = "DB6" !CDS_LOCATION = "DB6" &SEC = "1" #&CDS_SEC = "1";
"GND":   PN = "1"  !CDS_PN = "1";
"IO1":   PN = "2"  !CDS_PN = "2";
"IO2":   PN = "3"  !CDS_PN = "3";
BODY = "TDR_3P","I5": #LOCATION = "DB14" !CDS_LOCATION = "DB14" &SEC = "1" #&CDS_SEC = "1";
"GND":   PN = "1"  !CDS_PN = "1";
"IO1":   PN = "2"  !CDS_PN = "2";
"IO2":   PN = "3"  !CDS_PN = "3";
BODY = "TDR_3P","I8": #LOCATION = "DB13" !CDS_LOCATION = "DB13" &SEC = "1" #&CDS_SEC = "1";
"GND":   PN = "1"  !CDS_PN = "1";
"IO1":   PN = "2"  !CDS_PN = "2";
"IO2":   PN = "3"  !CDS_PN = "3";
BODY = "TDR_3P","I9": #LOCATION = "DB5" !CDS_LOCATION = "DB5" &SEC = "1" #&CDS_SEC = "1";
"GND":   PN = "1"  !CDS_PN = "1";
"IO1":   PN = "2"  !CDS_PN = "2";
"IO2":   PN = "3"  !CDS_PN = "3";
BODY = "TDR_3P","I12": #LOCATION = "DB4" !CDS_LOCATION = "DB4" &SEC = "1" #&CDS_SEC = "1";
"GND":   PN = "1"  !CDS_PN = "1";
"IO1":   PN = "2"  !CDS_PN = "2";
"IO2":   PN = "3"  !CDS_PN = "3";
BODY = "TDR_3P","I13": #LOCATION = "DB3" !CDS_LOCATION = "DB3" &SEC = "1" #&CDS_SEC = "1";
"GND":   PN = "1"  !CDS_PN = "1";
"IO1":   PN = "2"  !CDS_PN = "2";
"IO2":   PN = "3"  !CDS_PN = "3";
BODY = "TDR_3P","I15": #LOCATION = "DB2" !CDS_LOCATION = "DB2" &SEC = "1" #&CDS_SEC = "1";
"GND":   PN = "1"  !CDS_PN = "1";
"IO1":   PN = "2"  !CDS_PN = "2";
"IO2":   PN = "3"  !CDS_PN = "3";
BODY = "TDR_3P","I16": #LOCATION = "DB1" !CDS_LOCATION = "DB1" &SEC = "1" #&CDS_SEC = "1";
"GND":   PN = "1"  !CDS_PN = "1";
"IO1":   PN = "2"  !CDS_PN = "2";
"IO2":   PN = "3"  !CDS_PN = "3";
BODY = "TDR_3P","I18": #LOCATION = "DB12" !CDS_LOCATION = "DB12" &SEC = "1" #&CDS_SEC = "1";
"GND":   PN = "1"  !CDS_PN = "1";
"IO1":   PN = "2"  !CDS_PN = "2";
"IO2":   PN = "3"  !CDS_PN = "3";
BODY = "TDR_3P","I20": #LOCATION = "DB16" !CDS_LOCATION = "DB16" &SEC = "1" #&CDS_SEC = "1";
"GND":   PN = "1"  !CDS_PN = "1";
"IO1":   PN = "2"  !CDS_PN = "2";
"IO2":   PN = "3"  !CDS_PN = "3";
BODY = "TDR_3P","I22": #LOCATION = "DB15" !CDS_LOCATION = "DB15" &SEC = "1" #&CDS_SEC = "1";
"GND":   PN = "1"  !CDS_PN = "1";
"IO1":   PN = "2"  !CDS_PN = "2";
"IO2":   PN = "3"  !CDS_PN = "3";
BODY = "TDR_3P","I25": #LOCATION = "DB11" !CDS_LOCATION = "DB11" &SEC = "1" #&CDS_SEC = "1";
"GND":   PN = "1"  !CDS_PN = "1";
"IO1":   PN = "2"  !CDS_PN = "2";
"IO2":   PN = "3"  !CDS_PN = "3";
BODY = "TP_TDR_4P_FTS","I29": #LOCATION = "X6" !CDS_LOCATION = "X6" &SEC = "1" #&CDS_SEC = "1";
"P1":   PN = "2"  !CDS_PN = "2";
"P2":   PN = "3"  !CDS_PN = "3";
"S1":   PN = "1"  !CDS_PN = "1";
"S2":   PN = "4"  !CDS_PN = "4";
BODY = "TP_TDR_4P_FTS","I30": #LOCATION = "X26" !CDS_LOCATION = "X26" &SEC = "1" #&CDS_SEC = "1";
"P1":   PN = "2"  !CDS_PN = "2";
"P2":   PN = "3"  !CDS_PN = "3";
"S1":   PN = "1"  !CDS_PN = "1";
"S2":   PN = "4"  !CDS_PN = "4";
BODY = "TP_TDR_4P_FTS","I31": #LOCATION = "X25" !CDS_LOCATION = "X25" &SEC = "1" #&CDS_SEC = "1";
"P1":   PN = "2"  !CDS_PN = "2";
"P2":   PN = "3"  !CDS_PN = "3";
"S1":   PN = "1"  !CDS_PN = "1";
"S2":   PN = "4"  !CDS_PN = "4";
BODY = "TP_TDR_4P_FTS","I35": #LOCATION = "X5" !CDS_LOCATION = "X5" &SEC = "1" #&CDS_SEC = "1";
"P1":   PN = "2"  !CDS_PN = "2";
"P2":   PN = "3"  !CDS_PN = "3";
"S1":   PN = "1"  !CDS_PN = "1";
"S2":   PN = "4"  !CDS_PN = "4";
BODY = "TP_TDR_4P_FTS","I36": #LOCATION = "X4" !CDS_LOCATION = "X4" &SEC = "1" #&CDS_SEC = "1";
"P1":   PN = "2"  !CDS_PN = "2";
"P2":   PN = "3"  !CDS_PN = "3";
"S1":   PN = "1"  !CDS_PN = "1";
"S2":   PN = "4"  !CDS_PN = "4";
BODY = "TP_TDR_4P_FTS","I37": #LOCATION = "X3" !CDS_LOCATION = "X3" &SEC = "1" #&CDS_SEC = "1";
"P1":   PN = "2"  !CDS_PN = "2";
"P2":   PN = "3"  !CDS_PN = "3";
"S1":   PN = "1"  !CDS_PN = "1";
"S2":   PN = "4"  !CDS_PN = "4";
BODY = "TDR_3P","I38": #LOCATION = "DB10" !CDS_LOCATION = "DB10" &SEC = "1" #&CDS_SEC = "1";
"GND":   PN = "1"  !CDS_PN = "1";
"IO1":   PN = "2"  !CDS_PN = "2";
"IO2":   PN = "3"  !CDS_PN = "3";
BODY = "TDR_3P","I40": #LOCATION = "DB9" !CDS_LOCATION = "DB9" &SEC = "1" #&CDS_SEC = "1";
"GND":   PN = "1"  !CDS_PN = "1";
"IO1":   PN = "2"  !CDS_PN = "2";
"IO2":   PN = "3"  !CDS_PN = "3";
BODY = "TDR_3P","I42": #LOCATION = "DB8" !CDS_LOCATION = "DB8" &SEC = "1" #&CDS_SEC = "1";
"GND":   PN = "1"  !CDS_PN = "1";
"IO1":   PN = "2"  !CDS_PN = "2";
"IO2":   PN = "3"  !CDS_PN = "3";
BODY = "TDR_3P","I44": #LOCATION = "DB7" !CDS_LOCATION = "DB7" &SEC = "1" #&CDS_SEC = "1";
"GND":   PN = "1"  !CDS_PN = "1";
"IO1":   PN = "2"  !CDS_PN = "2";
"IO2":   PN = "3"  !CDS_PN = "3";
BODY = "TP_TDR_4P_FTS","I47": #LOCATION = "X2" !CDS_LOCATION = "X2" &SEC = "1" #&CDS_SEC = "1";
"P1":   PN = "2"  !CDS_PN = "2";
"P2":   PN = "3"  !CDS_PN = "3";
"S1":   PN = "1"  !CDS_PN = "1";
"S2":   PN = "4"  !CDS_PN = "4";
BODY = "TP_TDR_4P_FTS","I48": #LOCATION = "X1" !CDS_LOCATION = "X1" &SEC = "1" #&CDS_SEC = "1";
"P1":   PN = "2"  !CDS_PN = "2";
"P2":   PN = "3"  !CDS_PN = "3";
"S1":   PN = "1"  !CDS_PN = "1";
"S2":   PN = "4"  !CDS_PN = "4";
BODY = "TP_TDR_4P_FTS","I49": #LOCATION = "X12" !CDS_LOCATION = "X12" &SEC = "1" #&CDS_SEC = "1";
"P1":   PN = "2"  !CDS_PN = "2";
"P2":   PN = "3"  !CDS_PN = "3";
"S1":   PN = "1"  !CDS_PN = "1";
"S2":   PN = "4"  !CDS_PN = "4";
BODY = "TP_TDR_4P_FTS","I52": #LOCATION = "X28" !CDS_LOCATION = "X28" &SEC = "1" #&CDS_SEC = "1";
"P1":   PN = "2"  !CDS_PN = "2";
"P2":   PN = "3"  !CDS_PN = "3";
"S1":   PN = "1"  !CDS_PN = "1";
"S2":   PN = "4"  !CDS_PN = "4";
BODY = "TP_TDR_4P_FTS","I53": #LOCATION = "X27" !CDS_LOCATION = "X27" &SEC = "1" #&CDS_SEC = "1";
"P1":   PN = "2"  !CDS_PN = "2";
"P2":   PN = "3"  !CDS_PN = "3";
"S1":   PN = "1"  !CDS_PN = "1";
"S2":   PN = "4"  !CDS_PN = "4";
BODY = "TP_TDR_4P_FTS","I56": #LOCATION = "X8006" !CDS_LOCATION = "X8006" &SEC = "1" #&CDS_SEC = "1";
"P1":   PN = "2"  !CDS_PN = "2";
"P2":   PN = "3"  !CDS_PN = "3";
"S1":   PN = "1"  !CDS_PN = "1";
"S2":   PN = "4"  !CDS_PN = "4";
BODY = "TP_TDR_4P_FTS","I58": #LOCATION = "X8026" !CDS_LOCATION = "X8026" &SEC = "1" #&CDS_SEC = "1";
"P1":   PN = "2"  !CDS_PN = "2";
"P2":   PN = "3"  !CDS_PN = "3";
"S1":   PN = "1"  !CDS_PN = "1";
"S2":   PN = "4"  !CDS_PN = "4";
BODY = "TP_TDR_4P_FTS","I60": #LOCATION = "X8025" !CDS_LOCATION = "X8025" &SEC = "1" #&CDS_SEC = "1";
"P1":   PN = "2"  !CDS_PN = "2";
"P2":   PN = "3"  !CDS_PN = "3";
"S1":   PN = "1"  !CDS_PN = "1";
"S2":   PN = "4"  !CDS_PN = "4";
BODY = "TP_TDR_4P_FTS","I61": #LOCATION = "X10" !CDS_LOCATION = "X10" &SEC = "1" #&CDS_SEC = "1";
"P1":   PN = "2"  !CDS_PN = "2";
"P2":   PN = "3"  !CDS_PN = "3";
"S1":   PN = "1"  !CDS_PN = "1";
"S2":   PN = "4"  !CDS_PN = "4";
BODY = "TP_TDR_4P_FTS","I62": #LOCATION = "X9" !CDS_LOCATION = "X9" &SEC = "1" #&CDS_SEC = "1";
"P1":   PN = "2"  !CDS_PN = "2";
"P2":   PN = "3"  !CDS_PN = "3";
"S1":   PN = "1"  !CDS_PN = "1";
"S2":   PN = "4"  !CDS_PN = "4";
BODY = "TP_TDR_4P_FTS","I66": #LOCATION = "X8005" !CDS_LOCATION = "X8005" &SEC = "1" #&CDS_SEC = "1";
"P1":   PN = "2"  !CDS_PN = "2";
"P2":   PN = "3"  !CDS_PN = "3";
"S1":   PN = "1"  !CDS_PN = "1";
"S2":   PN = "4"  !CDS_PN = "4";
BODY = "TP_TDR_4P_FTS","I68": #LOCATION = "X8004" !CDS_LOCATION = "X8004" &SEC = "1" #&CDS_SEC = "1";
"P1":   PN = "2"  !CDS_PN = "2";
"P2":   PN = "3"  !CDS_PN = "3";
"S1":   PN = "1"  !CDS_PN = "1";
"S2":   PN = "4"  !CDS_PN = "4";
BODY = "TP_TDR_4P_FTS","I70": #LOCATION = "X8003" !CDS_LOCATION = "X8003" &SEC = "1" #&CDS_SEC = "1";
"P1":   PN = "2"  !CDS_PN = "2";
"P2":   PN = "3"  !CDS_PN = "3";
"S1":   PN = "1"  !CDS_PN = "1";
"S2":   PN = "4"  !CDS_PN = "4";
BODY = "TP_TDR_4P_FTS","I73": #LOCATION = "X8028" !CDS_LOCATION = "X8028" &SEC = "1" #&CDS_SEC = "1";
"P1":   PN = "2"  !CDS_PN = "2";
"P2":   PN = "3"  !CDS_PN = "3";
"S1":   PN = "1"  !CDS_PN = "1";
"S2":   PN = "4"  !CDS_PN = "4";
BODY = "TP_TDR_4P_FTS","I74": #LOCATION = "X8027" !CDS_LOCATION = "X8027" &SEC = "1" #&CDS_SEC = "1";
"P1":   PN = "2"  !CDS_PN = "2";
"P2":   PN = "3"  !CDS_PN = "3";
"S1":   PN = "1"  !CDS_PN = "1";
"S2":   PN = "4"  !CDS_PN = "4";
BODY = "TP_TDR_4P_FTS","I76": #LOCATION = "X8011" !CDS_LOCATION = "X8011" &SEC = "1" #&CDS_SEC = "1";
"P1":   PN = "2"  !CDS_PN = "2";
"P2":   PN = "3"  !CDS_PN = "3";
"S1":   PN = "1"  !CDS_PN = "1";
"S2":   PN = "4"  !CDS_PN = "4";
BODY = "TP_TDR_4P_FTS","I78": #LOCATION = "X8010" !CDS_LOCATION = "X8010" &SEC = "1" #&CDS_SEC = "1";
"P1":   PN = "2"  !CDS_PN = "2";
"P2":   PN = "3"  !CDS_PN = "3";
"S1":   PN = "1"  !CDS_PN = "1";
"S2":   PN = "4"  !CDS_PN = "4";
BODY = "TP_TDR_4P_FTS","I79": #LOCATION = "X8009" !CDS_LOCATION = "X8009" &SEC = "1" #&CDS_SEC = "1";
"P1":   PN = "2"  !CDS_PN = "2";
"P2":   PN = "3"  !CDS_PN = "3";
"S1":   PN = "1"  !CDS_PN = "1";
"S2":   PN = "4"  !CDS_PN = "4";
BODY = "TP_TDR_4P_FTS","I82": #LOCATION = "X8" !CDS_LOCATION = "X8" &SEC = "1" #&CDS_SEC = "1";
"P1":   PN = "2"  !CDS_PN = "2";
"P2":   PN = "3"  !CDS_PN = "3";
"S1":   PN = "1"  !CDS_PN = "1";
"S2":   PN = "4"  !CDS_PN = "4";
BODY = "TP_TDR_4P_FTS","I84": #LOCATION = "X7" !CDS_LOCATION = "X7" &SEC = "1" #&CDS_SEC = "1";
"P1":   PN = "2"  !CDS_PN = "2";
"P2":   PN = "3"  !CDS_PN = "3";
"S1":   PN = "1"  !CDS_PN = "1";
"S2":   PN = "4"  !CDS_PN = "4";
BODY = "TP_TDR_4P_FTS","I87": #LOCATION = "X8002" !CDS_LOCATION = "X8002" &SEC = "1" #&CDS_SEC = "1";
"P1":   PN = "2"  !CDS_PN = "2";
"P2":   PN = "3"  !CDS_PN = "3";
"S1":   PN = "1"  !CDS_PN = "1";
"S2":   PN = "4"  !CDS_PN = "4";
BODY = "TP_TDR_4P_FTS","I89": #LOCATION = "X8001" !CDS_LOCATION = "X8001" &SEC = "1" #&CDS_SEC = "1";
"P1":   PN = "2"  !CDS_PN = "2";
"P2":   PN = "3"  !CDS_PN = "3";
"S1":   PN = "1"  !CDS_PN = "1";
"S2":   PN = "4"  !CDS_PN = "4";
BODY = "TP_TDR_4P_FTS","I90": #LOCATION = "X8008" !CDS_LOCATION = "X8008" &SEC = "1" #&CDS_SEC = "1";
"P1":   PN = "2"  !CDS_PN = "2";
"P2":   PN = "3"  !CDS_PN = "3";
"S1":   PN = "1"  !CDS_PN = "1";
"S2":   PN = "4"  !CDS_PN = "4";
BODY = "TP_TDR_4P_FTS","I92": #LOCATION = "X8007" !CDS_LOCATION = "X8007" &SEC = "1" #&CDS_SEC = "1";
"P1":   PN = "2"  !CDS_PN = "2";
"P2":   PN = "3"  !CDS_PN = "3";
"S1":   PN = "1"  !CDS_PN = "1";
"S2":   PN = "4"  !CDS_PN = "4";
BODY = "TP_TDR_4P_FTS","I94": #LOCATION = "X8012" !CDS_LOCATION = "X8012" &SEC = "1" #&CDS_SEC = "1";
"P1":   PN = "2"  !CDS_PN = "2";
"P2":   PN = "3"  !CDS_PN = "3";
"S1":   PN = "1"  !CDS_PN = "1";
"S2":   PN = "4"  !CDS_PN = "4";
BODY = "TP_TDR_4P_FTS","I96": #LOCATION = "X11" !CDS_LOCATION = "X11" &SEC = "1" #&CDS_SEC = "1";
"P1":   PN = "2"  !CDS_PN = "2";
"P2":   PN = "3"  !CDS_PN = "3";
"S1":   PN = "1"  !CDS_PN = "1";
"S2":   PN = "4"  !CDS_PN = "4";
DRAWING = "@t6g_mb_lib.t6g(sch_1):page266";
BODY = "TP_TDR_4P_FTS","I2": #LOCATION = "X9026" !CDS_LOCATION = "X9026" &SEC = "1" #&CDS_SEC = "1";
"P1":   PN = "2"  !CDS_PN = "2";
"P2":   PN = "3"  !CDS_PN = "3";
"S1":   PN = "1"  !CDS_PN = "1";
"S2":   PN = "4"  !CDS_PN = "4";
BODY = "TP_TDR_4P_FTS","I4": #LOCATION = "X9025" !CDS_LOCATION = "X9025" &SEC = "1" #&CDS_SEC = "1";
"P1":   PN = "2"  !CDS_PN = "2";
"P2":   PN = "3"  !CDS_PN = "3";
"S1":   PN = "1"  !CDS_PN = "1";
"S2":   PN = "4"  !CDS_PN = "4";
BODY = "TP_TDR_4P_FTS","I7": #LOCATION = "X9005" !CDS_LOCATION = "X9005" &SEC = "1" #&CDS_SEC = "1";
"P1":   PN = "2"  !CDS_PN = "2";
"P2":   PN = "3"  !CDS_PN = "3";
"S1":   PN = "1"  !CDS_PN = "1";
"S2":   PN = "4"  !CDS_PN = "4";
BODY = "TP_TDR_4P_FTS","I8": #LOCATION = "X9004" !CDS_LOCATION = "X9004" &SEC = "1" #&CDS_SEC = "1";
"P1":   PN = "2"  !CDS_PN = "2";
"P2":   PN = "3"  !CDS_PN = "3";
"S1":   PN = "1"  !CDS_PN = "1";
"S2":   PN = "4"  !CDS_PN = "4";
BODY = "TP_TDR_4P_FTS","I10": #LOCATION = "X9003" !CDS_LOCATION = "X9003" &SEC = "1" #&CDS_SEC = "1";
"P1":   PN = "2"  !CDS_PN = "2";
"P2":   PN = "3"  !CDS_PN = "3";
"S1":   PN = "1"  !CDS_PN = "1";
"S2":   PN = "4"  !CDS_PN = "4";
BODY = "TP_TDR_4P_FTS","I12": #LOCATION = "X9002" !CDS_LOCATION = "X9002" &SEC = "1" #&CDS_SEC = "1";
"P1":   PN = "2"  !CDS_PN = "2";
"P2":   PN = "3"  !CDS_PN = "3";
"S1":   PN = "1"  !CDS_PN = "1";
"S2":   PN = "4"  !CDS_PN = "4";
BODY = "TP_TDR_4P_FTS","I13": #LOCATION = "X9028" !CDS_LOCATION = "X9028" &SEC = "1" #&CDS_SEC = "1";
"P1":   PN = "2"  !CDS_PN = "2";
"P2":   PN = "3"  !CDS_PN = "3";
"S1":   PN = "1"  !CDS_PN = "1";
"S2":   PN = "4"  !CDS_PN = "4";
BODY = "TP_TDR_4P_FTS","I15": #LOCATION = "X9027" !CDS_LOCATION = "X9027" &SEC = "1" #&CDS_SEC = "1";
"P1":   PN = "2"  !CDS_PN = "2";
"P2":   PN = "3"  !CDS_PN = "3";
"S1":   PN = "1"  !CDS_PN = "1";
"S2":   PN = "4"  !CDS_PN = "4";
BODY = "TP_TDR_4P_FTS","I16": #LOCATION = "X9010" !CDS_LOCATION = "X9010" &SEC = "1" #&CDS_SEC = "1";
"P1":   PN = "2"  !CDS_PN = "2";
"P2":   PN = "3"  !CDS_PN = "3";
"S1":   PN = "1"  !CDS_PN = "1";
"S2":   PN = "4"  !CDS_PN = "4";
BODY = "TP_TDR_4P_FTS","I17": #LOCATION = "X9011" !CDS_LOCATION = "X9011" &SEC = "1" #&CDS_SEC = "1";
"P1":   PN = "2"  !CDS_PN = "2";
"P2":   PN = "3"  !CDS_PN = "3";
"S1":   PN = "1"  !CDS_PN = "1";
"S2":   PN = "4"  !CDS_PN = "4";
BODY = "TP_TDR_4P_FTS","I37": #LOCATION = "X9009" !CDS_LOCATION = "X9009" &SEC = "1" #&CDS_SEC = "1";
"P1":   PN = "2"  !CDS_PN = "2";
"P2":   PN = "3"  !CDS_PN = "3";
"S1":   PN = "1"  !CDS_PN = "1";
"S2":   PN = "4"  !CDS_PN = "4";
BODY = "TP_TDR_4P_FTS","I38": #LOCATION = "X9008" !CDS_LOCATION = "X9008" &SEC = "1" #&CDS_SEC = "1";
"P1":   PN = "2"  !CDS_PN = "2";
"P2":   PN = "3"  !CDS_PN = "3";
"S1":   PN = "1"  !CDS_PN = "1";
"S2":   PN = "4"  !CDS_PN = "4";
DRAWING = "@t6g_mb_lib.t6g(sch_1):page153";
BODY = "CYUSB330468LTXI","I1": #LOCATION = "U6001" !CDS_LOCATION = "U6001" #SEC = "1" !CDS_SEC = "1";
"DS1_DM":   PN = "59"  !CDS_PN = "59";
"DS1_DP":   PN = "60"  !CDS_PN = "60";
"DS1_RXM":   PN = "50"  !CDS_PN = "50";
"DS1_RXP":   PN = "51"  !CDS_PN = "51";
"DS1_TXM":   PN = "48"  !CDS_PN = "48";
"DS1_TXP":   PN = "47"  !CDS_PN = "47";
"DS2_DM":   PN = "63"  !CDS_PN = "63";
"DS2_DP":   PN = "62"  !CDS_PN = "62";
"DS2_RXM":   PN = "44"  !CDS_PN = "44";
"DS2_RXP":   PN = "45"  !CDS_PN = "45";
"DS2_TXM":   PN = "42"  !CDS_PN = "42";
"DS2_TXP":   PN = "41"  !CDS_PN = "41";
"DS3_DM":   PN = "64"  !CDS_PN = "64";
"DS3_DP":   PN = "65"  !CDS_PN = "65";
"DS3_RXM":   PN = "36"  !CDS_PN = "36";
"DS3_RXP":   PN = "35"  !CDS_PN = "35";
"DS3_TXM":   PN = "39"  !CDS_PN = "39";
"DS3_TXP":   PN = "38"  !CDS_PN = "38";
"DS4_DM":   PN = "68"  !CDS_PN = "68";
"DS4_DP":   PN = "67"  !CDS_PN = "67";
"DS4_RXM":   PN = "14"  !CDS_PN = "14";
"DS4_RXP":   PN = "15"  !CDS_PN = "15";
"DS4_TXM":   PN = "12"  !CDS_PN = "12";
"DS4_TXP":   PN = "11"  !CDS_PN = "11";
"EPAD":   PN = "TH"  !CDS_PN = "TH";
"GND":   PN = "40"  !CDS_PN = "40";
"I2C_CLK":   PN = "32"  !CDS_PN = "32";
"I2C_DATA":   PN = "33"  !CDS_PN = "33";
"MODE_SEL0":   PN = "23"  !CDS_PN = "23";
"MODE_SEL1":   PN = "24"  !CDS_PN = "24";
"NC_25":   PN = "25"  !CDS_PN = "25";
"OVRCURR":   PN = "30"  !CDS_PN = "30";
"PWR_EN":   PN = "29"  !CDS_PN = "29";
"RESERVED1":   PN = "21"  !CDS_PN = "21";
"RESERVED2":   PN = "22"  !CDS_PN = "22";
"RESET#":   PN = "31"  !CDS_PN = "31";
"RREF_SS":   PN = "26"  !CDS_PN = "26";
"RREF_USB2":   PN = "2"  !CDS_PN = "2";
"SUSPEND":   PN = "20"  !CDS_PN = "20";
"US_DM":   PN = "58"  !CDS_PN = "58";
"US_DP":   PN = "57"  !CDS_PN = "57";
"US_RXM":   PN = "8"  !CDS_PN = "8";
"US_RXP":   PN = "9"  !CDS_PN = "9";
"US_TXM":   PN = "5"  !CDS_PN = "5";
"US_TXP":   PN = "6"  !CDS_PN = "6";
"VBUS_DS":   PN = "18"  !CDS_PN = "18";
"VBUS_US":   PN = "17"  !CDS_PN = "17";
"XTL_IN":   PN = "55"  !CDS_PN = "55";
"XTL_OUT":   PN = "54"  !CDS_PN = "54";
BODY = "Q_XTAL_4P_13BI_24GND","I14": #LOCATION = "Y9" !CDS_LOCATION = "Y9" #SEC = "1" !CDS_SEC = "1";
"G1":   PN = "2"  !CDS_PN = "2";
"G2":   PN = "4"  !CDS_PN = "4";
"X1":   PN = "1"  !CDS_PN = "1";
"X2":   PN = "3"  !CDS_PN = "3";
BODY = "Q_RES","I20": #LOCATION = "R4451" !CDS_LOCATION = "R4451" &SEC = "1" #&CDS_SEC = "1";
"A":   PN = "1"  !CDS_PN = "1";
"B":   PN = "2"  !CDS_PN = "2";
BODY = "Q_RES","I23": #LOCATION = "R4453" !CDS_LOCATION = "R4453" &SEC = "1" #&CDS_SEC = "1";
"A":   PN = "1"  !CDS_PN = "1";
"B":   PN = "2"  !CDS_PN = "2";
BODY = "Q_CAP","I25": #LOCATION = "C2317" !CDS_LOCATION = "C2317" &SEC = "1" #&CDS_SEC = "1";
"A":   PN = "1"  !CDS_PN = "1";
"B":   PN = "2"  !CDS_PN = "2";
BODY = "Q_RES","I27": #LOCATION = "R4450" !CDS_LOCATION = "R4450" &SEC = "1" #&CDS_SEC = "1";
"A":   PN = "1"  !CDS_PN = "1";
"B":   PN = "2"  !CDS_PN = "2";
BODY = "Q_CAP","I28": #LOCATION = "C6027" !CDS_LOCATION = "C6027" &SEC = "1" #&CDS_SEC = "1";
"A":   PN = "1"  !CDS_PN = "1";
"B":   PN = "2"  !CDS_PN = "2";
BODY = "Q_CAP","I29": #LOCATION = "C6028" !CDS_LOCATION = "C6028" &SEC = "1" #&CDS_SEC = "1";
"A":   PN = "1"  !CDS_PN = "1";
"B":   PN = "2"  !CDS_PN = "2";
BODY = "Q_RES","I37": #LOCATION = "R6202" !CDS_LOCATION = "R6202" &SEC = "1" #&CDS_SEC = "1";
"A":   PN = "1"  !CDS_PN = "1";
"B":   PN = "2"  !CDS_PN = "2";
BODY = "Q_RES","I39": #LOCATION = "R6203" !CDS_LOCATION = "R6203" &SEC = "1" #&CDS_SEC = "1";
"A":   PN = "1"  !CDS_PN = "1";
"B":   PN = "2"  !CDS_PN = "2";
BODY = "Q_RES","I41": #LOCATION = "R6204" !CDS_LOCATION = "R6204" &SEC = "1" #&CDS_SEC = "1";
"A":   PN = "1"  !CDS_PN = "1";
"B":   PN = "2"  !CDS_PN = "2";
BODY = "Q_RES","I43": #LOCATION = "R6205" !CDS_LOCATION = "R6205" &SEC = "1" #&CDS_SEC = "1";
"A":   PN = "1"  !CDS_PN = "1";
"B":   PN = "2"  !CDS_PN = "2";
BODY = "Q_RES","I44": #LOCATION = "R6206" !CDS_LOCATION = "R6206" &SEC = "1" #&CDS_SEC = "1";
"A":   PN = "1"  !CDS_PN = "1";
"B":   PN = "2"  !CDS_PN = "2";
BODY = "Q_RES","I45": #LOCATION = "R6207" !CDS_LOCATION = "R6207" &SEC = "1" #&CDS_SEC = "1";
"A":   PN = "1"  !CDS_PN = "1";
"B":   PN = "2"  !CDS_PN = "2";
BODY = "Q_RES","I47": #LOCATION = "R6208" !CDS_LOCATION = "R6208" &SEC = "1" #&CDS_SEC = "1";
"A":   PN = "1"  !CDS_PN = "1";
"B":   PN = "2"  !CDS_PN = "2";
BODY = "Q_RES","I48": #LOCATION = "R6209" !CDS_LOCATION = "R6209" &SEC = "1" #&CDS_SEC = "1";
"A":   PN = "1"  !CDS_PN = "1";
"B":   PN = "2"  !CDS_PN = "2";
BODY = "M24128BWMN6TP","I64": #LOCATION = "U6003" !CDS_LOCATION = "U6003" #SEC = "1" !CDS_SEC = "1";
"E0":   PN = "1"  !CDS_PN = "1";
"E1":   PN = "2"  !CDS_PN = "2";
"E2":   PN = "3"  !CDS_PN = "3";
"SCL":   PN = "6"  !CDS_PN = "6";
"SDA":   PN = "5"  !CDS_PN = "5";
"VCC":   PN = "8"  !CDS_PN = "8";
"VSS":   PN = "4"  !CDS_PN = "4";
"WC#":   PN = "7"  !CDS_PN = "7";
BODY = "Q_RES","I65": #LOCATION = "R6222" !CDS_LOCATION = "R6222" &SEC = "1" #&CDS_SEC = "1";
"A":   PN = "1"  !CDS_PN = "1";
"B":   PN = "2"  !CDS_PN = "2";
BODY = "Q_RES","I66": #LOCATION = "R6219" !CDS_LOCATION = "R6219" &SEC = "1" #&CDS_SEC = "1";
"A":   PN = "1"  !CDS_PN = "1";
"B":   PN = "2"  !CDS_PN = "2";
BODY = "Q_RES","I67": #LOCATION = "R6221" !CDS_LOCATION = "R6221" &SEC = "1" #&CDS_SEC = "1";
"A":   PN = "1"  !CDS_PN = "1";
"B":   PN = "2"  !CDS_PN = "2";
BODY = "Q_RES","I68": #LOCATION = "R6217" !CDS_LOCATION = "R6217" &SEC = "1" #&CDS_SEC = "1";
"A":   PN = "1"  !CDS_PN = "1";
"B":   PN = "2"  !CDS_PN = "2";
BODY = "Q_RES","I69": #LOCATION = "R6218" !CDS_LOCATION = "R6218" &SEC = "1" #&CDS_SEC = "1";
"A":   PN = "1"  !CDS_PN = "1";
"B":   PN = "2"  !CDS_PN = "2";
BODY = "Q_RES","I70": #LOCATION = "R6220" !CDS_LOCATION = "R6220" &SEC = "1" #&CDS_SEC = "1";
"A":   PN = "1"  !CDS_PN = "1";
"B":   PN = "2"  !CDS_PN = "2";
BODY = "Q_CAP","I75": #LOCATION = "C6083" !CDS_LOCATION = "C6083" &SEC = "1" #&CDS_SEC = "1";
"A":   PN = "1"  !CDS_PN = "1";
"B":   PN = "2"  !CDS_PN = "2";
BODY = "Q_RES","I77": #LOCATION = "R6223" !CDS_LOCATION = "R6223" &SEC = "1" #&CDS_SEC = "1";
"A":   PN = "1"  !CDS_PN = "1";
"B":   PN = "2"  !CDS_PN = "2";
BODY = "Q_RES","I83": #LOCATION = "R6225" !CDS_LOCATION = "R6225" &SEC = "1" #&CDS_SEC = "1";
"A":   PN = "1"  !CDS_PN = "1";
"B":   PN = "2"  !CDS_PN = "2";
BODY = "Q_RES","I84": #LOCATION = "R6224" !CDS_LOCATION = "R6224" &SEC = "1" #&CDS_SEC = "1";
"A":   PN = "1"  !CDS_PN = "1";
"B":   PN = "2"  !CDS_PN = "2";
BODY = "Q_RES","I85": #LOCATION = "R6226" !CDS_LOCATION = "R6226" #SEC = "1" !CDS_SEC = "1";
"A":   PN = "1"  !CDS_PN = "1";
"B":   PN = "2"  !CDS_PN = "2";
BODY = "Q_RES","I86": #LOCATION = "R6227" !CDS_LOCATION = "R6227" #SEC = "1" !CDS_SEC = "1";
"A":   PN = "1"  !CDS_PN = "1";
"B":   PN = "2"  !CDS_PN = "2";
BODY = "Q_RES","I87": #LOCATION = "R6213" !CDS_LOCATION = "R6213" &SEC = "1" #&CDS_SEC = "1";
"A":   PN = "1"  !CDS_PN = "1";
"B":   PN = "2"  !CDS_PN = "2";
BODY = "Q_RES","I88": #LOCATION = "R6214" !CDS_LOCATION = "R6214" &SEC = "1" #&CDS_SEC = "1";
"A":   PN = "1"  !CDS_PN = "1";
"B":   PN = "2"  !CDS_PN = "2";
BODY = "Q_RES","I89": #LOCATION = "R6215" !CDS_LOCATION = "R6215" &SEC = "1" #&CDS_SEC = "1";
"A":   PN = "1"  !CDS_PN = "1";
"B":   PN = "2"  !CDS_PN = "2";
BODY = "Q_RES","I90": #LOCATION = "R6216" !CDS_LOCATION = "R6216" &SEC = "1" #&CDS_SEC = "1";
"A":   PN = "1"  !CDS_PN = "1";
"B":   PN = "2"  !CDS_PN = "2";
BODY = "Q_CAP","I92": #LOCATION = "C91" !CDS_LOCATION = "C91" &SEC = "1" #&CDS_SEC = "1";
"A":   PN = "1"  !CDS_PN = "1";
"B":   PN = "2"  !CDS_PN = "2";
BODY = "Q_RES","I93": #LOCATION = "R4452" !CDS_LOCATION = "R4452" &SEC = "1" #&CDS_SEC = "1";
"A":   PN = "1"  !CDS_PN = "1";
"B":   PN = "2"  !CDS_PN = "2";
BODY = "Q_CAP","I91": #LOCATION = "C93" !CDS_LOCATION = "C93" &SEC = "1" #&CDS_SEC = "1";
"A":   PN = "1"  !CDS_PN = "1";
"B":   PN = "2"  !CDS_PN = "2";
DRAWING = "@t6g_mb_lib.t6g(sch_1):page154";
BODY = "CYUSB330468LTXI","I1": #LOCATION = "U6001" !CDS_LOCATION = "U6001" &SEC = "2" #&CDS_SEC = "2";
"AVDD12_1":   PN = "10"  !CDS_PN = "10";
"AVDD12_2":   PN = "16"  !CDS_PN = "16";
"AVDD12_3":   PN = "34"  !CDS_PN = "34";
"AVDD12_4":   PN = "46"  !CDS_PN = "46";
"AVDD12_5":   PN = "52"  !CDS_PN = "52";
"AVDD12_6":   PN = "53"  !CDS_PN = "53";
"AVDD33_1":   PN = "4"  !CDS_PN = "4";
"AVDD33_2":   PN = "56"  !CDS_PN = "56";
"AVDD33_3":   PN = "61"  !CDS_PN = "61";
"AVDD33_4":   PN = "66"  !CDS_PN = "66";
"DVDD12_1":   PN = "1"  !CDS_PN = "1";
"DVDD12_2":   PN = "3"  !CDS_PN = "3";
"DVDD12_3":   PN = "27"  !CDS_PN = "27";
"DVDD12_4":   PN = "49"  !CDS_PN = "49";
"DVDD12_5":   PN = "7"  !CDS_PN = "7";
"DVDD12_6":   PN = "13"  !CDS_PN = "13";
"DVDD12_7":   PN = "37"  !CDS_PN = "37";
"DVDD12_8":   PN = "43"  !CDS_PN = "43";
"VDD_EFUSE":   PN = "19"  !CDS_PN = "19";
"VDD_IO":   PN = "28"  !CDS_PN = "28";
BODY = "Q_INDUCTOR","I3": #LOCATION = "L6000" !CDS_LOCATION = "L6000" &SEC = "1" #&CDS_SEC = "1";
"1":   PN = "1"  !CDS_PN = "1";
"2":   PN = "2"  !CDS_PN = "2";
BODY = "Q_CAP","I5": #LOCATION = "C6040" !CDS_LOCATION = "C6040" &SEC = "1" #&CDS_SEC = "1";
"A":   PN = "1"  !CDS_PN = "1";
"B":   PN = "2"  !CDS_PN = "2";
BODY = "Q_CAP","I7": #LOCATION = "C6041" !CDS_LOCATION = "C6041" &SEC = "1" #&CDS_SEC = "1";
"A":   PN = "1"  !CDS_PN = "1";
"B":   PN = "2"  !CDS_PN = "2";
BODY = "Q_CAP","I9": #LOCATION = "C6042" !CDS_LOCATION = "C6042" &SEC = "1" #&CDS_SEC = "1";
"A":   PN = "1"  !CDS_PN = "1";
"B":   PN = "2"  !CDS_PN = "2";
BODY = "Q_CAP","I10": #LOCATION = "C6043" !CDS_LOCATION = "C6043" &SEC = "1" #&CDS_SEC = "1";
"A":   PN = "1"  !CDS_PN = "1";
"B":   PN = "2"  !CDS_PN = "2";
BODY = "Q_CAP","I12": #LOCATION = "C6044" !CDS_LOCATION = "C6044" &SEC = "1" #&CDS_SEC = "1";
"A":   PN = "1"  !CDS_PN = "1";
"B":   PN = "2"  !CDS_PN = "2";
BODY = "Q_CAP","I13": #LOCATION = "C6045" !CDS_LOCATION = "C6045" &SEC = "1" #&CDS_SEC = "1";
"A":   PN = "1"  !CDS_PN = "1";
"B":   PN = "2"  !CDS_PN = "2";
BODY = "Q_CAP","I14": #LOCATION = "C6046" !CDS_LOCATION = "C6046" &SEC = "1" #&CDS_SEC = "1";
"A":   PN = "1"  !CDS_PN = "1";
"B":   PN = "2"  !CDS_PN = "2";
BODY = "Q_CAP","I15": #LOCATION = "C6047" !CDS_LOCATION = "C6047" &SEC = "1" #&CDS_SEC = "1";
"A":   PN = "1"  !CDS_PN = "1";
"B":   PN = "2"  !CDS_PN = "2";
BODY = "Q_CAP","I17": #LOCATION = "C6048" !CDS_LOCATION = "C6048" &SEC = "1" #&CDS_SEC = "1";
"A":   PN = "1"  !CDS_PN = "1";
"B":   PN = "2"  !CDS_PN = "2";
BODY = "Q_CAP","I19": #LOCATION = "C6049" !CDS_LOCATION = "C6049" &SEC = "1" #&CDS_SEC = "1";
"A":   PN = "1"  !CDS_PN = "1";
"B":   PN = "2"  !CDS_PN = "2";
BODY = "Q_CAP","I20": #LOCATION = "C6050" !CDS_LOCATION = "C6050" &SEC = "1" #&CDS_SEC = "1";
"A":   PN = "1"  !CDS_PN = "1";
"B":   PN = "2"  !CDS_PN = "2";
BODY = "Q_CAP","I21": #LOCATION = "C6051" !CDS_LOCATION = "C6051" &SEC = "1" #&CDS_SEC = "1";
"A":   PN = "1"  !CDS_PN = "1";
"B":   PN = "2"  !CDS_PN = "2";
BODY = "Q_CAP","I22": #LOCATION = "C6053" !CDS_LOCATION = "C6053" &SEC = "1" #&CDS_SEC = "1";
"A":   PN = "1"  !CDS_PN = "1";
"B":   PN = "2"  !CDS_PN = "2";
BODY = "Q_CAP","I23": #LOCATION = "C6052" !CDS_LOCATION = "C6052" &SEC = "1" #&CDS_SEC = "1";
"A":   PN = "1"  !CDS_PN = "1";
"B":   PN = "2"  !CDS_PN = "2";
BODY = "Q_INDUCTOR","I26": #LOCATION = "L6001" !CDS_LOCATION = "L6001" &SEC = "1" #&CDS_SEC = "1";
"1":   PN = "1"  !CDS_PN = "1";
"2":   PN = "2"  !CDS_PN = "2";
BODY = "Q_CAP","I27": #LOCATION = "C6030" !CDS_LOCATION = "C6030" &SEC = "1" #&CDS_SEC = "1";
"A":   PN = "1"  !CDS_PN = "1";
"B":   PN = "2"  !CDS_PN = "2";
BODY = "Q_CAP","I29": #LOCATION = "C6031" !CDS_LOCATION = "C6031" &SEC = "1" #&CDS_SEC = "1";
"A":   PN = "1"  !CDS_PN = "1";
"B":   PN = "2"  !CDS_PN = "2";
BODY = "Q_CAP","I31": #LOCATION = "C6035" !CDS_LOCATION = "C6035" &SEC = "1" #&CDS_SEC = "1";
"A":   PN = "1"  !CDS_PN = "1";
"B":   PN = "2"  !CDS_PN = "2";
BODY = "Q_CAP","I32": #LOCATION = "C6034" !CDS_LOCATION = "C6034" &SEC = "1" #&CDS_SEC = "1";
"A":   PN = "1"  !CDS_PN = "1";
"B":   PN = "2"  !CDS_PN = "2";
BODY = "Q_CAP","I34": #LOCATION = "C6033" !CDS_LOCATION = "C6033" &SEC = "1" #&CDS_SEC = "1";
"A":   PN = "1"  !CDS_PN = "1";
"B":   PN = "2"  !CDS_PN = "2";
BODY = "Q_CAP","I35": #LOCATION = "C6032" !CDS_LOCATION = "C6032" &SEC = "1" #&CDS_SEC = "1";
"A":   PN = "1"  !CDS_PN = "1";
"B":   PN = "2"  !CDS_PN = "2";
BODY = "Q_CAP","I37": #LOCATION = "C6036" !CDS_LOCATION = "C6036" &SEC = "1" #&CDS_SEC = "1";
"A":   PN = "1"  !CDS_PN = "1";
"B":   PN = "2"  !CDS_PN = "2";
BODY = "Q_CAP","I38": #LOCATION = "C6037" !CDS_LOCATION = "C6037" &SEC = "1" #&CDS_SEC = "1";
"A":   PN = "1"  !CDS_PN = "1";
"B":   PN = "2"  !CDS_PN = "2";
BODY = "Q_CAP","I40": #LOCATION = "C6039" !CDS_LOCATION = "C6039" &SEC = "1" #&CDS_SEC = "1";
"A":   PN = "1"  !CDS_PN = "1";
"B":   PN = "2"  !CDS_PN = "2";
BODY = "Q_CAP","I41": #LOCATION = "C6038" !CDS_LOCATION = "C6038" &SEC = "1" #&CDS_SEC = "1";
"A":   PN = "1"  !CDS_PN = "1";
"B":   PN = "2"  !CDS_PN = "2";
BODY = "Q_CAP","I43": #LOCATION = "C6054" !CDS_LOCATION = "C6054" &SEC = "1" #&CDS_SEC = "1";
"A":   PN = "1"  !CDS_PN = "1";
"B":   PN = "2"  !CDS_PN = "2";
BODY = "Q_CAP","I44": #LOCATION = "C6055" !CDS_LOCATION = "C6055" &SEC = "1" #&CDS_SEC = "1";
"A":   PN = "1"  !CDS_PN = "1";
"B":   PN = "2"  !CDS_PN = "2";
BODY = "Q_CAP","I46": #LOCATION = "C6056" !CDS_LOCATION = "C6056" &SEC = "1" #&CDS_SEC = "1";
"A":   PN = "1"  !CDS_PN = "1";
"B":   PN = "2"  !CDS_PN = "2";
BODY = "Q_CAP","I47": #LOCATION = "C6057" !CDS_LOCATION = "C6057" &SEC = "1" #&CDS_SEC = "1";
"A":   PN = "1"  !CDS_PN = "1";
"B":   PN = "2"  !CDS_PN = "2";
BODY = "Q_CAP","I49": #LOCATION = "C6058" !CDS_LOCATION = "C6058" &SEC = "1" #&CDS_SEC = "1";
"A":   PN = "1"  !CDS_PN = "1";
"B":   PN = "2"  !CDS_PN = "2";
BODY = "Q_CAP","I50": #LOCATION = "C6059" !CDS_LOCATION = "C6059" &SEC = "1" #&CDS_SEC = "1";
"A":   PN = "1"  !CDS_PN = "1";
"B":   PN = "2"  !CDS_PN = "2";
BODY = "Q_CAP","I52": #LOCATION = "C6060" !CDS_LOCATION = "C6060" &SEC = "1" #&CDS_SEC = "1";
"A":   PN = "1"  !CDS_PN = "1";
"B":   PN = "2"  !CDS_PN = "2";
BODY = "Q_CAP","I53": #LOCATION = "C6061" !CDS_LOCATION = "C6061" &SEC = "1" #&CDS_SEC = "1";
"A":   PN = "1"  !CDS_PN = "1";
"B":   PN = "2"  !CDS_PN = "2";
BODY = "Q_CAP","I55": #LOCATION = "C6062" !CDS_LOCATION = "C6062" &SEC = "1" #&CDS_SEC = "1";
"A":   PN = "1"  !CDS_PN = "1";
"B":   PN = "2"  !CDS_PN = "2";
BODY = "Q_CAP","I56": #LOCATION = "C6063" !CDS_LOCATION = "C6063" &SEC = "1" #&CDS_SEC = "1";
"A":   PN = "1"  !CDS_PN = "1";
"B":   PN = "2"  !CDS_PN = "2";
BODY = "Q_CAP","I58": #LOCATION = "C6064" !CDS_LOCATION = "C6064" &SEC = "1" #&CDS_SEC = "1";
"A":   PN = "1"  !CDS_PN = "1";
"B":   PN = "2"  !CDS_PN = "2";
BODY = "Q_CAP","I59": #LOCATION = "C6065" !CDS_LOCATION = "C6065" &SEC = "1" #&CDS_SEC = "1";
"A":   PN = "1"  !CDS_PN = "1";
"B":   PN = "2"  !CDS_PN = "2";
BODY = "Q_CAP","I60": #LOCATION = "C6066" !CDS_LOCATION = "C6066" &SEC = "1" #&CDS_SEC = "1";
"A":   PN = "1"  !CDS_PN = "1";
"B":   PN = "2"  !CDS_PN = "2";
BODY = "Q_CAP","I63": #LOCATION = "C6069" !CDS_LOCATION = "C6069" &SEC = "1" #&CDS_SEC = "1";
"A":   PN = "1"  !CDS_PN = "1";
"B":   PN = "2"  !CDS_PN = "2";
BODY = "Q_CAP","I64": #LOCATION = "C6079" !CDS_LOCATION = "C6079" &SEC = "1" #&CDS_SEC = "1";
"A":   PN = "1"  !CDS_PN = "1";
"B":   PN = "2"  !CDS_PN = "2";
BODY = "Q_CAP","I65": #LOCATION = "C6078" !CDS_LOCATION = "C6078" &SEC = "1" #&CDS_SEC = "1";
"A":   PN = "1"  !CDS_PN = "1";
"B":   PN = "2"  !CDS_PN = "2";
BODY = "Q_CAP","I66": #LOCATION = "C6077" !CDS_LOCATION = "C6077" &SEC = "1" #&CDS_SEC = "1";
"A":   PN = "1"  !CDS_PN = "1";
"B":   PN = "2"  !CDS_PN = "2";
BODY = "Q_CAP","I68": #LOCATION = "C6076" !CDS_LOCATION = "C6076" &SEC = "1" #&CDS_SEC = "1";
"A":   PN = "1"  !CDS_PN = "1";
"B":   PN = "2"  !CDS_PN = "2";
BODY = "Q_CAP","I69": #LOCATION = "C6075" !CDS_LOCATION = "C6075" &SEC = "1" #&CDS_SEC = "1";
"A":   PN = "1"  !CDS_PN = "1";
"B":   PN = "2"  !CDS_PN = "2";
BODY = "Q_CAP","I71": #LOCATION = "C6074" !CDS_LOCATION = "C6074" &SEC = "1" #&CDS_SEC = "1";
"A":   PN = "1"  !CDS_PN = "1";
"B":   PN = "2"  !CDS_PN = "2";
BODY = "Q_CAP","I73": #LOCATION = "C6073" !CDS_LOCATION = "C6073" &SEC = "1" #&CDS_SEC = "1";
"A":   PN = "1"  !CDS_PN = "1";
"B":   PN = "2"  !CDS_PN = "2";
BODY = "Q_CAP","I74": #LOCATION = "C6072" !CDS_LOCATION = "C6072" &SEC = "1" #&CDS_SEC = "1";
"A":   PN = "1"  !CDS_PN = "1";
"B":   PN = "2"  !CDS_PN = "2";
BODY = "Q_CAP","I75": #LOCATION = "C6071" !CDS_LOCATION = "C6071" &SEC = "1" #&CDS_SEC = "1";
"A":   PN = "1"  !CDS_PN = "1";
"B":   PN = "2"  !CDS_PN = "2";
BODY = "Q_CAP","I76": #LOCATION = "C6070" !CDS_LOCATION = "C6070" &SEC = "1" #&CDS_SEC = "1";
"A":   PN = "1"  !CDS_PN = "1";
"B":   PN = "2"  !CDS_PN = "2";
BODY = "Q_CAP","I78": #LOCATION = "C6068" !CDS_LOCATION = "C6068" &SEC = "1" #&CDS_SEC = "1";
"A":   PN = "1"  !CDS_PN = "1";
"B":   PN = "2"  !CDS_PN = "2";
BODY = "Q_CAP","I79": #LOCATION = "C6067" !CDS_LOCATION = "C6067" &SEC = "1" #&CDS_SEC = "1";
"A":   PN = "1"  !CDS_PN = "1";
"B":   PN = "2"  !CDS_PN = "2";
BODY = "Q_CAP","I81": #LOCATION = "C6080" !CDS_LOCATION = "C6080" &SEC = "1" #&CDS_SEC = "1";
"A":   PN = "1"  !CDS_PN = "1";
"B":   PN = "2"  !CDS_PN = "2";
BODY = "Q_CAP","I82": #LOCATION = "C6081" !CDS_LOCATION = "C6081" &SEC = "1" #&CDS_SEC = "1";
"A":   PN = "1"  !CDS_PN = "1";
"B":   PN = "2"  !CDS_PN = "2";
BODY = "Q_CAP","I83": #LOCATION = "C6082" !CDS_LOCATION = "C6082" &SEC = "1" #&CDS_SEC = "1";
"A":   PN = "1"  !CDS_PN = "1";
"B":   PN = "2"  !CDS_PN = "2";
DRAWING = "@t6g_mb_lib.t6g(sch_1):page158";
BODY = "Q_RES","I3": #LOCATION = "R6192" !CDS_LOCATION = "R6192" &SEC = "1" #&CDS_SEC = "1";
"A":   PN = "1"  !CDS_PN = "1";
"B":   PN = "2"  !CDS_PN = "2";
BODY = "Q_RES","I4": #LOCATION = "R6193" !CDS_LOCATION = "R6193" &SEC = "1" #&CDS_SEC = "1";
"A":   PN = "1"  !CDS_PN = "1";
"B":   PN = "2"  !CDS_PN = "2";
BODY = "Q_RES","I5": #LOCATION = "R6191" !CDS_LOCATION = "R6191" &SEC = "1" #&CDS_SEC = "1";
"A":   PN = "1"  !CDS_PN = "1";
"B":   PN = "2"  !CDS_PN = "2";
BODY = "Q_RES","I6": #LOCATION = "R6190" !CDS_LOCATION = "R6190" &SEC = "1" #&CDS_SEC = "1";
"A":   PN = "1"  !CDS_PN = "1";
"B":   PN = "2"  !CDS_PN = "2";
BODY = "Q_CAP_DIFFBUS","I49": #LOCATION = "C6015" !CDS_LOCATION = "C6015" &SEC = "1" #&CDS_SEC = "1";
"1":   PN = "1"  !CDS_PN = "1";
"2":   PN = "2"  !CDS_PN = "2";
BODY = "Q_CAP_DIFFBUS","I50": #LOCATION = "C6016" !CDS_LOCATION = "C6016" &SEC = "1" #&CDS_SEC = "1";
"1":   PN = "1"  !CDS_PN = "1";
"2":   PN = "2"  !CDS_PN = "2";
BODY = "Q_RES","I71": #LOCATION = "R6195" !CDS_LOCATION = "R6195" &SEC = "1" #&CDS_SEC = "1";
"A":   PN = "1"  !CDS_PN = "1";
"B":   PN = "2"  !CDS_PN = "2";
BODY = "Q_RES","I72": #LOCATION = "R6194" !CDS_LOCATION = "R6194" &SEC = "1" #&CDS_SEC = "1";
"A":   PN = "1"  !CDS_PN = "1";
"B":   PN = "2"  !CDS_PN = "2";
BODY = "Q_RES","I73": #LOCATION = "R6196" !CDS_LOCATION = "R6196" &SEC = "1" #&CDS_SEC = "1";
"A":   PN = "1"  !CDS_PN = "1";
"B":   PN = "2"  !CDS_PN = "2";
BODY = "Q_RES","I74": #LOCATION = "R6197" !CDS_LOCATION = "R6197" &SEC = "1" #&CDS_SEC = "1";
"A":   PN = "1"  !CDS_PN = "1";
"B":   PN = "2"  !CDS_PN = "2";
BODY = "Q_CAP_DIFFBUS","I85": #LOCATION = "C6019" !CDS_LOCATION = "C6019" &SEC = "1" #&CDS_SEC = "1";
"1":   PN = "1"  !CDS_PN = "1";
"2":   PN = "2"  !CDS_PN = "2";
BODY = "Q_CAP_DIFFBUS","I86": #LOCATION = "C6020" !CDS_LOCATION = "C6020" &SEC = "1" #&CDS_SEC = "1";
"1":   PN = "1"  !CDS_PN = "1";
"2":   PN = "2"  !CDS_PN = "2";
BODY = "Q_CAP_DIFFBUS","I87": #LOCATION = "C6021" !CDS_LOCATION = "C6021" &SEC = "1" #&CDS_SEC = "1";
"1":   PN = "1"  !CDS_PN = "1";
"2":   PN = "2"  !CDS_PN = "2";
BODY = "Q_CAP_DIFFBUS","I88": #LOCATION = "C6022" !CDS_LOCATION = "C6022" &SEC = "1" #&CDS_SEC = "1";
"1":   PN = "1"  !CDS_PN = "1";
"2":   PN = "2"  !CDS_PN = "2";
BODY = "Q_RES","I120": #LOCATION = "R339" !CDS_LOCATION = "R339" &SEC = "1" #&CDS_SEC = "1";
"A":   PN = "1"  !CDS_PN = "1";
"B":   PN = "2"  !CDS_PN = "2";
BODY = "Q_RES","I121": #LOCATION = "R340" !CDS_LOCATION = "R340" &SEC = "1" #&CDS_SEC = "1";
"A":   PN = "1"  !CDS_PN = "1";
"B":   PN = "2"  !CDS_PN = "2";
BODY = "Q_RES","I124": #LOCATION = "R345" !CDS_LOCATION = "R345" &SEC = "1" #&CDS_SEC = "1";
"A":   PN = "1"  !CDS_PN = "1";
"B":   PN = "2"  !CDS_PN = "2";
BODY = "Q_RES","I125": #LOCATION = "R343" !CDS_LOCATION = "R343" &SEC = "1" #&CDS_SEC = "1";
"A":   PN = "1"  !CDS_PN = "1";
"B":   PN = "2"  !CDS_PN = "2";
BODY = "Q_RES","I126": #LOCATION = "R346" !CDS_LOCATION = "R346" &SEC = "1" #&CDS_SEC = "1";
"A":   PN = "1"  !CDS_PN = "1";
"B":   PN = "2"  !CDS_PN = "2";
BODY = "Q_RES","I127": #LOCATION = "R344" !CDS_LOCATION = "R344" &SEC = "1" #&CDS_SEC = "1";
"A":   PN = "1"  !CDS_PN = "1";
"B":   PN = "2"  !CDS_PN = "2";
BODY = "Q_CAP","I137": #LOCATION = "C6023" !CDS_LOCATION = "C6023" &SEC = "1" #&CDS_SEC = "1";
"A":   PN = "1"  !CDS_PN = "1";
"B":   PN = "2"  !CDS_PN = "2";
BODY = "Q_CAP","I138": #LOCATION = "C6024" !CDS_LOCATION = "C6024" &SEC = "1" #&CDS_SEC = "1";
"A":   PN = "1"  !CDS_PN = "1";
"B":   PN = "2"  !CDS_PN = "2";
BODY = "Q_CAP","I139": #LOCATION = "C6025" !CDS_LOCATION = "C6025" &SEC = "1" #&CDS_SEC = "1";
"A":   PN = "1"  !CDS_PN = "1";
"B":   PN = "2"  !CDS_PN = "2";
BODY = "Q_CAP","I140": #LOCATION = "C6026" !CDS_LOCATION = "C6026" &SEC = "1" #&CDS_SEC = "1";
"A":   PN = "1"  !CDS_PN = "1";
"B":   PN = "2"  !CDS_PN = "2";
BODY = "Q_CAP","I141": #LOCATION = "C6014" !CDS_LOCATION = "C6014" &SEC = "1" #&CDS_SEC = "1";
"A":   PN = "1"  !CDS_PN = "1";
"B":   PN = "2"  !CDS_PN = "2";
BODY = "Q_CAP","I142": #LOCATION = "C6013" !CDS_LOCATION = "C6013" &SEC = "1" #&CDS_SEC = "1";
"A":   PN = "1"  !CDS_PN = "1";
"B":   PN = "2"  !CDS_PN = "2";
BODY = "Q_CAP","I143": #LOCATION = "C6004" !CDS_LOCATION = "C6004" &SEC = "1" #&CDS_SEC = "1";
"A":   PN = "1"  !CDS_PN = "1";
"B":   PN = "2"  !CDS_PN = "2";
BODY = "Q_CAP","I144": #LOCATION = "C6003" !CDS_LOCATION = "C6003" &SEC = "1" #&CDS_SEC = "1";
"A":   PN = "1"  !CDS_PN = "1";
"B":   PN = "2"  !CDS_PN = "2";
BODY = "Q_RES","I145": #LOCATION = "R341" !CDS_LOCATION = "R341" &SEC = "1" #&CDS_SEC = "1";
"A":   PN = "1"  !CDS_PN = "1";
"B":   PN = "2"  !CDS_PN = "2";
BODY = "Q_RES","I146": #LOCATION = "R342" !CDS_LOCATION = "R342" &SEC = "1" #&CDS_SEC = "1";
"A":   PN = "1"  !CDS_PN = "1";
"B":   PN = "2"  !CDS_PN = "2";
BODY = "Q_CAP","I147": #LOCATION = "C6018" !CDS_LOCATION = "C6018" &SEC = "1" #&CDS_SEC = "1";
"A":   PN = "1"  !CDS_PN = "1";
"B":   PN = "2"  !CDS_PN = "2";
BODY = "Q_CAP","I148": #LOCATION = "C6017" !CDS_LOCATION = "C6017" &SEC = "1" #&CDS_SEC = "1";
"A":   PN = "1"  !CDS_PN = "1";
"B":   PN = "2"  !CDS_PN = "2";
DRAWING = "@t6g_mb_lib.t6g(sch_1):page315";
BODY = "Q_RES","I2": #LOCATION = "R6242" !CDS_LOCATION = "R6242" &SEC = "1" #&CDS_SEC = "1";
"A":   PN = "1"  !CDS_PN = "1";
"B":   PN = "2"  !CDS_PN = "2";
BODY = "Q_CAP","I5": #LOCATION = "PC6020" !CDS_LOCATION = "PC6020" &SEC = "1" #&CDS_SEC = "1";
"A":   PN = "1"  !CDS_PN = "1";
"B":   PN = "2"  !CDS_PN = "2";
BODY = "Q_INDUCTOR","I7": #LOCATION = "PL6002" !CDS_LOCATION = "PL6002" &SEC = "1" #&CDS_SEC = "1";
"1":   PN = "1"  !CDS_PN = "1";
"2":   PN = "2"  !CDS_PN = "2";
BODY = "Q_CAP","I8": #LOCATION = "PC6012" !CDS_LOCATION = "PC6012" &SEC = "1" #&CDS_SEC = "1";
"A":   PN = "1"  !CDS_PN = "1";
"B":   PN = "2"  !CDS_PN = "2";
BODY = "Q_CAP","I10": #LOCATION = "PC6014" !CDS_LOCATION = "PC6014" &SEC = "1" #&CDS_SEC = "1";
"A":   PN = "1"  !CDS_PN = "1";
"B":   PN = "2"  !CDS_PN = "2";
BODY = "Q_RES","I12": #LOCATION = "PR6003" !CDS_LOCATION = "PR6003" &SEC = "1" #&CDS_SEC = "1";
"A":   PN = "1"  !CDS_PN = "1";
"B":   PN = "2"  !CDS_PN = "2";
BODY = "Q_CAP","I13": #LOCATION = "PC6008" !CDS_LOCATION = "PC6008" &SEC = "1" #&CDS_SEC = "1";
"A":   PN = "1"  !CDS_PN = "1";
"B":   PN = "2"  !CDS_PN = "2";
BODY = "Q_RES","I15": #LOCATION = "PR6006" !CDS_LOCATION = "PR6006" &SEC = "1" #&CDS_SEC = "1";
"A":   PN = "1"  !CDS_PN = "1";
"B":   PN = "2"  !CDS_PN = "2";
BODY = "MPQ8626GDZ","I18": #LOCATION = "PU6000" !CDS_LOCATION = "PU6000" #SEC = "1" !CDS_SEC = "1";
"AGND":   PN = "7"  !CDS_PN = "7";
"BST":   PN = "10"  !CDS_PN = "10";
"CS":   PN = "4"  !CDS_PN = "4";
"EN":   PN = "5"  !CDS_PN = "5";
"FB":   PN = "6"  !CDS_PN = "6";
"MODE":   PN = "12"  !CDS_PN = "12";
"PGND1":   PN = "1"  !CDS_PN = "1";
"PGND2":   PN = "14"  !CDS_PN = "14";
"PGOOD":   PN = "9"  !CDS_PN = "9";
"SW1":   PN = "2"  !CDS_PN = "2";
"SW2":   PN = "11"  !CDS_PN = "11";
"TRK_REF":   PN = "8"  !CDS_PN = "8";
"VCC":   PN = "13"  !CDS_PN = "13";
"VIN":   PN = "3"  !CDS_PN = "3";
BODY = "Q_CAP","I19": #LOCATION = "PC6010" !CDS_LOCATION = "PC6010" &SEC = "1" #&CDS_SEC = "1";
"A":   PN = "1"  !CDS_PN = "1";
"B":   PN = "2"  !CDS_PN = "2";
BODY = "Q_CAP","I21": #LOCATION = "PC384" !CDS_LOCATION = "PC384" &SEC = "1" #&CDS_SEC = "1";
"A":   PN = "1"  !CDS_PN = "1";
"B":   PN = "2"  !CDS_PN = "2";
BODY = "Q_RES","I23": #LOCATION = "PR6010" !CDS_LOCATION = "PR6010" &SEC = "1" #&CDS_SEC = "1";
"A":   PN = "1"  !CDS_PN = "1";
"B":   PN = "2"  !CDS_PN = "2";
BODY = "Q_INDUCTOR","I25": #LOCATION = "PL6000" !CDS_LOCATION = "PL6000" &SEC = "1" #&CDS_SEC = "1";
"1":   PN = "1"  !CDS_PN = "1";
"2":   PN = "2"  !CDS_PN = "2";
BODY = "Q_CAP","I26": #LOCATION = "PC6019" !CDS_LOCATION = "PC6019" &SEC = "1" #&CDS_SEC = "1";
"A":   PN = "1"  !CDS_PN = "1";
"B":   PN = "2"  !CDS_PN = "2";
BODY = "Q_CAP","I27": #LOCATION = "PC6021" !CDS_LOCATION = "PC6021" &SEC = "1" #&CDS_SEC = "1";
"A":   PN = "1"  !CDS_PN = "1";
"B":   PN = "2"  !CDS_PN = "2";
BODY = "Q_RES","I28": #LOCATION = "PR6007" !CDS_LOCATION = "PR6007" &SEC = "1" #&CDS_SEC = "1";
"A":   PN = "1"  !CDS_PN = "1";
"B":   PN = "2"  !CDS_PN = "2";
BODY = "Q_CAP","I29": #LOCATION = "PC865" !CDS_LOCATION = "PC865" &SEC = "1" #&CDS_SEC = "1";
"A":   PN = "1"  !CDS_PN = "1";
"B":   PN = "2"  !CDS_PN = "2";
BODY = "Q_CAP","I30": #LOCATION = "PC641" !CDS_LOCATION = "PC641" &SEC = "1" #&CDS_SEC = "1";
"A":   PN = "1"  !CDS_PN = "1";
"B":   PN = "2"  !CDS_PN = "2";
BODY = "Q_RES","I32": #LOCATION = "R6243" !CDS_LOCATION = "R6243" &SEC = "1" #&CDS_SEC = "1";
"A":   PN = "1"  !CDS_PN = "1";
"B":   PN = "2"  !CDS_PN = "2";
BODY = "Q_CAP","I34": #LOCATION = "PC866" !CDS_LOCATION = "PC866" &SEC = "1" #&CDS_SEC = "1";
"A":   PN = "1"  !CDS_PN = "1";
"B":   PN = "2"  !CDS_PN = "2";
BODY = "Q_CAP","I36": #LOCATION = "PC867" !CDS_LOCATION = "PC867" &SEC = "1" #&CDS_SEC = "1";
"A":   PN = "1"  !CDS_PN = "1";
"B":   PN = "2"  !CDS_PN = "2";
BODY = "Q_CAP","I37": #LOCATION = "PC850" !CDS_LOCATION = "PC850" &SEC = "1" #&CDS_SEC = "1";
"A":   PN = "1"  !CDS_PN = "1";
"B":   PN = "2"  !CDS_PN = "2";
BODY = "Q_RES","I40": #LOCATION = "R6119" !CDS_LOCATION = "R6119" #SEC = "1" !CDS_SEC = "1";
"A":   PN = "1"  !CDS_PN = "1";
"B":   PN = "2"  !CDS_PN = "2";
BODY = "Q_CAP","I41": #LOCATION = "C345" !CDS_LOCATION = "C345" &SEC = "1" #&CDS_SEC = "1";
"A":   PN = "1"  !CDS_PN = "1";
"B":   PN = "2"  !CDS_PN = "2";
BODY = "Q_RES","I44": #LOCATION = "R214" !CDS_LOCATION = "R214" &SEC = "1" #&CDS_SEC = "1";
"A":   PN = "1"  !CDS_PN = "1";
"B":   PN = "2"  !CDS_PN = "2";
BODY = "Q_RES","I45": #LOCATION = "PR8003" !CDS_LOCATION = "PR8003" #SEC = "1" !CDS_SEC = "1";
"A":   PN = "1"  !CDS_PN = "1";
"B":   PN = "2"  !CDS_PN = "2";
DRAWING = "@t6g_mb_lib.t6g(sch_1):page380";
BODY = "Q_INDUCTOR","I2": #LOCATION = "PL6003" !CDS_LOCATION = "PL6003" &SEC = "1" #&CDS_SEC = "1";
"1":   PN = "1"  !CDS_PN = "1";
"2":   PN = "2"  !CDS_PN = "2";
BODY = "Q_CAP","I3": #LOCATION = "PC6013" !CDS_LOCATION = "PC6013" &SEC = "1" #&CDS_SEC = "1";
"A":   PN = "1"  !CDS_PN = "1";
"B":   PN = "2"  !CDS_PN = "2";
BODY = "Q_RES","I6": #LOCATION = "PR6004" !CDS_LOCATION = "PR6004" &SEC = "1" #&CDS_SEC = "1";
"A":   PN = "1"  !CDS_PN = "1";
"B":   PN = "2"  !CDS_PN = "2";
BODY = "Q_CAP","I7": #LOCATION = "PC6009" !CDS_LOCATION = "PC6009" &SEC = "1" #&CDS_SEC = "1";
"A":   PN = "1"  !CDS_PN = "1";
"B":   PN = "2"  !CDS_PN = "2";
BODY = "Q_CAP","I10": #LOCATION = "PC6015" !CDS_LOCATION = "PC6015" &SEC = "1" #&CDS_SEC = "1";
"A":   PN = "1"  !CDS_PN = "1";
"B":   PN = "2"  !CDS_PN = "2";
BODY = "Q_RES","I11": #LOCATION = "PR6005" !CDS_LOCATION = "PR6005" &SEC = "1" #&CDS_SEC = "1";
"A":   PN = "1"  !CDS_PN = "1";
"B":   PN = "2"  !CDS_PN = "2";
BODY = "Q_CAP","I12": #LOCATION = "PC6011" !CDS_LOCATION = "PC6011" &SEC = "1" #&CDS_SEC = "1";
"A":   PN = "1"  !CDS_PN = "1";
"B":   PN = "2"  !CDS_PN = "2";
BODY = "MPQ8626GDZ","I16": #LOCATION = "PU6001" !CDS_LOCATION = "PU6001" #SEC = "1" !CDS_SEC = "1";
"AGND":   PN = "7"  !CDS_PN = "7";
"BST":   PN = "10"  !CDS_PN = "10";
"CS":   PN = "4"  !CDS_PN = "4";
"EN":   PN = "5"  !CDS_PN = "5";
"FB":   PN = "6"  !CDS_PN = "6";
"MODE":   PN = "12"  !CDS_PN = "12";
"PGND1":   PN = "1"  !CDS_PN = "1";
"PGND2":   PN = "14"  !CDS_PN = "14";
"PGOOD":   PN = "9"  !CDS_PN = "9";
"SW1":   PN = "2"  !CDS_PN = "2";
"SW2":   PN = "11"  !CDS_PN = "11";
"TRK_REF":   PN = "8"  !CDS_PN = "8";
"VCC":   PN = "13"  !CDS_PN = "13";
"VIN":   PN = "3"  !CDS_PN = "3";
BODY = "Q_CAP","I17": #LOCATION = "PC6016" !CDS_LOCATION = "PC6016" &SEC = "1" #&CDS_SEC = "1";
"A":   PN = "1"  !CDS_PN = "1";
"B":   PN = "2"  !CDS_PN = "2";
BODY = "Q_CAP","I18": #LOCATION = "PC6017" !CDS_LOCATION = "PC6017" &SEC = "1" #&CDS_SEC = "1";
"A":   PN = "1"  !CDS_PN = "1";
"B":   PN = "2"  !CDS_PN = "2";
BODY = "Q_RES","I19": #LOCATION = "R6244" !CDS_LOCATION = "R6244" &SEC = "1" #&CDS_SEC = "1";
"A":   PN = "1"  !CDS_PN = "1";
"B":   PN = "2"  !CDS_PN = "2";
BODY = "Q_RES","I21": #LOCATION = "PR6011" !CDS_LOCATION = "PR6011" &SEC = "1" #&CDS_SEC = "1";
"A":   PN = "1"  !CDS_PN = "1";
"B":   PN = "2"  !CDS_PN = "2";
BODY = "Q_CAP","I23": #LOCATION = "PC6022" !CDS_LOCATION = "PC6022" &SEC = "1" #&CDS_SEC = "1";
"A":   PN = "1"  !CDS_PN = "1";
"B":   PN = "2"  !CDS_PN = "2";
BODY = "Q_INDUCTOR","I24": #LOCATION = "PL6001" !CDS_LOCATION = "PL6001" &SEC = "1" #&CDS_SEC = "1";
"1":   PN = "1"  !CDS_PN = "1";
"2":   PN = "2"  !CDS_PN = "2";
BODY = "Q_CAP","I26": #LOCATION = "PC852" !CDS_LOCATION = "PC852" &SEC = "1" #&CDS_SEC = "1";
"A":   PN = "1"  !CDS_PN = "1";
"B":   PN = "2"  !CDS_PN = "2";
BODY = "Q_RES","I27": #LOCATION = "PR6008" !CDS_LOCATION = "PR6008" &SEC = "1" #&CDS_SEC = "1";
"A":   PN = "1"  !CDS_PN = "1";
"B":   PN = "2"  !CDS_PN = "2";
BODY = "Q_CAP","I28": #LOCATION = "PC6024" !CDS_LOCATION = "PC6024" &SEC = "1" #&CDS_SEC = "1";
"A":   PN = "1"  !CDS_PN = "1";
"B":   PN = "2"  !CDS_PN = "2";
BODY = "Q_CAP","I29": #LOCATION = "PC6025" !CDS_LOCATION = "PC6025" &SEC = "1" #&CDS_SEC = "1";
"A":   PN = "1"  !CDS_PN = "1";
"B":   PN = "2"  !CDS_PN = "2";
BODY = "Q_CAP","I32": #LOCATION = "PC6026" !CDS_LOCATION = "PC6026" &SEC = "1" #&CDS_SEC = "1";
"A":   PN = "1"  !CDS_PN = "1";
"B":   PN = "2"  !CDS_PN = "2";
BODY = "Q_CAP","I33": #LOCATION = "PC6018" !CDS_LOCATION = "PC6018" &SEC = "1" #&CDS_SEC = "1";
"A":   PN = "1"  !CDS_PN = "1";
"B":   PN = "2"  !CDS_PN = "2";
BODY = "Q_CAP","I35": #LOCATION = "PC6023" !CDS_LOCATION = "PC6023" &SEC = "1" #&CDS_SEC = "1";
"A":   PN = "1"  !CDS_PN = "1";
"B":   PN = "2"  !CDS_PN = "2";
BODY = "Q_RES","I38": #LOCATION = "R6245" !CDS_LOCATION = "R6245" &SEC = "1" #&CDS_SEC = "1";
"A":   PN = "1"  !CDS_PN = "1";
"B":   PN = "2"  !CDS_PN = "2";
BODY = "Q_RES","I40": #LOCATION = "R6240" !CDS_LOCATION = "R6240" &SEC = "1" #&CDS_SEC = "1";
"A":   PN = "1"  !CDS_PN = "1";
"B":   PN = "2"  !CDS_PN = "2";
BODY = "Q_CAP","I41": #LOCATION = "C6085" !CDS_LOCATION = "C6085" &SEC = "1" #&CDS_SEC = "1";
"A":   PN = "1"  !CDS_PN = "1";
"B":   PN = "2"  !CDS_PN = "2";
BODY = "Q_RES","I44": #LOCATION = "R6241" !CDS_LOCATION = "R6241" &SEC = "1" #&CDS_SEC = "1";
"A":   PN = "1"  !CDS_PN = "1";
"B":   PN = "2"  !CDS_PN = "2";
BODY = "Q_RES","I45": #LOCATION = "PR8004" !CDS_LOCATION = "PR8004" #SEC = "1" !CDS_SEC = "1";
"A":   PN = "1"  !CDS_PN = "1";
"B":   PN = "2"  !CDS_PN = "2";
DRAWING = "@t6g_mb_lib.t6g(sch_1):page157";
BODY = "Q_INDUCTOR","I17": #LOCATION = "L6003" !CDS_LOCATION = "L6003" &SEC = "1" #&CDS_SEC = "1";
"1":   PN = "1"  !CDS_PN = "1";
"2":   PN = "2"  !CDS_PN = "2";
BODY = "Q_INDUCTOR","I20": #LOCATION = "L6004" !CDS_LOCATION = "L6004" &SEC = "1" #&CDS_SEC = "1";
"1":   PN = "1"  !CDS_PN = "1";
"2":   PN = "2"  !CDS_PN = "2";
BODY = "Q_CAP","I21": #LOCATION = "C6092" !CDS_LOCATION = "C6092" &SEC = "1" #&CDS_SEC = "1";
"A":   PN = "1"  !CDS_PN = "1";
"B":   PN = "2"  !CDS_PN = "2";
BODY = "Q_CAP","I22": #LOCATION = "C6094" !CDS_LOCATION = "C6094" &SEC = "1" #&CDS_SEC = "1";
"A":   PN = "1"  !CDS_PN = "1";
"B":   PN = "2"  !CDS_PN = "2";
BODY = "Q_CAP","I23": #LOCATION = "C6095" !CDS_LOCATION = "C6095" &SEC = "1" #&CDS_SEC = "1";
"A":   PN = "1"  !CDS_PN = "1";
"B":   PN = "2"  !CDS_PN = "2";
BODY = "Q_CAP","I24": #LOCATION = "C6093" !CDS_LOCATION = "C6093" &SEC = "1" #&CDS_SEC = "1";
"A":   PN = "1"  !CDS_PN = "1";
"B":   PN = "2"  !CDS_PN = "2";
BODY = "Q_CAP","I25": #LOCATION = "C6098" !CDS_LOCATION = "C6098" &SEC = "1" #&CDS_SEC = "1";
"A":   PN = "1"  !CDS_PN = "1";
"B":   PN = "2"  !CDS_PN = "2";
BODY = "Q_CAP","I26": #LOCATION = "C6097" !CDS_LOCATION = "C6097" &SEC = "1" #&CDS_SEC = "1";
"A":   PN = "1"  !CDS_PN = "1";
"B":   PN = "2"  !CDS_PN = "2";
BODY = "Q_CAP","I27": #LOCATION = "C6096" !CDS_LOCATION = "C6096" &SEC = "1" #&CDS_SEC = "1";
"A":   PN = "1"  !CDS_PN = "1";
"B":   PN = "2"  !CDS_PN = "2";
BODY = "Q_CAP","I28": #LOCATION = "C6101" !CDS_LOCATION = "C6101" &SEC = "1" #&CDS_SEC = "1";
"A":   PN = "1"  !CDS_PN = "1";
"B":   PN = "2"  !CDS_PN = "2";
BODY = "Q_CAP","I29": #LOCATION = "C6100" !CDS_LOCATION = "C6100" &SEC = "1" #&CDS_SEC = "1";
"A":   PN = "1"  !CDS_PN = "1";
"B":   PN = "2"  !CDS_PN = "2";
BODY = "Q_CAP","I30": #LOCATION = "C6099" !CDS_LOCATION = "C6099" &SEC = "1" #&CDS_SEC = "1";
"A":   PN = "1"  !CDS_PN = "1";
"B":   PN = "2"  !CDS_PN = "2";
BODY = "Q_CAP","I31": #LOCATION = "C6104" !CDS_LOCATION = "C6104" &SEC = "1" #&CDS_SEC = "1";
"A":   PN = "1"  !CDS_PN = "1";
"B":   PN = "2"  !CDS_PN = "2";
BODY = "Q_CAP","I32": #LOCATION = "C6103" !CDS_LOCATION = "C6103" &SEC = "1" #&CDS_SEC = "1";
"A":   PN = "1"  !CDS_PN = "1";
"B":   PN = "2"  !CDS_PN = "2";
BODY = "Q_CAP","I33": #LOCATION = "C6102" !CDS_LOCATION = "C6102" &SEC = "1" #&CDS_SEC = "1";
"A":   PN = "1"  !CDS_PN = "1";
"B":   PN = "2"  !CDS_PN = "2";
BODY = "Q_CAP","I36": #LOCATION = "C6105" !CDS_LOCATION = "C6105" &SEC = "1" #&CDS_SEC = "1";
"A":   PN = "1"  !CDS_PN = "1";
"B":   PN = "2"  !CDS_PN = "2";
BODY = "Q_CAP","I39": #LOCATION = "C6108" !CDS_LOCATION = "C6108" &SEC = "1" #&CDS_SEC = "1";
"A":   PN = "1"  !CDS_PN = "1";
"B":   PN = "2"  !CDS_PN = "2";
BODY = "Q_CAP","I40": #LOCATION = "C6107" !CDS_LOCATION = "C6107" &SEC = "1" #&CDS_SEC = "1";
"A":   PN = "1"  !CDS_PN = "1";
"B":   PN = "2"  !CDS_PN = "2";
BODY = "Q_CAP","I41": #LOCATION = "C6106" !CDS_LOCATION = "C6106" &SEC = "1" #&CDS_SEC = "1";
"A":   PN = "1"  !CDS_PN = "1";
"B":   PN = "2"  !CDS_PN = "2";
BODY = "Q_CAP","I42": #LOCATION = "C6111" !CDS_LOCATION = "C6111" &SEC = "1" #&CDS_SEC = "1";
"A":   PN = "1"  !CDS_PN = "1";
"B":   PN = "2"  !CDS_PN = "2";
BODY = "Q_CAP","I43": #LOCATION = "C6110" !CDS_LOCATION = "C6110" &SEC = "1" #&CDS_SEC = "1";
"A":   PN = "1"  !CDS_PN = "1";
"B":   PN = "2"  !CDS_PN = "2";
BODY = "Q_CAP","I44": #LOCATION = "C6109" !CDS_LOCATION = "C6109" &SEC = "1" #&CDS_SEC = "1";
"A":   PN = "1"  !CDS_PN = "1";
"B":   PN = "2"  !CDS_PN = "2";
BODY = "Q_CAP","I45": #LOCATION = "C6114" !CDS_LOCATION = "C6114" &SEC = "1" #&CDS_SEC = "1";
"A":   PN = "1"  !CDS_PN = "1";
"B":   PN = "2"  !CDS_PN = "2";
BODY = "Q_CAP","I46": #LOCATION = "C6113" !CDS_LOCATION = "C6113" &SEC = "1" #&CDS_SEC = "1";
"A":   PN = "1"  !CDS_PN = "1";
"B":   PN = "2"  !CDS_PN = "2";
BODY = "Q_CAP","I47": #LOCATION = "C6112" !CDS_LOCATION = "C6112" &SEC = "1" #&CDS_SEC = "1";
"A":   PN = "1"  !CDS_PN = "1";
"B":   PN = "2"  !CDS_PN = "2";
BODY = "Q_CAP","I48": #LOCATION = "C6117" !CDS_LOCATION = "C6117" &SEC = "1" #&CDS_SEC = "1";
"A":   PN = "1"  !CDS_PN = "1";
"B":   PN = "2"  !CDS_PN = "2";
BODY = "Q_CAP","I49": #LOCATION = "C6116" !CDS_LOCATION = "C6116" &SEC = "1" #&CDS_SEC = "1";
"A":   PN = "1"  !CDS_PN = "1";
"B":   PN = "2"  !CDS_PN = "2";
BODY = "Q_CAP","I50": #LOCATION = "C6115" !CDS_LOCATION = "C6115" &SEC = "1" #&CDS_SEC = "1";
"A":   PN = "1"  !CDS_PN = "1";
"B":   PN = "2"  !CDS_PN = "2";
BODY = "Q_CAP","I51": #LOCATION = "C6121" !CDS_LOCATION = "C6121" &SEC = "1" #&CDS_SEC = "1";
"A":   PN = "1"  !CDS_PN = "1";
"B":   PN = "2"  !CDS_PN = "2";
BODY = "Q_CAP","I52": #LOCATION = "C6120" !CDS_LOCATION = "C6120" &SEC = "1" #&CDS_SEC = "1";
"A":   PN = "1"  !CDS_PN = "1";
"B":   PN = "2"  !CDS_PN = "2";
BODY = "Q_CAP","I53": #LOCATION = "C6119" !CDS_LOCATION = "C6119" &SEC = "1" #&CDS_SEC = "1";
"A":   PN = "1"  !CDS_PN = "1";
"B":   PN = "2"  !CDS_PN = "2";
BODY = "Q_CAP","I54": #LOCATION = "C6118" !CDS_LOCATION = "C6118" &SEC = "1" #&CDS_SEC = "1";
"A":   PN = "1"  !CDS_PN = "1";
"B":   PN = "2"  !CDS_PN = "2";
BODY = "Q_RES","I63": #LOCATION = "R6283" !CDS_LOCATION = "R6283" &SEC = "1" #&CDS_SEC = "1";
"A":   PN = "1"  !CDS_PN = "1";
"B":   PN = "2"  !CDS_PN = "2";
BODY = "Q_RES","I75": #LOCATION = "R6291" !CDS_LOCATION = "R6291" &SEC = "1" #&CDS_SEC = "1";
"A":   PN = "1"  !CDS_PN = "1";
"B":   PN = "2"  !CDS_PN = "2";
BODY = "Q_RES","I76": #LOCATION = "R6290" !CDS_LOCATION = "R6290" &SEC = "1" #&CDS_SEC = "1";
"A":   PN = "1"  !CDS_PN = "1";
"B":   PN = "2"  !CDS_PN = "2";
BODY = "Q_RES","I77": #LOCATION = "R6292" !CDS_LOCATION = "R6292" &SEC = "1" #&CDS_SEC = "1";
"A":   PN = "1"  !CDS_PN = "1";
"B":   PN = "2"  !CDS_PN = "2";
BODY = "Q_RES","I79": #LOCATION = "R6293" !CDS_LOCATION = "R6293" &SEC = "1" #&CDS_SEC = "1";
"A":   PN = "1"  !CDS_PN = "1";
"B":   PN = "2"  !CDS_PN = "2";
BODY = "Q_RES","I81": #LOCATION = "R6294" !CDS_LOCATION = "R6294" &SEC = "1" #&CDS_SEC = "1";
"A":   PN = "1"  !CDS_PN = "1";
"B":   PN = "2"  !CDS_PN = "2";
BODY = "TUSB8042AIRGCR","I119": #LOCATION = "U6002" !CDS_LOCATION = "U6002" #SEC = "2" !CDS_SEC = "2";
"AUTOENZ||HS_SUSPEND":   PN = "45"  !CDS_PN = "45";
"FULLPWRMGMTZ||FULLAUTOZ||SMBA1||SS_UP":   PN = "40"  !CDS_PN = "40";
"GANGED||SMBA2||HS_UP":   PN = "42"  !CDS_PN = "42";
"SCL||SMBCLK":   PN = "38"  !CDS_PN = "38";
"SDA||SMBDAT":   PN = "37"  !CDS_PN = "37";
"SMBUSZ||SS_SUSPEND":   PN = "39"  !CDS_PN = "39";
"VDD33_16":   PN = "16"  !CDS_PN = "16";
"VDD33_34":   PN = "34"  !CDS_PN = "34";
"VDD33_52":   PN = "52"  !CDS_PN = "52";
"VDD33_63":   PN = "63"  !CDS_PN = "63";
"VDD_5":   PN = "5"  !CDS_PN = "5";
"VDD_8":   PN = "8"  !CDS_PN = "8";
"VDD_13":   PN = "13"  !CDS_PN = "13";
"VDD_21":   PN = "21"  !CDS_PN = "21";
"VDD_28":   PN = "28"  !CDS_PN = "28";
"VDD_31":   PN = "31"  !CDS_PN = "31";
"VDD_51":   PN = "51"  !CDS_PN = "51";
"VDD_57":   PN = "57"  !CDS_PN = "57";
"XI":   PN = "62"  !CDS_PN = "62";
"XO":   PN = "61"  !CDS_PN = "61";
BODY = "Q_RES","I122": #LOCATION = "R6267" !CDS_LOCATION = "R6267" &SEC = "1" #&CDS_SEC = "1";
"A":   PN = "1"  !CDS_PN = "1";
"B":   PN = "2"  !CDS_PN = "2";
BODY = "Q_RES","I124": #LOCATION = "R6278" !CDS_LOCATION = "R6278" &SEC = "1" #&CDS_SEC = "1";
"A":   PN = "1"  !CDS_PN = "1";
"B":   PN = "2"  !CDS_PN = "2";
BODY = "Q_RES","I125": #LOCATION = "R6276" !CDS_LOCATION = "R6276" &SEC = "1" #&CDS_SEC = "1";
"A":   PN = "1"  !CDS_PN = "1";
"B":   PN = "2"  !CDS_PN = "2";
BODY = "Q_RES","I130": #LOCATION = "R6277" !CDS_LOCATION = "R6277" &SEC = "1" #&CDS_SEC = "1";
"A":   PN = "1"  !CDS_PN = "1";
"B":   PN = "2"  !CDS_PN = "2";
BODY = "Q_RES","I131": #LOCATION = "R6275" !CDS_LOCATION = "R6275" &SEC = "1" #&CDS_SEC = "1";
"A":   PN = "1"  !CDS_PN = "1";
"B":   PN = "2"  !CDS_PN = "2";
BODY = "Q_RES","I134": #LOCATION = "R6262" !CDS_LOCATION = "R6262" &SEC = "1" #&CDS_SEC = "1";
"A":   PN = "1"  !CDS_PN = "1";
"B":   PN = "2"  !CDS_PN = "2";
BODY = "Q_RES","I136": #LOCATION = "R6269" !CDS_LOCATION = "R6269" &SEC = "1" #&CDS_SEC = "1";
"A":   PN = "1"  !CDS_PN = "1";
"B":   PN = "2"  !CDS_PN = "2";
BODY = "Q_RES","I138": #LOCATION = "R6282" !CDS_LOCATION = "R6282" &SEC = "1" #&CDS_SEC = "1";
"A":   PN = "1"  !CDS_PN = "1";
"B":   PN = "2"  !CDS_PN = "2";
BODY = "Q_RES","I139": #LOCATION = "R6281" !CDS_LOCATION = "R6281" &SEC = "1" #&CDS_SEC = "1";
"A":   PN = "1"  !CDS_PN = "1";
"B":   PN = "2"  !CDS_PN = "2";
BODY = "Q_RES","I142": #LOCATION = "R6274" !CDS_LOCATION = "R6274" &SEC = "1" #&CDS_SEC = "1";
"A":   PN = "1"  !CDS_PN = "1";
"B":   PN = "2"  !CDS_PN = "2";
BODY = "Q_RES","I145": #LOCATION = "R6265" !CDS_LOCATION = "R6265" &SEC = "1" #&CDS_SEC = "1";
"A":   PN = "1"  !CDS_PN = "1";
"B":   PN = "2"  !CDS_PN = "2";
BODY = "Q_RES","I146": #LOCATION = "R6280" !CDS_LOCATION = "R6280" &SEC = "1" #&CDS_SEC = "1";
"A":   PN = "1"  !CDS_PN = "1";
"B":   PN = "2"  !CDS_PN = "2";
BODY = "Q_RES","I148": #LOCATION = "R6279" !CDS_LOCATION = "R6279" &SEC = "1" #&CDS_SEC = "1";
"A":   PN = "1"  !CDS_PN = "1";
"B":   PN = "2"  !CDS_PN = "2";
BODY = "Q_RES","I150": #LOCATION = "R6305" !CDS_LOCATION = "R6305" &SEC = "1" #&CDS_SEC = "1";
"A":   PN = "1"  !CDS_PN = "1";
"B":   PN = "2"  !CDS_PN = "2";
BODY = "Q_RES","I151": #LOCATION = "R6304" !CDS_LOCATION = "R6304" &SEC = "1" #&CDS_SEC = "1";
"A":   PN = "1"  !CDS_PN = "1";
"B":   PN = "2"  !CDS_PN = "2";
BODY = "Q_RES","I153": #LOCATION = "R6308" !CDS_LOCATION = "R6308" &SEC = "1" #&CDS_SEC = "1";
"A":   PN = "1"  !CDS_PN = "1";
"B":   PN = "2"  !CDS_PN = "2";
BODY = "Q_RES","I155": #LOCATION = "R6306" !CDS_LOCATION = "R6306" &SEC = "1" #&CDS_SEC = "1";
"A":   PN = "1"  !CDS_PN = "1";
"B":   PN = "2"  !CDS_PN = "2";
BODY = "Q_RES","I156": #LOCATION = "R6307" !CDS_LOCATION = "R6307" &SEC = "1" #&CDS_SEC = "1";
"A":   PN = "1"  !CDS_PN = "1";
"B":   PN = "2"  !CDS_PN = "2";
BODY = "Q_RES","I158": #LOCATION = "R6309" !CDS_LOCATION = "R6309" &SEC = "1" #&CDS_SEC = "1";
"A":   PN = "1"  !CDS_PN = "1";
"B":   PN = "2"  !CDS_PN = "2";
BODY = "Q_RES","I160": #LOCATION = "R6257" !CDS_LOCATION = "R6257" &SEC = "1" #&CDS_SEC = "1";
"A":   PN = "1"  !CDS_PN = "1";
"B":   PN = "2"  !CDS_PN = "2";
BODY = "Q_XTAL_4P_13BI_24GND","I164": #LOCATION = "Y6000" !CDS_LOCATION = "Y6000" #SEC = "1" !CDS_SEC = "1";
"G1":   PN = "2"  !CDS_PN = "2";
"G2":   PN = "4"  !CDS_PN = "4";
"X1":   PN = "1"  !CDS_PN = "1";
"X2":   PN = "3"  !CDS_PN = "3";
BODY = "Q_RES","I170": #LOCATION = "R6260" !CDS_LOCATION = "R6260" &SEC = "1" #&CDS_SEC = "1";
"A":   PN = "1"  !CDS_PN = "1";
"B":   PN = "2"  !CDS_PN = "2";
BODY = "Q_RES","I171": #LOCATION = "R6284" !CDS_LOCATION = "R6284" #SEC = "1" !CDS_SEC = "1";
"A":   PN = "1"  !CDS_PN = "1";
"B":   PN = "2"  !CDS_PN = "2";
BODY = "Q_CAP","I174": #LOCATION = "C6090" !CDS_LOCATION = "C6090" #SEC = "1" !CDS_SEC = "1";
"A":   PN = "1"  !CDS_PN = "1";
"B":   PN = "2"  !CDS_PN = "2";
BODY = "Q_CAP","I175": #LOCATION = "C6091" !CDS_LOCATION = "C6091" #SEC = "1" !CDS_SEC = "1";
"A":   PN = "1"  !CDS_PN = "1";
"B":   PN = "2"  !CDS_PN = "2";
DRAWING = "@t6g_mb_lib.t6g(sch_1):page271";
BODY = "Q_RES","I9": #LOCATION = "R6252" !CDS_LOCATION = "R6252" &SEC = "1" #&CDS_SEC = "1";
"A":   PN = "1"  !CDS_PN = "1";
"B":   PN = "2"  !CDS_PN = "2";
BODY = "Q_RES","I10": #LOCATION = "R6253" !CDS_LOCATION = "R6253" &SEC = "1" #&CDS_SEC = "1";
"A":   PN = "1"  !CDS_PN = "1";
"B":   PN = "2"  !CDS_PN = "2";
BODY = "Q_CAP","I11": #LOCATION = "C6086" !CDS_LOCATION = "C6086" &SEC = "1" #&CDS_SEC = "1";
"A":   PN = "1"  !CDS_PN = "1";
"B":   PN = "2"  !CDS_PN = "2";
BODY = "Q_RES","I14": #LOCATION = "R6251" !CDS_LOCATION = "R6251" &SEC = "1" #&CDS_SEC = "1";
"A":   PN = "1"  !CDS_PN = "1";
"B":   PN = "2"  !CDS_PN = "2";
BODY = "Q_CAP","I22": #LOCATION = "C6087" !CDS_LOCATION = "C6087" &SEC = "1" #&CDS_SEC = "1";
"A":   PN = "1"  !CDS_PN = "1";
"B":   PN = "2"  !CDS_PN = "2";
BODY = "Q_RES","I25": #LOCATION = "R6247" !CDS_LOCATION = "R6247" &SEC = "1" #&CDS_SEC = "1";
"A":   PN = "1"  !CDS_PN = "1";
"B":   PN = "2"  !CDS_PN = "2";
BODY = "ISL28022FRZT","I28": #LOCATION = "U6005" !CDS_LOCATION = "U6005" #SEC = "1" !CDS_SEC = "1";
"A0":   PN = "2"  !CDS_PN = "2";
"A1":   PN = "1"  !CDS_PN = "1";
"EXT_CLK||INT":   PN = "3"  !CDS_PN = "3";
"GND":   PN = "10"  !CDS_PN = "10";
"NC0":   PN = "6"  !CDS_PN = "6";
"NC1":   PN = "7"  !CDS_PN = "7";
"NC2":   PN = "8"  !CDS_PN = "8";
"NC3":   PN = "14"  !CDS_PN = "14";
"NC4":   PN = "15"  !CDS_PN = "15";
"NC5":   PN = "16"  !CDS_PN = "16";
"SCL|||SMBCLK":   PN = "5"  !CDS_PN = "5";
"SDA||SMBDAT":   PN = "4"  !CDS_PN = "4";
"TH_GND":   PN = "TH"  !CDS_PN = "TH";
"VBUS":   PN = "11"  !CDS_PN = "11";
"VCC":   PN = "9"  !CDS_PN = "9";
"VINM":   PN = "12"  !CDS_PN = "12";
"VINP":   PN = "13"  !CDS_PN = "13";
BODY = "Q_RES","I29": #LOCATION = "R6254" !CDS_LOCATION = "R6254" &SEC = "1" #&CDS_SEC = "1";
"A":   PN = "1"  !CDS_PN = "1";
"B":   PN = "2"  !CDS_PN = "2";
BODY = "Q_RES","I30": #LOCATION = "R6250" !CDS_LOCATION = "R6250" &SEC = "1" #&CDS_SEC = "1";
"A":   PN = "1"  !CDS_PN = "1";
"B":   PN = "2"  !CDS_PN = "2";
DRAWING = "@t6g_mb_lib.t6g(sch_1):page155";
BODY = "Q_RES","I89": #LOCATION = "R6326" !CDS_LOCATION = "R6326" &SEC = "1" #&CDS_SEC = "1";
"A":   PN = "1"  !CDS_PN = "1";
"B":   PN = "2"  !CDS_PN = "2";
BODY = "Q_RES","I91": #LOCATION = "R6327" !CDS_LOCATION = "R6327" &SEC = "1" #&CDS_SEC = "1";
"A":   PN = "1"  !CDS_PN = "1";
"B":   PN = "2"  !CDS_PN = "2";
BODY = "TUSB8042AIRGCR","I101": #LOCATION = "U6002" !CDS_LOCATION = "U6002" #SEC = "1" !CDS_SEC = "1";
"GRSTZ":   PN = "50"  !CDS_PN = "50";
"NC_1":   PN = "60"  !CDS_PN = "60";
"OVERCUR1Z":   PN = "46"  !CDS_PN = "46";
"OVERCUR2Z":   PN = "47"  !CDS_PN = "47";
"OVERCUR3Z":   PN = "44"  !CDS_PN = "44";
"OVERCUR4Z":   PN = "43"  !CDS_PN = "43";
"PWRCTL1||BATEN1":   PN = "36"  !CDS_PN = "36";
"PWRCTL2||BATEN2":   PN = "35"  !CDS_PN = "35";
"PWRCTL3||BATEN3":   PN = "33"  !CDS_PN = "33";
"PWRCTL4||BATEN4":   PN = "32"  !CDS_PN = "32";
"PWRCTL_POL":   PN = "41"  !CDS_PN = "41";
"TEST":   PN = "49"  !CDS_PN = "49";
"TH_VSS":   PN = "TH"  !CDS_PN = "TH";
"USB_DM_DN1":   PN = "2"  !CDS_PN = "2";
"USB_DM_DN2":   PN = "10"  !CDS_PN = "10";
"USB_DM_DN3":   PN = "18"  !CDS_PN = "18";
"USB_DM_DN4":   PN = "25"  !CDS_PN = "25";
"USB_DM_UP":   PN = "54"  !CDS_PN = "54";
"USB_DP_DN1":   PN = "1"  !CDS_PN = "1";
"USB_DP_DN2":   PN = "9"  !CDS_PN = "9";
"USB_DP_DN3":   PN = "17"  !CDS_PN = "17";
"USB_DP_DN4":   PN = "24"  !CDS_PN = "24";
"USB_DP_UP":   PN = "53"  !CDS_PN = "53";
"USB_R1":   PN = "64"  !CDS_PN = "64";
"USB_SSRXM_DN1":   PN = "7"  !CDS_PN = "7";
"USB_SSRXM_DN2":   PN = "15"  !CDS_PN = "15";
"USB_SSRXM_DN3":   PN = "23"  !CDS_PN = "23";
"USB_SSRXM_DN4":   PN = "30"  !CDS_PN = "30";
"USB_SSRXM_UP":   PN = "59"  !CDS_PN = "59";
"USB_SSRXP_DN1":   PN = "6"  !CDS_PN = "6";
"USB_SSRXP_DN2":   PN = "14"  !CDS_PN = "14";
"USB_SSRXP_DN3":   PN = "22"  !CDS_PN = "22";
"USB_SSRXP_DN4":   PN = "29"  !CDS_PN = "29";
"USB_SSRXP_UP":   PN = "58"  !CDS_PN = "58";
"USB_SSTXM_DN1":   PN = "4"  !CDS_PN = "4";
"USB_SSTXM_DN2":   PN = "12"  !CDS_PN = "12";
"USB_SSTXM_DN3":   PN = "20"  !CDS_PN = "20";
"USB_SSTXM_DN4":   PN = "27"  !CDS_PN = "27";
"USB_SSTXM_UP":   PN = "56"  !CDS_PN = "56";
"USB_SSTXP_DN1":   PN = "3"  !CDS_PN = "3";
"USB_SSTXP_DN2":   PN = "11"  !CDS_PN = "11";
"USB_SSTXP_DN3":   PN = "19"  !CDS_PN = "19";
"USB_SSTXP_DN4":   PN = "26"  !CDS_PN = "26";
"USB_SSTXP_UP":   PN = "55"  !CDS_PN = "55";
"USB_VBUS":   PN = "48"  !CDS_PN = "48";
BODY = "Q_RES","I102": #LOCATION = "R6271" !CDS_LOCATION = "R6271" &SEC = "1" #&CDS_SEC = "1";
"A":   PN = "1"  !CDS_PN = "1";
"B":   PN = "2"  !CDS_PN = "2";
BODY = "Q_RES","I104": #LOCATION = "R6273" !CDS_LOCATION = "R6273" &SEC = "1" #&CDS_SEC = "1";
"A":   PN = "1"  !CDS_PN = "1";
"B":   PN = "2"  !CDS_PN = "2";
BODY = "Q_RES","I105": #LOCATION = "R6272" !CDS_LOCATION = "R6272" &SEC = "1" #&CDS_SEC = "1";
"A":   PN = "1"  !CDS_PN = "1";
"B":   PN = "2"  !CDS_PN = "2";
BODY = "Q_RES","I111": #LOCATION = "R6333" !CDS_LOCATION = "R6333" &SEC = "1" #&CDS_SEC = "1";
"A":   PN = "1"  !CDS_PN = "1";
"B":   PN = "2"  !CDS_PN = "2";
BODY = "Q_RES","I114": #LOCATION = "R6328" !CDS_LOCATION = "R6328" &SEC = "1" #&CDS_SEC = "1";
"A":   PN = "1"  !CDS_PN = "1";
"B":   PN = "2"  !CDS_PN = "2";
BODY = "Q_RES","I115": #LOCATION = "R6323" !CDS_LOCATION = "R6323" &SEC = "1" #&CDS_SEC = "1";
"A":   PN = "1"  !CDS_PN = "1";
"B":   PN = "2"  !CDS_PN = "2";
BODY = "Q_RES","I116": #LOCATION = "R6325" !CDS_LOCATION = "R6325" &SEC = "1" #&CDS_SEC = "1";
"A":   PN = "1"  !CDS_PN = "1";
"B":   PN = "2"  !CDS_PN = "2";
BODY = "Q_RES","I118": #LOCATION = "R6324" !CDS_LOCATION = "R6324" &SEC = "1" #&CDS_SEC = "1";
"A":   PN = "1"  !CDS_PN = "1";
"B":   PN = "2"  !CDS_PN = "2";
BODY = "Q_RES","I119": #LOCATION = "R6316" !CDS_LOCATION = "R6316" &SEC = "1" #&CDS_SEC = "1";
"A":   PN = "1"  !CDS_PN = "1";
"B":   PN = "2"  !CDS_PN = "2";
BODY = "Q_RES","I121": #LOCATION = "R6319" !CDS_LOCATION = "R6319" &SEC = "1" #&CDS_SEC = "1";
"A":   PN = "1"  !CDS_PN = "1";
"B":   PN = "2"  !CDS_PN = "2";
BODY = "Q_RES","I123": #LOCATION = "R6318" !CDS_LOCATION = "R6318" &SEC = "1" #&CDS_SEC = "1";
"A":   PN = "1"  !CDS_PN = "1";
"B":   PN = "2"  !CDS_PN = "2";
BODY = "Q_RES","I124": #LOCATION = "R6317" !CDS_LOCATION = "R6317" &SEC = "1" #&CDS_SEC = "1";
"A":   PN = "1"  !CDS_PN = "1";
"B":   PN = "2"  !CDS_PN = "2";
BODY = "Q_CAP","I127": #LOCATION = "C6088" !CDS_LOCATION = "C6088" &SEC = "1" #&CDS_SEC = "1";
"A":   PN = "1"  !CDS_PN = "1";
"B":   PN = "2"  !CDS_PN = "2";
BODY = "Q_RES","I129": #LOCATION = "R6321" !CDS_LOCATION = "R6321" &SEC = "1" #&CDS_SEC = "1";
"A":   PN = "1"  !CDS_PN = "1";
"B":   PN = "2"  !CDS_PN = "2";
BODY = "Q_RES","I131": #LOCATION = "R6322" !CDS_LOCATION = "R6322" &SEC = "1" #&CDS_SEC = "1";
"A":   PN = "1"  !CDS_PN = "1";
"B":   PN = "2"  !CDS_PN = "2";
BODY = "Q_RES","I134": #LOCATION = "R6261" !CDS_LOCATION = "R6261" &SEC = "1" #&CDS_SEC = "1";
"A":   PN = "1"  !CDS_PN = "1";
"B":   PN = "2"  !CDS_PN = "2";
BODY = "Q_RES","I136": #LOCATION = "R6266" !CDS_LOCATION = "R6266" &SEC = "1" #&CDS_SEC = "1";
"A":   PN = "1"  !CDS_PN = "1";
"B":   PN = "2"  !CDS_PN = "2";
BODY = "Q_RES","I137": #LOCATION = "R6314" !CDS_LOCATION = "R6314" &SEC = "1" #&CDS_SEC = "1";
"A":   PN = "1"  !CDS_PN = "1";
"B":   PN = "2"  !CDS_PN = "2";
BODY = "Q_RES","I138": #LOCATION = "R6313" !CDS_LOCATION = "R6313" &SEC = "1" #&CDS_SEC = "1";
"A":   PN = "1"  !CDS_PN = "1";
"B":   PN = "2"  !CDS_PN = "2";
BODY = "Q_RES","I140": #LOCATION = "R6315" !CDS_LOCATION = "R6315" &SEC = "1" #&CDS_SEC = "1";
"A":   PN = "1"  !CDS_PN = "1";
"B":   PN = "2"  !CDS_PN = "2";
BODY = "Q_RES","I143": #LOCATION = "R6270" !CDS_LOCATION = "R6270" &SEC = "1" #&CDS_SEC = "1";
"A":   PN = "1"  !CDS_PN = "1";
"B":   PN = "2"  !CDS_PN = "2";
BODY = "Q_CAP","I145": #LOCATION = "C6089" !CDS_LOCATION = "C6089" &SEC = "1" #&CDS_SEC = "1";
"A":   PN = "1"  !CDS_PN = "1";
"B":   PN = "2"  !CDS_PN = "2";
BODY = "Q_RES","I149": #LOCATION = "R6268" !CDS_LOCATION = "R6268" &SEC = "1" #&CDS_SEC = "1";
"A":   PN = "1"  !CDS_PN = "1";
"B":   PN = "2"  !CDS_PN = "2";
BODY = "Q_RES","I151": #LOCATION = "R6264" !CDS_LOCATION = "R6264" &SEC = "1" #&CDS_SEC = "1";
"A":   PN = "1"  !CDS_PN = "1";
"B":   PN = "2"  !CDS_PN = "2";
BODY = "Q_RES","I155": #LOCATION = "R6263" !CDS_LOCATION = "R6263" &SEC = "1" #&CDS_SEC = "1";
"A":   PN = "1"  !CDS_PN = "1";
"B":   PN = "2"  !CDS_PN = "2";
BODY = "Q_RES","I164": #LOCATION = "R6258" !CDS_LOCATION = "R6258" &SEC = "1" #&CDS_SEC = "1";
"A":   PN = "1"  !CDS_PN = "1";
"B":   PN = "2"  !CDS_PN = "2";
BODY = "Q_RES","I166": #LOCATION = "R6259" !CDS_LOCATION = "R6259" &SEC = "1" #&CDS_SEC = "1";
"A":   PN = "1"  !CDS_PN = "1";
"B":   PN = "2"  !CDS_PN = "2";
BODY = "Q_RES","I169": #LOCATION = "R6303" !CDS_LOCATION = "R6303" &SEC = "1" #&CDS_SEC = "1";
"A":   PN = "1"  !CDS_PN = "1";
"B":   PN = "2"  !CDS_PN = "2";
BODY = "Q_RES","I175": #LOCATION = "R6302" !CDS_LOCATION = "R6302" &SEC = "1" #&CDS_SEC = "1";
"A":   PN = "1"  !CDS_PN = "1";
"B":   PN = "2"  !CDS_PN = "2";
BODY = "Q_RES","I179": #LOCATION = "R6301" !CDS_LOCATION = "R6301" &SEC = "1" #&CDS_SEC = "1";
"A":   PN = "1"  !CDS_PN = "1";
"B":   PN = "2"  !CDS_PN = "2";
BODY = "Q_RES","I180": #LOCATION = "R6299" !CDS_LOCATION = "R6299" &SEC = "1" #&CDS_SEC = "1";
"A":   PN = "1"  !CDS_PN = "1";
"B":   PN = "2"  !CDS_PN = "2";
BODY = "Q_RES","I181": #LOCATION = "R6300" !CDS_LOCATION = "R6300" &SEC = "1" #&CDS_SEC = "1";
"A":   PN = "1"  !CDS_PN = "1";
"B":   PN = "2"  !CDS_PN = "2";
BODY = "Q_RES","I182": #LOCATION = "R6295" !CDS_LOCATION = "R6295" &SEC = "1" #&CDS_SEC = "1";
"A":   PN = "1"  !CDS_PN = "1";
"B":   PN = "2"  !CDS_PN = "2";
BODY = "Q_RES","I183": #LOCATION = "R6296" !CDS_LOCATION = "R6296" &SEC = "1" #&CDS_SEC = "1";
"A":   PN = "1"  !CDS_PN = "1";
"B":   PN = "2"  !CDS_PN = "2";
BODY = "Q_RES","I185": #LOCATION = "R6297" !CDS_LOCATION = "R6297" &SEC = "1" #&CDS_SEC = "1";
"A":   PN = "1"  !CDS_PN = "1";
"B":   PN = "2"  !CDS_PN = "2";
BODY = "Q_RES","I187": #LOCATION = "R6298" !CDS_LOCATION = "R6298" &SEC = "1" #&CDS_SEC = "1";
"A":   PN = "1"  !CDS_PN = "1";
"B":   PN = "2"  !CDS_PN = "2";
BODY = "Q_RES","I188": #LOCATION = "R6330" !CDS_LOCATION = "R6330" &SEC = "1" #&CDS_SEC = "1";
"A":   PN = "1"  !CDS_PN = "1";
"B":   PN = "2"  !CDS_PN = "2";
BODY = "Q_RES","I192": #LOCATION = "R6285" !CDS_LOCATION = "R6285" &SEC = "1" #&CDS_SEC = "1";
"A":   PN = "1"  !CDS_PN = "1";
"B":   PN = "2"  !CDS_PN = "2";
BODY = "Q_RES","I193": #LOCATION = "R6286" !CDS_LOCATION = "R6286" &SEC = "1" #&CDS_SEC = "1";
"A":   PN = "1"  !CDS_PN = "1";
"B":   PN = "2"  !CDS_PN = "2";
BODY = "Q_RES","I195": #LOCATION = "R6289" !CDS_LOCATION = "R6289" &SEC = "1" #&CDS_SEC = "1";
"A":   PN = "1"  !CDS_PN = "1";
"B":   PN = "2"  !CDS_PN = "2";
BODY = "Q_RES","I197": #LOCATION = "R6287" !CDS_LOCATION = "R6287" &SEC = "1" #&CDS_SEC = "1";
"A":   PN = "1"  !CDS_PN = "1";
"B":   PN = "2"  !CDS_PN = "2";
BODY = "Q_RES","I198": #LOCATION = "R6288" !CDS_LOCATION = "R6288" &SEC = "1" #&CDS_SEC = "1";
"A":   PN = "1"  !CDS_PN = "1";
"B":   PN = "2"  !CDS_PN = "2";
BODY = "Q_RES","I200": #LOCATION = "R6311" !CDS_LOCATION = "R6311" &SEC = "1" #&CDS_SEC = "1";
"A":   PN = "1"  !CDS_PN = "1";
"B":   PN = "2"  !CDS_PN = "2";
BODY = "Q_RES","I202": #LOCATION = "R6310" !CDS_LOCATION = "R6310" &SEC = "1" #&CDS_SEC = "1";
"A":   PN = "1"  !CDS_PN = "1";
"B":   PN = "2"  !CDS_PN = "2";
BODY = "Q_RES","I205": #LOCATION = "R6312" !CDS_LOCATION = "R6312" #SEC = "1" !CDS_SEC = "1";
"A":   PN = "1"  !CDS_PN = "1";
"B":   PN = "2"  !CDS_PN = "2";
BODY = "Q_RES","I207": #LOCATION = "R6331" !CDS_LOCATION = "R6331" &SEC = "1" #&CDS_SEC = "1";
"A":   PN = "1"  !CDS_PN = "1";
"B":   PN = "2"  !CDS_PN = "2";
BODY = "Q_RES","I208": #LOCATION = "R6332" !CDS_LOCATION = "R6332" &SEC = "1" #&CDS_SEC = "1";
"A":   PN = "1"  !CDS_PN = "1";
"B":   PN = "2"  !CDS_PN = "2";
BODY = "Q_RES","I212": #LOCATION = "R6320" !CDS_LOCATION = "R6320" &SEC = "1" #&CDS_SEC = "1";
"A":   PN = "1"  !CDS_PN = "1";
"B":   PN = "2"  !CDS_PN = "2";
BODY = "Q_RES","I213": #LOCATION = "R6329" !CDS_LOCATION = "R6329" &SEC = "1" #&CDS_SEC = "1";
"A":   PN = "1"  !CDS_PN = "1";
"B":   PN = "2"  !CDS_PN = "2";
DRAWING = "@t6g_mb_lib.t6g(sch_1):page130";
BODY = "NC7SB3157P6X","I1": #LOCATION = "U8000" !CDS_LOCATION = "U8000" #SEC = "1" !CDS_SEC = "1";
"A":   PN = "4"  !CDS_PN = "4";
"B0":   PN = "3"  !CDS_PN = "3";
"B1":   PN = "1"  !CDS_PN = "1";
"GND":   PN = "2"  !CDS_PN = "2";
"S":   PN = "6"  !CDS_PN = "6";
"VCC":   PN = "5"  !CDS_PN = "5";
BODY = "Q_CAP","I4": #LOCATION = "C8007" !CDS_LOCATION = "C8007" &SEC = "1" #&CDS_SEC = "1";
"A":   PN = "1"  !CDS_PN = "1";
"B":   PN = "2"  !CDS_PN = "2";
BODY = "Q_RES","I11": #LOCATION = "R8035" !CDS_LOCATION = "R8035" &SEC = "1" #&CDS_SEC = "1";
"A":   PN = "1"  !CDS_PN = "1";
"B":   PN = "2"  !CDS_PN = "2";
BODY = "Q_RES","I12": #LOCATION = "R8036" !CDS_LOCATION = "R8036" &SEC = "1" #&CDS_SEC = "1";
"A":   PN = "1"  !CDS_PN = "1";
"B":   PN = "2"  !CDS_PN = "2";
BODY = "Q_RES","I23": #LOCATION = "R8034" !CDS_LOCATION = "R8034" #SEC = "1" !CDS_SEC = "1";
"A":   PN = "1"  !CDS_PN = "1";
"B":   PN = "2"  !CDS_PN = "2";
BODY = "Q_RES","I24": #LOCATION = "R1197" !CDS_LOCATION = "R1197" &SEC = "1" #&CDS_SEC = "1";
"A":   PN = "1"  !CDS_PN = "1";
"B":   PN = "2"  !CDS_PN = "2";
DRAWING = "@t6g_mb_lib.t6g(sch_1):page381";
BODY = "PT5161LRS","I3": #LOCATION = "U6010" !CDS_LOCATION = "U6010" &SEC = "8" #&CDS_SEC = "8";
"B_PERN0":   PN = "R35"  !CDS_PN = "R35";
"B_PERN1":   PN = "AB35"  !CDS_PN = "AB35";
"B_PERN2":   PN = "AJ35"  !CDS_PN = "AJ35";
"B_PERN3":   PN = "AT35"  !CDS_PN = "AT35";
"B_PERN4":   PN = "BC35"  !CDS_PN = "BC35";
"B_PERN5":   PN = "BK35"  !CDS_PN = "BK35";
"B_PERN6":   PN = "BU35"  !CDS_PN = "BU35";
"B_PERN7":   PN = "CD35"  !CDS_PN = "CD35";
"B_PERP0":   PN = "N34"  !CDS_PN = "N34";
"B_PERP1":   PN = "Y34"  !CDS_PN = "Y34";
"B_PERP2":   PN = "AG34"  !CDS_PN = "AG34";
"B_PERP3":   PN = "AP34"  !CDS_PN = "AP34";
"B_PERP4":   PN = "BA34"  !CDS_PN = "BA34";
"B_PERP5":   PN = "BH34"  !CDS_PN = "BH34";
"B_PERP6":   PN = "BR34"  !CDS_PN = "BR34";
"B_PERP7":   PN = "CB34"  !CDS_PN = "CB34";
BODY = "PT5161LRS","I4": #LOCATION = "U6010" !CDS_LOCATION = "U6010" &SEC = "9" #&CDS_SEC = "9";
"B_PERN8":   PN = "CL35"  !CDS_PN = "CL35";
"B_PERN9":   PN = "CV35"  !CDS_PN = "CV35";
"B_PERN10":   PN = "DE35"  !CDS_PN = "DE35";
"B_PERN11":   PN = "DM35"  !CDS_PN = "DM35";
"B_PERN12":   PN = "DW35"  !CDS_PN = "DW35";
"B_PERN13":   PN = "EF35"  !CDS_PN = "EF35";
"B_PERN14":   PN = "EN35"  !CDS_PN = "EN35";
"B_PERN15":   PN = "EY35"  !CDS_PN = "EY35";
"B_PERP8":   PN = "CJ34"  !CDS_PN = "CJ34";
"B_PERP9":   PN = "CT34"  !CDS_PN = "CT34";
"B_PERP10":   PN = "DC34"  !CDS_PN = "DC34";
"B_PERP11":   PN = "DK34"  !CDS_PN = "DK34";
"B_PERP12":   PN = "DU34"  !CDS_PN = "DU34";
"B_PERP13":   PN = "ED34"  !CDS_PN = "ED34";
"B_PERP14":   PN = "EL34"  !CDS_PN = "EL34";
"B_PERP15":   PN = "EV34"  !CDS_PN = "EV34";
DRAWING = "@t6g_mb_lib.t6g(sch_1):page382";
BODY = "PT5161LRS","I2": #LOCATION = "U6010" !CDS_LOCATION = "U6010" &SEC = "6" #&CDS_SEC = "6";
"A_PETN0":   PN = "P29"  !CDS_PN = "P29";
"A_PETN1":   PN = "AA29"  !CDS_PN = "AA29";
"A_PETN2":   PN = "AH29"  !CDS_PN = "AH29";
"A_PETN3":   PN = "AR29"  !CDS_PN = "AR29";
"A_PETN4":   PN = "BB29"  !CDS_PN = "BB29";
"A_PETN5":   PN = "BJ29"  !CDS_PN = "BJ29";
"A_PETN6":   PN = "BT29"  !CDS_PN = "BT29";
"A_PETN7":   PN = "CC29"  !CDS_PN = "CC29";
"A_PETP0":   PN = "M26"  !CDS_PN = "M26";
"A_PETP1":   PN = "W26"  !CDS_PN = "W26";
"A_PETP2":   PN = "AF26"  !CDS_PN = "AF26";
"A_PETP3":   PN = "AN26"  !CDS_PN = "AN26";
"A_PETP4":   PN = "AY26"  !CDS_PN = "AY26";
"A_PETP5":   PN = "BG26"  !CDS_PN = "BG26";
"A_PETP6":   PN = "BP26"  !CDS_PN = "BP26";
"A_PETP7":   PN = "CA26"  !CDS_PN = "CA26";
BODY = "PT5161LRS","I3": #LOCATION = "U6010" !CDS_LOCATION = "U6010" &SEC = "7" #&CDS_SEC = "7";
"A_PETN8":   PN = "CK29"  !CDS_PN = "CK29";
"A_PETN9":   PN = "CU29"  !CDS_PN = "CU29";
"A_PETN10":   PN = "DD29"  !CDS_PN = "DD29";
"A_PETN11":   PN = "DL29"  !CDS_PN = "DL29";
"A_PETN12":   PN = "DV29"  !CDS_PN = "DV29";
"A_PETN13":   PN = "EE29"  !CDS_PN = "EE29";
"A_PETN14":   PN = "EM29"  !CDS_PN = "EM29";
"A_PETN15":   PN = "EW29"  !CDS_PN = "EW29";
"A_PETP8":   PN = "CH26"  !CDS_PN = "CH26";
"A_PETP9":   PN = "CR26"  !CDS_PN = "CR26";
"A_PETP10":   PN = "DB26"  !CDS_PN = "DB26";
"A_PETP11":   PN = "DJ26"  !CDS_PN = "DJ26";
"A_PETP12":   PN = "DT26"  !CDS_PN = "DT26";
"A_PETP13":   PN = "EC26"  !CDS_PN = "EC26";
"A_PETP14":   PN = "EK26"  !CDS_PN = "EK26";
"A_PETP15":   PN = "EU26"  !CDS_PN = "EU26";
DRAWING = "@t6g_mb_lib.t6g(sch_1):page383";
BODY = "PT5161LRS","I3": #LOCATION = "U6010" !CDS_LOCATION = "U6010" &SEC = "2" #&CDS_SEC = "2";
"A_PERN8":   PN = "CJ2"  !CDS_PN = "CJ2";
"A_PERN9":   PN = "CT2"  !CDS_PN = "CT2";
"A_PERN10":   PN = "DC2"  !CDS_PN = "DC2";
"A_PERN11":   PN = "DK2"  !CDS_PN = "DK2";
"A_PERN12":   PN = "DU2"  !CDS_PN = "DU2";
"A_PERN13":   PN = "ED2"  !CDS_PN = "ED2";
"A_PERN14":   PN = "EL2"  !CDS_PN = "EL2";
"A_PERN15":   PN = "EV2"  !CDS_PN = "EV2";
"A_PERP8":   PN = "CL1"  !CDS_PN = "CL1";
"A_PERP9":   PN = "CV1"  !CDS_PN = "CV1";
"A_PERP10":   PN = "DE1"  !CDS_PN = "DE1";
"A_PERP11":   PN = "DM1"  !CDS_PN = "DM1";
"A_PERP12":   PN = "DW1"  !CDS_PN = "DW1";
"A_PERP13":   PN = "EF1"  !CDS_PN = "EF1";
"A_PERP14":   PN = "EN1"  !CDS_PN = "EN1";
"A_PERP15":   PN = "EY1"  !CDS_PN = "EY1";
BODY = "PT5161LRS","I4": #LOCATION = "U6010" !CDS_LOCATION = "U6010" &SEC = "1" #&CDS_SEC = "1";
"A_PERN0":   PN = "N2"  !CDS_PN = "N2";
"A_PERN1":   PN = "Y2"  !CDS_PN = "Y2";
"A_PERN2":   PN = "AG2"  !CDS_PN = "AG2";
"A_PERN3":   PN = "AP2"  !CDS_PN = "AP2";
"A_PERN4":   PN = "BA2"  !CDS_PN = "BA2";
"A_PERN5":   PN = "BH2"  !CDS_PN = "BH2";
"A_PERN6":   PN = "BR2"  !CDS_PN = "BR2";
"A_PERN7":   PN = "CB2"  !CDS_PN = "CB2";
"A_PERP0":   PN = "R1"  !CDS_PN = "R1";
"A_PERP1":   PN = "AB1"  !CDS_PN = "AB1";
"A_PERP2":   PN = "AJ1"  !CDS_PN = "AJ1";
"A_PERP3":   PN = "AT1"  !CDS_PN = "AT1";
"A_PERP4":   PN = "BC1"  !CDS_PN = "BC1";
"A_PERP5":   PN = "BK1"  !CDS_PN = "BK1";
"A_PERP6":   PN = "BU1"  !CDS_PN = "BU1";
"A_PERP7":   PN = "CD1"  !CDS_PN = "CD1";
DRAWING = "@t6g_mb_lib.t6g(sch_1):page384";
BODY = "PT5161LRS","I1": #LOCATION = "U6010" !CDS_LOCATION = "U6010" &SEC = "10" #&CDS_SEC = "10";
"B_PETN0":   PN = "P10"  !CDS_PN = "P10";
"B_PETN1":   PN = "AA10"  !CDS_PN = "AA10";
"B_PETN2":   PN = "AH10"  !CDS_PN = "AH10";
"B_PETN3":   PN = "AR10"  !CDS_PN = "AR10";
"B_PETN4":   PN = "BB10"  !CDS_PN = "BB10";
"B_PETN5":   PN = "BJ10"  !CDS_PN = "BJ10";
"B_PETN6":   PN = "BT10"  !CDS_PN = "BT10";
"B_PETN7":   PN = "CC10"  !CDS_PN = "CC10";
"B_PETP0":   PN = "M7"  !CDS_PN = "M7";
"B_PETP1":   PN = "W7"  !CDS_PN = "W7";
"B_PETP2":   PN = "AF7"  !CDS_PN = "AF7";
"B_PETP3":   PN = "AN7"  !CDS_PN = "AN7";
"B_PETP4":   PN = "AY7"  !CDS_PN = "AY7";
"B_PETP5":   PN = "BG7"  !CDS_PN = "BG7";
"B_PETP6":   PN = "BP7"  !CDS_PN = "BP7";
"B_PETP7":   PN = "CA7"  !CDS_PN = "CA7";
BODY = "PT5161LRS","I2": #LOCATION = "U6010" !CDS_LOCATION = "U6010" &SEC = "11" #&CDS_SEC = "11";
"B_PETN8":   PN = "CK10"  !CDS_PN = "CK10";
"B_PETN9":   PN = "CU10"  !CDS_PN = "CU10";
"B_PETN10":   PN = "DD10"  !CDS_PN = "DD10";
"B_PETN11":   PN = "DL10"  !CDS_PN = "DL10";
"B_PETN12":   PN = "DV10"  !CDS_PN = "DV10";
"B_PETN13":   PN = "EE10"  !CDS_PN = "EE10";
"B_PETN14":   PN = "EM10"  !CDS_PN = "EM10";
"B_PETN15":   PN = "EW10"  !CDS_PN = "EW10";
"B_PETP8":   PN = "CH7"  !CDS_PN = "CH7";
"B_PETP9":   PN = "CR7"  !CDS_PN = "CR7";
"B_PETP10":   PN = "DB7"  !CDS_PN = "DB7";
"B_PETP11":   PN = "DJ7"  !CDS_PN = "DJ7";
"B_PETP12":   PN = "DT7"  !CDS_PN = "DT7";
"B_PETP13":   PN = "EC7"  !CDS_PN = "EC7";
"B_PETP14":   PN = "EK7"  !CDS_PN = "EK7";
"B_PETP15":   PN = "EU7"  !CDS_PN = "EU7";
BODY = "Q_CAP_DIFFBUS","I59": #LOCATION = "C6516" !CDS_LOCATION = "C6516" &SEC = "1" #&CDS_SEC = "1";
"1":   PN = "1"  !CDS_PN = "1";
"2":   PN = "2"  !CDS_PN = "2";
BODY = "Q_CAP_DIFFBUS","I60": #LOCATION = "C6513" !CDS_LOCATION = "C6513" &SEC = "1" #&CDS_SEC = "1";
"1":   PN = "1"  !CDS_PN = "1";
"2":   PN = "2"  !CDS_PN = "2";
BODY = "Q_CAP_DIFFBUS","I61": #LOCATION = "C6514" !CDS_LOCATION = "C6514" &SEC = "1" #&CDS_SEC = "1";
"1":   PN = "1"  !CDS_PN = "1";
"2":   PN = "2"  !CDS_PN = "2";
BODY = "Q_CAP_DIFFBUS","I62": #LOCATION = "C6515" !CDS_LOCATION = "C6515" &SEC = "1" #&CDS_SEC = "1";
"1":   PN = "1"  !CDS_PN = "1";
"2":   PN = "2"  !CDS_PN = "2";
BODY = "Q_CAP_DIFFBUS","I63": #LOCATION = "C6511" !CDS_LOCATION = "C6511" &SEC = "1" #&CDS_SEC = "1";
"1":   PN = "1"  !CDS_PN = "1";
"2":   PN = "2"  !CDS_PN = "2";
BODY = "Q_CAP_DIFFBUS","I64": #LOCATION = "C6512" !CDS_LOCATION = "C6512" &SEC = "1" #&CDS_SEC = "1";
"1":   PN = "1"  !CDS_PN = "1";
"2":   PN = "2"  !CDS_PN = "2";
BODY = "Q_CAP_DIFFBUS","I65": #LOCATION = "C6509" !CDS_LOCATION = "C6509" &SEC = "1" #&CDS_SEC = "1";
"1":   PN = "1"  !CDS_PN = "1";
"2":   PN = "2"  !CDS_PN = "2";
BODY = "Q_CAP_DIFFBUS","I66": #LOCATION = "C6510" !CDS_LOCATION = "C6510" &SEC = "1" #&CDS_SEC = "1";
"1":   PN = "1"  !CDS_PN = "1";
"2":   PN = "2"  !CDS_PN = "2";
BODY = "Q_CAP_DIFFBUS","I71": #LOCATION = "C6508" !CDS_LOCATION = "C6508" &SEC = "1" #&CDS_SEC = "1";
"1":   PN = "1"  !CDS_PN = "1";
"2":   PN = "2"  !CDS_PN = "2";
BODY = "Q_CAP_DIFFBUS","I72": #LOCATION = "C6506" !CDS_LOCATION = "C6506" &SEC = "1" #&CDS_SEC = "1";
"1":   PN = "1"  !CDS_PN = "1";
"2":   PN = "2"  !CDS_PN = "2";
BODY = "Q_CAP_DIFFBUS","I73": #LOCATION = "C6507" !CDS_LOCATION = "C6507" &SEC = "1" #&CDS_SEC = "1";
"1":   PN = "1"  !CDS_PN = "1";
"2":   PN = "2"  !CDS_PN = "2";
BODY = "Q_CAP_DIFFBUS","I74": #LOCATION = "C6505" !CDS_LOCATION = "C6505" &SEC = "1" #&CDS_SEC = "1";
"1":   PN = "1"  !CDS_PN = "1";
"2":   PN = "2"  !CDS_PN = "2";
BODY = "Q_CAP_DIFFBUS","I75": #LOCATION = "C6503" !CDS_LOCATION = "C6503" &SEC = "1" #&CDS_SEC = "1";
"1":   PN = "1"  !CDS_PN = "1";
"2":   PN = "2"  !CDS_PN = "2";
BODY = "Q_CAP_DIFFBUS","I76": #LOCATION = "C6504" !CDS_LOCATION = "C6504" &SEC = "1" #&CDS_SEC = "1";
"1":   PN = "1"  !CDS_PN = "1";
"2":   PN = "2"  !CDS_PN = "2";
BODY = "Q_CAP_DIFFBUS","I77": #LOCATION = "C6501" !CDS_LOCATION = "C6501" &SEC = "1" #&CDS_SEC = "1";
"1":   PN = "1"  !CDS_PN = "1";
"2":   PN = "2"  !CDS_PN = "2";
BODY = "Q_CAP_DIFFBUS","I78": #LOCATION = "C6502" !CDS_LOCATION = "C6502" &SEC = "1" #&CDS_SEC = "1";
"1":   PN = "1"  !CDS_PN = "1";
"2":   PN = "2"  !CDS_PN = "2";
BODY = "Q_CAP_DIFFBUS","I99": #LOCATION = "C6517" !CDS_LOCATION = "C6517" &SEC = "1" #&CDS_SEC = "1";
"1":   PN = "1"  !CDS_PN = "1";
"2":   PN = "2"  !CDS_PN = "2";
BODY = "Q_CAP_DIFFBUS","I100": #LOCATION = "C6518" !CDS_LOCATION = "C6518" &SEC = "1" #&CDS_SEC = "1";
"1":   PN = "1"  !CDS_PN = "1";
"2":   PN = "2"  !CDS_PN = "2";
BODY = "Q_CAP_DIFFBUS","I101": #LOCATION = "C6520" !CDS_LOCATION = "C6520" &SEC = "1" #&CDS_SEC = "1";
"1":   PN = "1"  !CDS_PN = "1";
"2":   PN = "2"  !CDS_PN = "2";
BODY = "Q_CAP_DIFFBUS","I102": #LOCATION = "C6519" !CDS_LOCATION = "C6519" &SEC = "1" #&CDS_SEC = "1";
"1":   PN = "1"  !CDS_PN = "1";
"2":   PN = "2"  !CDS_PN = "2";
BODY = "Q_CAP_DIFFBUS","I118": #LOCATION = "C6522" !CDS_LOCATION = "C6522" &SEC = "1" #&CDS_SEC = "1";
"1":   PN = "1"  !CDS_PN = "1";
"2":   PN = "2"  !CDS_PN = "2";
BODY = "Q_CAP_DIFFBUS","I119": #LOCATION = "C6521" !CDS_LOCATION = "C6521" &SEC = "1" #&CDS_SEC = "1";
"1":   PN = "1"  !CDS_PN = "1";
"2":   PN = "2"  !CDS_PN = "2";
BODY = "Q_CAP_DIFFBUS","I120": #LOCATION = "C6523" !CDS_LOCATION = "C6523" &SEC = "1" #&CDS_SEC = "1";
"1":   PN = "1"  !CDS_PN = "1";
"2":   PN = "2"  !CDS_PN = "2";
BODY = "Q_CAP_DIFFBUS","I121": #LOCATION = "C6524" !CDS_LOCATION = "C6524" &SEC = "1" #&CDS_SEC = "1";
"1":   PN = "1"  !CDS_PN = "1";
"2":   PN = "2"  !CDS_PN = "2";
BODY = "Q_CAP_DIFFBUS","I122": #LOCATION = "C6526" !CDS_LOCATION = "C6526" &SEC = "1" #&CDS_SEC = "1";
"1":   PN = "1"  !CDS_PN = "1";
"2":   PN = "2"  !CDS_PN = "2";
BODY = "Q_CAP_DIFFBUS","I123": #LOCATION = "C6525" !CDS_LOCATION = "C6525" &SEC = "1" #&CDS_SEC = "1";
"1":   PN = "1"  !CDS_PN = "1";
"2":   PN = "2"  !CDS_PN = "2";
BODY = "Q_CAP_DIFFBUS","I124": #LOCATION = "C6527" !CDS_LOCATION = "C6527" &SEC = "1" #&CDS_SEC = "1";
"1":   PN = "1"  !CDS_PN = "1";
"2":   PN = "2"  !CDS_PN = "2";
BODY = "Q_CAP_DIFFBUS","I125": #LOCATION = "C6528" !CDS_LOCATION = "C6528" &SEC = "1" #&CDS_SEC = "1";
"1":   PN = "1"  !CDS_PN = "1";
"2":   PN = "2"  !CDS_PN = "2";
BODY = "Q_CAP_DIFFBUS","I126": #LOCATION = "C6529" !CDS_LOCATION = "C6529" &SEC = "1" #&CDS_SEC = "1";
"1":   PN = "1"  !CDS_PN = "1";
"2":   PN = "2"  !CDS_PN = "2";
BODY = "Q_CAP_DIFFBUS","I127": #LOCATION = "C6530" !CDS_LOCATION = "C6530" &SEC = "1" #&CDS_SEC = "1";
"1":   PN = "1"  !CDS_PN = "1";
"2":   PN = "2"  !CDS_PN = "2";
BODY = "Q_CAP_DIFFBUS","I129": #LOCATION = "C6531" !CDS_LOCATION = "C6531" &SEC = "1" #&CDS_SEC = "1";
"1":   PN = "1"  !CDS_PN = "1";
"2":   PN = "2"  !CDS_PN = "2";
BODY = "Q_CAP_DIFFBUS","I130": #LOCATION = "C6532" !CDS_LOCATION = "C6532" &SEC = "1" #&CDS_SEC = "1";
"1":   PN = "1"  !CDS_PN = "1";
"2":   PN = "2"  !CDS_PN = "2";
DRAWING = "@t6g_mb_lib.t6g(sch_1):page393";
BODY = "Q_CAP_DIFFBUS","I17": #LOCATION = "C6676" !CDS_LOCATION = "C6676" &SEC = "1" #&CDS_SEC = "1";
"1":   PN = "1"  !CDS_PN = "1";
"2":   PN = "2"  !CDS_PN = "2";
BODY = "Q_CAP_DIFFBUS","I18": #LOCATION = "C6675" !CDS_LOCATION = "C6675" &SEC = "1" #&CDS_SEC = "1";
"1":   PN = "1"  !CDS_PN = "1";
"2":   PN = "2"  !CDS_PN = "2";
BODY = "Q_CAP_DIFFBUS","I19": #LOCATION = "C6674" !CDS_LOCATION = "C6674" &SEC = "1" #&CDS_SEC = "1";
"1":   PN = "1"  !CDS_PN = "1";
"2":   PN = "2"  !CDS_PN = "2";
BODY = "Q_CAP_DIFFBUS","I20": #LOCATION = "C6673" !CDS_LOCATION = "C6673" &SEC = "1" #&CDS_SEC = "1";
"1":   PN = "1"  !CDS_PN = "1";
"2":   PN = "2"  !CDS_PN = "2";
BODY = "Q_CAP_DIFFBUS","I23": #LOCATION = "C6672" !CDS_LOCATION = "C6672" &SEC = "1" #&CDS_SEC = "1";
"1":   PN = "1"  !CDS_PN = "1";
"2":   PN = "2"  !CDS_PN = "2";
BODY = "Q_CAP_DIFFBUS","I24": #LOCATION = "C6671" !CDS_LOCATION = "C6671" &SEC = "1" #&CDS_SEC = "1";
"1":   PN = "1"  !CDS_PN = "1";
"2":   PN = "2"  !CDS_PN = "2";
BODY = "Q_CAP_DIFFBUS","I25": #LOCATION = "C6670" !CDS_LOCATION = "C6670" &SEC = "1" #&CDS_SEC = "1";
"1":   PN = "1"  !CDS_PN = "1";
"2":   PN = "2"  !CDS_PN = "2";
BODY = "Q_CAP_DIFFBUS","I26": #LOCATION = "C6669" !CDS_LOCATION = "C6669" &SEC = "1" #&CDS_SEC = "1";
"1":   PN = "1"  !CDS_PN = "1";
"2":   PN = "2"  !CDS_PN = "2";
BODY = "Q_CAP_DIFFBUS","I27": #LOCATION = "C6667" !CDS_LOCATION = "C6667" &SEC = "1" #&CDS_SEC = "1";
"1":   PN = "1"  !CDS_PN = "1";
"2":   PN = "2"  !CDS_PN = "2";
BODY = "Q_CAP_DIFFBUS","I28": #LOCATION = "C6668" !CDS_LOCATION = "C6668" &SEC = "1" #&CDS_SEC = "1";
"1":   PN = "1"  !CDS_PN = "1";
"2":   PN = "2"  !CDS_PN = "2";
BODY = "Q_CAP_DIFFBUS","I29": #LOCATION = "C6666" !CDS_LOCATION = "C6666" &SEC = "1" #&CDS_SEC = "1";
"1":   PN = "1"  !CDS_PN = "1";
"2":   PN = "2"  !CDS_PN = "2";
BODY = "Q_CAP_DIFFBUS","I30": #LOCATION = "C6665" !CDS_LOCATION = "C6665" &SEC = "1" #&CDS_SEC = "1";
"1":   PN = "1"  !CDS_PN = "1";
"2":   PN = "2"  !CDS_PN = "2";
BODY = "Q_CAP_DIFFBUS","I31": #LOCATION = "C6663" !CDS_LOCATION = "C6663" &SEC = "1" #&CDS_SEC = "1";
"1":   PN = "1"  !CDS_PN = "1";
"2":   PN = "2"  !CDS_PN = "2";
BODY = "Q_CAP_DIFFBUS","I32": #LOCATION = "C6664" !CDS_LOCATION = "C6664" &SEC = "1" #&CDS_SEC = "1";
"1":   PN = "1"  !CDS_PN = "1";
"2":   PN = "2"  !CDS_PN = "2";
BODY = "Q_CAP_DIFFBUS","I33": #LOCATION = "C6662" !CDS_LOCATION = "C6662" &SEC = "1" #&CDS_SEC = "1";
"1":   PN = "1"  !CDS_PN = "1";
"2":   PN = "2"  !CDS_PN = "2";
BODY = "PT5161LRS","I41": #LOCATION = "U6015" !CDS_LOCATION = "U6015" &SEC = "10" #&CDS_SEC = "10";
"B_PETN0":   PN = "P10"  !CDS_PN = "P10";
"B_PETN1":   PN = "AA10"  !CDS_PN = "AA10";
"B_PETN2":   PN = "AH10"  !CDS_PN = "AH10";
"B_PETN3":   PN = "AR10"  !CDS_PN = "AR10";
"B_PETN4":   PN = "BB10"  !CDS_PN = "BB10";
"B_PETN5":   PN = "BJ10"  !CDS_PN = "BJ10";
"B_PETN6":   PN = "BT10"  !CDS_PN = "BT10";
"B_PETN7":   PN = "CC10"  !CDS_PN = "CC10";
"B_PETP0":   PN = "M7"  !CDS_PN = "M7";
"B_PETP1":   PN = "W7"  !CDS_PN = "W7";
"B_PETP2":   PN = "AF7"  !CDS_PN = "AF7";
"B_PETP3":   PN = "AN7"  !CDS_PN = "AN7";
"B_PETP4":   PN = "AY7"  !CDS_PN = "AY7";
"B_PETP5":   PN = "BG7"  !CDS_PN = "BG7";
"B_PETP6":   PN = "BP7"  !CDS_PN = "BP7";
"B_PETP7":   PN = "CA7"  !CDS_PN = "CA7";
BODY = "Q_CAP_DIFFBUS","I42": #LOCATION = "C6661" !CDS_LOCATION = "C6661" &SEC = "1" #&CDS_SEC = "1";
"1":   PN = "1"  !CDS_PN = "1";
"2":   PN = "2"  !CDS_PN = "2";
BODY = "Q_CAP_DIFFBUS","I84": #LOCATION = "C6692" !CDS_LOCATION = "C6692" &SEC = "1" #&CDS_SEC = "1";
"1":   PN = "1"  !CDS_PN = "1";
"2":   PN = "2"  !CDS_PN = "2";
BODY = "Q_CAP_DIFFBUS","I85": #LOCATION = "C6691" !CDS_LOCATION = "C6691" &SEC = "1" #&CDS_SEC = "1";
"1":   PN = "1"  !CDS_PN = "1";
"2":   PN = "2"  !CDS_PN = "2";
BODY = "Q_CAP_DIFFBUS","I86": #LOCATION = "C6690" !CDS_LOCATION = "C6690" &SEC = "1" #&CDS_SEC = "1";
"1":   PN = "1"  !CDS_PN = "1";
"2":   PN = "2"  !CDS_PN = "2";
BODY = "Q_CAP_DIFFBUS","I87": #LOCATION = "C6689" !CDS_LOCATION = "C6689" &SEC = "1" #&CDS_SEC = "1";
"1":   PN = "1"  !CDS_PN = "1";
"2":   PN = "2"  !CDS_PN = "2";
BODY = "Q_CAP_DIFFBUS","I88": #LOCATION = "C6688" !CDS_LOCATION = "C6688" &SEC = "1" #&CDS_SEC = "1";
"1":   PN = "1"  !CDS_PN = "1";
"2":   PN = "2"  !CDS_PN = "2";
BODY = "Q_CAP_DIFFBUS","I89": #LOCATION = "C6687" !CDS_LOCATION = "C6687" &SEC = "1" #&CDS_SEC = "1";
"1":   PN = "1"  !CDS_PN = "1";
"2":   PN = "2"  !CDS_PN = "2";
BODY = "Q_CAP_DIFFBUS","I95": #LOCATION = "C6686" !CDS_LOCATION = "C6686" &SEC = "1" #&CDS_SEC = "1";
"1":   PN = "1"  !CDS_PN = "1";
"2":   PN = "2"  !CDS_PN = "2";
BODY = "Q_CAP_DIFFBUS","I96": #LOCATION = "C6685" !CDS_LOCATION = "C6685" &SEC = "1" #&CDS_SEC = "1";
"1":   PN = "1"  !CDS_PN = "1";
"2":   PN = "2"  !CDS_PN = "2";
BODY = "Q_CAP_DIFFBUS","I97": #LOCATION = "C6684" !CDS_LOCATION = "C6684" &SEC = "1" #&CDS_SEC = "1";
"1":   PN = "1"  !CDS_PN = "1";
"2":   PN = "2"  !CDS_PN = "2";
BODY = "Q_CAP_DIFFBUS","I98": #LOCATION = "C6683" !CDS_LOCATION = "C6683" &SEC = "1" #&CDS_SEC = "1";
"1":   PN = "1"  !CDS_PN = "1";
"2":   PN = "2"  !CDS_PN = "2";
BODY = "Q_CAP_DIFFBUS","I99": #LOCATION = "C6681" !CDS_LOCATION = "C6681" &SEC = "1" #&CDS_SEC = "1";
"1":   PN = "1"  !CDS_PN = "1";
"2":   PN = "2"  !CDS_PN = "2";
BODY = "Q_CAP_DIFFBUS","I100": #LOCATION = "C6682" !CDS_LOCATION = "C6682" &SEC = "1" #&CDS_SEC = "1";
"1":   PN = "1"  !CDS_PN = "1";
"2":   PN = "2"  !CDS_PN = "2";
BODY = "Q_CAP_DIFFBUS","I101": #LOCATION = "C6679" !CDS_LOCATION = "C6679" &SEC = "1" #&CDS_SEC = "1";
"1":   PN = "1"  !CDS_PN = "1";
"2":   PN = "2"  !CDS_PN = "2";
BODY = "Q_CAP_DIFFBUS","I102": #LOCATION = "C6680" !CDS_LOCATION = "C6680" &SEC = "1" #&CDS_SEC = "1";
"1":   PN = "1"  !CDS_PN = "1";
"2":   PN = "2"  !CDS_PN = "2";
BODY = "Q_CAP_DIFFBUS","I103": #LOCATION = "C6678" !CDS_LOCATION = "C6678" &SEC = "1" #&CDS_SEC = "1";
"1":   PN = "1"  !CDS_PN = "1";
"2":   PN = "2"  !CDS_PN = "2";
BODY = "Q_CAP_DIFFBUS","I104": #LOCATION = "C6677" !CDS_LOCATION = "C6677" &SEC = "1" #&CDS_SEC = "1";
"1":   PN = "1"  !CDS_PN = "1";
"2":   PN = "2"  !CDS_PN = "2";
BODY = "PT5161LRS","I142": #LOCATION = "U6015" !CDS_LOCATION = "U6015" &SEC = "11" #&CDS_SEC = "11";
"B_PETN8":   PN = "CK10"  !CDS_PN = "CK10";
"B_PETN9":   PN = "CU10"  !CDS_PN = "CU10";
"B_PETN10":   PN = "DD10"  !CDS_PN = "DD10";
"B_PETN11":   PN = "DL10"  !CDS_PN = "DL10";
"B_PETN12":   PN = "DV10"  !CDS_PN = "DV10";
"B_PETN13":   PN = "EE10"  !CDS_PN = "EE10";
"B_PETN14":   PN = "EM10"  !CDS_PN = "EM10";
"B_PETN15":   PN = "EW10"  !CDS_PN = "EW10";
"B_PETP8":   PN = "CH7"  !CDS_PN = "CH7";
"B_PETP9":   PN = "CR7"  !CDS_PN = "CR7";
"B_PETP10":   PN = "DB7"  !CDS_PN = "DB7";
"B_PETP11":   PN = "DJ7"  !CDS_PN = "DJ7";
"B_PETP12":   PN = "DT7"  !CDS_PN = "DT7";
"B_PETP13":   PN = "EC7"  !CDS_PN = "EC7";
"B_PETP14":   PN = "EK7"  !CDS_PN = "EK7";
"B_PETP15":   PN = "EU7"  !CDS_PN = "EU7";
DRAWING = "@t6g_mb_lib.t6g(sch_1):page394";
BODY = "PT5161LRS","I1": #LOCATION = "U6015" !CDS_LOCATION = "U6015" &SEC = "1" #&CDS_SEC = "1";
"A_PERN0":   PN = "N2"  !CDS_PN = "N2";
"A_PERN1":   PN = "Y2"  !CDS_PN = "Y2";
"A_PERN2":   PN = "AG2"  !CDS_PN = "AG2";
"A_PERN3":   PN = "AP2"  !CDS_PN = "AP2";
"A_PERN4":   PN = "BA2"  !CDS_PN = "BA2";
"A_PERN5":   PN = "BH2"  !CDS_PN = "BH2";
"A_PERN6":   PN = "BR2"  !CDS_PN = "BR2";
"A_PERN7":   PN = "CB2"  !CDS_PN = "CB2";
"A_PERP0":   PN = "R1"  !CDS_PN = "R1";
"A_PERP1":   PN = "AB1"  !CDS_PN = "AB1";
"A_PERP2":   PN = "AJ1"  !CDS_PN = "AJ1";
"A_PERP3":   PN = "AT1"  !CDS_PN = "AT1";
"A_PERP4":   PN = "BC1"  !CDS_PN = "BC1";
"A_PERP5":   PN = "BK1"  !CDS_PN = "BK1";
"A_PERP6":   PN = "BU1"  !CDS_PN = "BU1";
"A_PERP7":   PN = "CD1"  !CDS_PN = "CD1";
BODY = "PT5161LRS","I38": #LOCATION = "U6015" !CDS_LOCATION = "U6015" &SEC = "2" #&CDS_SEC = "2";
"A_PERN8":   PN = "CJ2"  !CDS_PN = "CJ2";
"A_PERN9":   PN = "CT2"  !CDS_PN = "CT2";
"A_PERN10":   PN = "DC2"  !CDS_PN = "DC2";
"A_PERN11":   PN = "DK2"  !CDS_PN = "DK2";
"A_PERN12":   PN = "DU2"  !CDS_PN = "DU2";
"A_PERN13":   PN = "ED2"  !CDS_PN = "ED2";
"A_PERN14":   PN = "EL2"  !CDS_PN = "EL2";
"A_PERN15":   PN = "EV2"  !CDS_PN = "EV2";
"A_PERP8":   PN = "CL1"  !CDS_PN = "CL1";
"A_PERP9":   PN = "CV1"  !CDS_PN = "CV1";
"A_PERP10":   PN = "DE1"  !CDS_PN = "DE1";
"A_PERP11":   PN = "DM1"  !CDS_PN = "DM1";
"A_PERP12":   PN = "DW1"  !CDS_PN = "DW1";
"A_PERP13":   PN = "EF1"  !CDS_PN = "EF1";
"A_PERP14":   PN = "EN1"  !CDS_PN = "EN1";
"A_PERP15":   PN = "EY1"  !CDS_PN = "EY1";
DRAWING = "@t6g_mb_lib.t6g(sch_1):page395";
BODY = "PT5161LRS","I1": #LOCATION = "U6015" !CDS_LOCATION = "U6015" &SEC = "6" #&CDS_SEC = "6";
"A_PETN0":   PN = "P29"  !CDS_PN = "P29";
"A_PETN1":   PN = "AA29"  !CDS_PN = "AA29";
"A_PETN2":   PN = "AH29"  !CDS_PN = "AH29";
"A_PETN3":   PN = "AR29"  !CDS_PN = "AR29";
"A_PETN4":   PN = "BB29"  !CDS_PN = "BB29";
"A_PETN5":   PN = "BJ29"  !CDS_PN = "BJ29";
"A_PETN6":   PN = "BT29"  !CDS_PN = "BT29";
"A_PETN7":   PN = "CC29"  !CDS_PN = "CC29";
"A_PETP0":   PN = "M26"  !CDS_PN = "M26";
"A_PETP1":   PN = "W26"  !CDS_PN = "W26";
"A_PETP2":   PN = "AF26"  !CDS_PN = "AF26";
"A_PETP3":   PN = "AN26"  !CDS_PN = "AN26";
"A_PETP4":   PN = "AY26"  !CDS_PN = "AY26";
"A_PETP5":   PN = "BG26"  !CDS_PN = "BG26";
"A_PETP6":   PN = "BP26"  !CDS_PN = "BP26";
"A_PETP7":   PN = "CA26"  !CDS_PN = "CA26";
BODY = "PT5161LRS","I38": #LOCATION = "U6015" !CDS_LOCATION = "U6015" &SEC = "7" #&CDS_SEC = "7";
"A_PETN8":   PN = "CK29"  !CDS_PN = "CK29";
"A_PETN9":   PN = "CU29"  !CDS_PN = "CU29";
"A_PETN10":   PN = "DD29"  !CDS_PN = "DD29";
"A_PETN11":   PN = "DL29"  !CDS_PN = "DL29";
"A_PETN12":   PN = "DV29"  !CDS_PN = "DV29";
"A_PETN13":   PN = "EE29"  !CDS_PN = "EE29";
"A_PETN14":   PN = "EM29"  !CDS_PN = "EM29";
"A_PETN15":   PN = "EW29"  !CDS_PN = "EW29";
"A_PETP8":   PN = "CH26"  !CDS_PN = "CH26";
"A_PETP9":   PN = "CR26"  !CDS_PN = "CR26";
"A_PETP10":   PN = "DB26"  !CDS_PN = "DB26";
"A_PETP11":   PN = "DJ26"  !CDS_PN = "DJ26";
"A_PETP12":   PN = "DT26"  !CDS_PN = "DT26";
"A_PETP13":   PN = "EC26"  !CDS_PN = "EC26";
"A_PETP14":   PN = "EK26"  !CDS_PN = "EK26";
"A_PETP15":   PN = "EU26"  !CDS_PN = "EU26";
DRAWING = "@t6g_mb_lib.t6g(sch_1):page396";
BODY = "PT5161LRS","I1": #LOCATION = "U6015" !CDS_LOCATION = "U6015" &SEC = "8" #&CDS_SEC = "8";
"B_PERN0":   PN = "R35"  !CDS_PN = "R35";
"B_PERN1":   PN = "AB35"  !CDS_PN = "AB35";
"B_PERN2":   PN = "AJ35"  !CDS_PN = "AJ35";
"B_PERN3":   PN = "AT35"  !CDS_PN = "AT35";
"B_PERN4":   PN = "BC35"  !CDS_PN = "BC35";
"B_PERN5":   PN = "BK35"  !CDS_PN = "BK35";
"B_PERN6":   PN = "BU35"  !CDS_PN = "BU35";
"B_PERN7":   PN = "CD35"  !CDS_PN = "CD35";
"B_PERP0":   PN = "N34"  !CDS_PN = "N34";
"B_PERP1":   PN = "Y34"  !CDS_PN = "Y34";
"B_PERP2":   PN = "AG34"  !CDS_PN = "AG34";
"B_PERP3":   PN = "AP34"  !CDS_PN = "AP34";
"B_PERP4":   PN = "BA34"  !CDS_PN = "BA34";
"B_PERP5":   PN = "BH34"  !CDS_PN = "BH34";
"B_PERP6":   PN = "BR34"  !CDS_PN = "BR34";
"B_PERP7":   PN = "CB34"  !CDS_PN = "CB34";
BODY = "PT5161LRS","I38": #LOCATION = "U6015" !CDS_LOCATION = "U6015" &SEC = "9" #&CDS_SEC = "9";
"B_PERN8":   PN = "CL35"  !CDS_PN = "CL35";
"B_PERN9":   PN = "CV35"  !CDS_PN = "CV35";
"B_PERN10":   PN = "DE35"  !CDS_PN = "DE35";
"B_PERN11":   PN = "DM35"  !CDS_PN = "DM35";
"B_PERN12":   PN = "DW35"  !CDS_PN = "DW35";
"B_PERN13":   PN = "EF35"  !CDS_PN = "EF35";
"B_PERN14":   PN = "EN35"  !CDS_PN = "EN35";
"B_PERN15":   PN = "EY35"  !CDS_PN = "EY35";
"B_PERP8":   PN = "CJ34"  !CDS_PN = "CJ34";
"B_PERP9":   PN = "CT34"  !CDS_PN = "CT34";
"B_PERP10":   PN = "DC34"  !CDS_PN = "DC34";
"B_PERP11":   PN = "DK34"  !CDS_PN = "DK34";
"B_PERP12":   PN = "DU34"  !CDS_PN = "DU34";
"B_PERP13":   PN = "ED34"  !CDS_PN = "ED34";
"B_PERP14":   PN = "EL34"  !CDS_PN = "EL34";
"B_PERP15":   PN = "EV34"  !CDS_PN = "EV34";
DRAWING = "@t6g_mb_lib.t6g(sch_1):page400";
BODY = "PT5161LRS","I1": #LOCATION = "U6014" !CDS_LOCATION = "U6014" &SEC = "4" #&CDS_SEC = "4";
"PWR_1A_1":   PN = "BV20"  !CDS_PN = "BV20";
"PWR_1A_2":   PN = "CE17"  !CDS_PN = "CE17";
"PWR_1A_3":   PN = "CE20"  !CDS_PN = "CE20";
"PWR_1A_4":   PN = "CM17"  !CDS_PN = "CM17";
"PWR_1A_5":   PN = "CM20"  !CDS_PN = "CM20";
"PWR_1D":   PN = "BV17"  !CDS_PN = "BV17";
"PWR_2A_1":   PN = "AC17"  !CDS_PN = "AC17";
"PWR_2A_2":   PN = "AC20"  !CDS_PN = "AC20";
"PWR_2A_3":   PN = "AK17"  !CDS_PN = "AK17";
"PWR_2A_4":   PN = "AK20"  !CDS_PN = "AK20";
"PWR_2A_5":   PN = "AU17"  !CDS_PN = "AU17";
"PWR_2A_6":   PN = "AU20"  !CDS_PN = "AU20";
"PWR_2A_7":   PN = "BD17"  !CDS_PN = "BD17";
"PWR_2A_8":   PN = "BD20"  !CDS_PN = "BD20";
"PWR_2A_9":   PN = "DF17"  !CDS_PN = "DF17";
"PWR_2A_10":   PN = "DF20"  !CDS_PN = "DF20";
"PWR_2A_11":   PN = "DN17"  !CDS_PN = "DN17";
"PWR_2A_12":   PN = "DN20"  !CDS_PN = "DN20";
"PWR_2A_13":   PN = "DY17"  !CDS_PN = "DY17";
"PWR_2A_14":   PN = "DY20"  !CDS_PN = "DY20";
"PWR_2A_15":   PN = "EG17"  !CDS_PN = "EG17";
"PWR_2A_16":   PN = "EG20"  !CDS_PN = "EG20";
"PWR_2A_17":   PN = "EP17"  !CDS_PN = "EP17";
"PWR_2A_18":   PN = "EP20"  !CDS_PN = "EP20";
"PWR_2A_19":   PN = "T17"  !CDS_PN = "T17";
"PWR_2A_20":   PN = "T20"  !CDS_PN = "T20";
"PWR_2D_1":   PN = "BL17"  !CDS_PN = "BL17";
"PWR_2D_2":   PN = "BL20"  !CDS_PN = "BL20";
"PWR_2D_3":   PN = "CW17"  !CDS_PN = "CW17";
"PWR_2D_4":   PN = "CW20"  !CDS_PN = "CW20";
"VQPS":   PN = "G1"  !CDS_PN = "G1";
BODY = "PT5161LRS","I2": #LOCATION = "U6014" !CDS_LOCATION = "U6014" &SEC = "5" #&CDS_SEC = "5";
"GND1":   PN = "AC13"  !CDS_PN = "AC13";
"GND2":   PN = "AC22"  !CDS_PN = "AC22";
"GND3":   PN = "AC32"  !CDS_PN = "AC32";
"GND4":   PN = "AC4"  !CDS_PN = "AC4";
"GND5":   PN = "AD2"  !CDS_PN = "AD2";
"GND6":   PN = "AD34"  !CDS_PN = "AD34";
"GND7":   PN = "AE1"  !CDS_PN = "AE1";
"GND8":   PN = "AE35"  !CDS_PN = "AE35";
"GND9":   PN = "AK13"  !CDS_PN = "AK13";
"GND10":   PN = "AK22"  !CDS_PN = "AK22";
"GND11":   PN = "AK32"  !CDS_PN = "AK32";
"GND12":   PN = "AK4"  !CDS_PN = "AK4";
"GND13":   PN = "AL2"  !CDS_PN = "AL2";
"GND14":   PN = "AL34"  !CDS_PN = "AL34";
"GND15":   PN = "AM1"  !CDS_PN = "AM1";
"GND16":   PN = "AM35"  !CDS_PN = "AM35";
"GND17":   PN = "AU13"  !CDS_PN = "AU13";
"GND18":   PN = "AU22"  !CDS_PN = "AU22";
"GND19":   PN = "AU32"  !CDS_PN = "AU32";
"GND20":   PN = "AU4"  !CDS_PN = "AU4";
"GND21":   PN = "AV2"  !CDS_PN = "AV2";
"GND22":   PN = "AV34"  !CDS_PN = "AV34";
"GND23":   PN = "AW1"  !CDS_PN = "AW1";
"GND24":   PN = "AW35"  !CDS_PN = "AW35";
"GND25":   PN = "B19"  !CDS_PN = "B19";
"GND26":   PN = "BD13"  !CDS_PN = "BD13";
"GND27":   PN = "BD22"  !CDS_PN = "BD22";
"GND28":   PN = "BD32"  !CDS_PN = "BD32";
"GND29":   PN = "BD4"  !CDS_PN = "BD4";
"GND30":   PN = "BE2"  !CDS_PN = "BE2";
"GND31":   PN = "BE34"  !CDS_PN = "BE34";
"GND32":   PN = "BF1"  !CDS_PN = "BF1";
"GND33":   PN = "BF35"  !CDS_PN = "BF35";
"GND34":   PN = "BL13"  !CDS_PN = "BL13";
"GND35":   PN = "BL22"  !CDS_PN = "BL22";
"GND36":   PN = "BL32"  !CDS_PN = "BL32";
"GND37":   PN = "BL4"  !CDS_PN = "BL4";
"GND38":   PN = "BM2"  !CDS_PN = "BM2";
"GND39":   PN = "BM34"  !CDS_PN = "BM34";
"GND40":   PN = "BN1"  !CDS_PN = "BN1";
"GND41":   PN = "BN35"  !CDS_PN = "BN35";
"GND42":   PN = "BV13"  !CDS_PN = "BV13";
"GND43":   PN = "BV22"  !CDS_PN = "BV22";
"GND44":   PN = "BV32"  !CDS_PN = "BV32";
"GND45":   PN = "BV4"  !CDS_PN = "BV4";
"GND46":   PN = "BW2"  !CDS_PN = "BW2";
"GND47":   PN = "BW34"  !CDS_PN = "BW34";
"GND48":   PN = "BY1"  !CDS_PN = "BY1";
"GND49":   PN = "BY35"  !CDS_PN = "BY35";
"GND50":   PN = "CE13"  !CDS_PN = "CE13";
"GND51":   PN = "CE22"  !CDS_PN = "CE22";
"GND52":   PN = "CE32"  !CDS_PN = "CE32";
"GND53":   PN = "CE4"  !CDS_PN = "CE4";
"GND54":   PN = "CF2"  !CDS_PN = "CF2";
"GND55":   PN = "CF34"  !CDS_PN = "CF34";
"GND56":   PN = "CG1"  !CDS_PN = "CG1";
"GND57":   PN = "CG35"  !CDS_PN = "CG35";
"GND58":   PN = "CM13"  !CDS_PN = "CM13";
"GND59":   PN = "CM22"  !CDS_PN = "CM22";
"GND60":   PN = "CM32"  !CDS_PN = "CM32";
"GND61":   PN = "CM4"  !CDS_PN = "CM4";
"GND62":   PN = "CN2"  !CDS_PN = "CN2";
"GND63":   PN = "CN34"  !CDS_PN = "CN34";
"GND64":   PN = "CP1"  !CDS_PN = "CP1";
"GND65":   PN = "CP35"  !CDS_PN = "CP35";
"GND66":   PN = "CW13"  !CDS_PN = "CW13";
"GND67":   PN = "CW22"  !CDS_PN = "CW22";
"GND68":   PN = "CW32"  !CDS_PN = "CW32";
"GND69":   PN = "CW4"  !CDS_PN = "CW4";
"GND70":   PN = "CY2"  !CDS_PN = "CY2";
"GND71":   PN = "CY34"  !CDS_PN = "CY34";
"GND72":   PN = "DA1"  !CDS_PN = "DA1";
"GND73":   PN = "DA35"  !CDS_PN = "DA35";
"GND74":   PN = "DF13"  !CDS_PN = "DF13";
"GND75":   PN = "DF22"  !CDS_PN = "DF22";
"GND76":   PN = "DF32"  !CDS_PN = "DF32";
"GND77":   PN = "DF4"  !CDS_PN = "DF4";
"GND78":   PN = "DG2"  !CDS_PN = "DG2";
"GND79":   PN = "DG34"  !CDS_PN = "DG34";
"GND80":   PN = "DH1"  !CDS_PN = "DH1";
"GND81":   PN = "DH35"  !CDS_PN = "DH35";
"GND82":   PN = "DN13"  !CDS_PN = "DN13";
"GND83":   PN = "DN22"  !CDS_PN = "DN22";
"GND84":   PN = "DN32"  !CDS_PN = "DN32";
"GND85":   PN = "DN4"  !CDS_PN = "DN4";
"GND86":   PN = "DP2"  !CDS_PN = "DP2";
"GND87":   PN = "DP34"  !CDS_PN = "DP34";
"GND88":   PN = "DR1"  !CDS_PN = "DR1";
"GND89":   PN = "DR35"  !CDS_PN = "DR35";
"GND90":   PN = "DY13"  !CDS_PN = "DY13";
"GND91":   PN = "DY22"  !CDS_PN = "DY22";
"GND92":   PN = "DY32"  !CDS_PN = "DY32";
"GND93":   PN = "DY4"  !CDS_PN = "DY4";
"GND94":   PN = "E14"  !CDS_PN = "E14";
"GND95":   PN = "E27"  !CDS_PN = "E27";
"GND96":   PN = "E33"  !CDS_PN = "E33";
"GND97":   PN = "EA2"  !CDS_PN = "EA2";
"GND98":   PN = "EA34"  !CDS_PN = "EA34";
"GND99":   PN = "EB1"  !CDS_PN = "EB1";
"GND100":   PN = "EB35"  !CDS_PN = "EB35";
"GND101":   PN = "EG13"  !CDS_PN = "EG13";
"GND102":   PN = "EG22"  !CDS_PN = "EG22";
"GND103":   PN = "EG32"  !CDS_PN = "EG32";
"GND104":   PN = "EG4"  !CDS_PN = "EG4";
"GND105":   PN = "EH2"  !CDS_PN = "EH2";
"GND106":   PN = "EH34"  !CDS_PN = "EH34";
"GND107":   PN = "EJ1"  !CDS_PN = "EJ1";
"GND108":   PN = "EJ35"  !CDS_PN = "EJ35";
"GND109":   PN = "EP13"  !CDS_PN = "EP13";
"GND110":   PN = "EP22"  !CDS_PN = "EP22";
"GND111":   PN = "EP32"  !CDS_PN = "EP32";
"GND112":   PN = "EP4"  !CDS_PN = "EP4";
"GND113":   PN = "ER2"  !CDS_PN = "ER2";
"GND114":   PN = "ER34"  !CDS_PN = "ER34";
"GND115":   PN = "ET1"  !CDS_PN = "ET1";
"GND116":   PN = "ET35"  !CDS_PN = "ET35";
"GND117":   PN = "FA15"  !CDS_PN = "FA15";
"GND118":   PN = "FA32"  !CDS_PN = "FA32";
"GND119":   PN = "FB2"  !CDS_PN = "FB2";
"GND120":   PN = "FB34"  !CDS_PN = "FB34";
"GND121":   PN = "FC19"  !CDS_PN = "FC19";
"GND122":   PN = "FC23"  !CDS_PN = "FC23";
"GND123":   PN = "FC25"  !CDS_PN = "FC25";
"GND124":   PN = "FC28"  !CDS_PN = "FC28";
"GND125":   PN = "FC3"  !CDS_PN = "FC3";
"GND126":   PN = "FC6"  !CDS_PN = "FC6";
"GND127":   PN = "FC9"  !CDS_PN = "FC9";
"GND128":   PN = "FD1"  !CDS_PN = "FD1";
"GND129":   PN = "FD35"  !CDS_PN = "FD35";
"GND130":   PN = "FF14"  !CDS_PN = "FF14";
"GND131":   PN = "FF21"  !CDS_PN = "FF21";
"GND132":   PN = "FJ12"  !CDS_PN = "FJ12";
"GND133":   PN = "FJ19"  !CDS_PN = "FJ19";
"GND134":   PN = "H12"  !CDS_PN = "H12";
"GND135":   PN = "H16"  !CDS_PN = "H16";
"GND136":   PN = "H19"  !CDS_PN = "H19";
"GND137":   PN = "H31"  !CDS_PN = "H31";
"GND138":   PN = "J22"  !CDS_PN = "J22";
"GND139":   PN = "J4"  !CDS_PN = "J4";
"GND140":   PN = "K2"  !CDS_PN = "K2";
"GND141":   PN = "K34"  !CDS_PN = "K34";
"GND142":   PN = "L1"  !CDS_PN = "L1";
"GND143":   PN = "L35"  !CDS_PN = "L35";
"GND144":   PN = "T13"  !CDS_PN = "T13";
"GND145":   PN = "T22"  !CDS_PN = "T22";
"GND146":   PN = "T32"  !CDS_PN = "T32";
"GND147":   PN = "T4"  !CDS_PN = "T4";
"GND148":   PN = "U2"  !CDS_PN = "U2";
"GND149":   PN = "U34"  !CDS_PN = "U34";
"GND150":   PN = "V1"  !CDS_PN = "V1";
"GND151":   PN = "V35"  !CDS_PN = "V35";
"NCF_GND1":   PN = "A1"  !CDS_PN = "A1";
"NCF_GND2":   PN = "A35"  !CDS_PN = "A35";
"NCF_GND3":   PN = "C2"  !CDS_PN = "C2";
"NCF_GND4":   PN = "C34"  !CDS_PN = "C34";
"NCF_GND5":   PN = "D1"  !CDS_PN = "D1";
"NCF_GND6":   PN = "D35"  !CDS_PN = "D35";
"NCF_GND7":   PN = "FE2"  !CDS_PN = "FE2";
"NCF_GND8":   PN = "FE34"  !CDS_PN = "FE34";
"NCF_GND9":   PN = "FG1"  !CDS_PN = "FG1";
"NCF_GND10":   PN = "FG35"  !CDS_PN = "FG35";
"NCF_GND11":   PN = "FH2"  !CDS_PN = "FH2";
"NCF_GND12":   PN = "FH34"  !CDS_PN = "FH34";
BODY = "Q_RES","I102": #LOCATION = "R711" !CDS_LOCATION = "R711" &SEC = "1" #&CDS_SEC = "1";
"A":   PN = "1"  !CDS_PN = "1";
"B":   PN = "2"  !CDS_PN = "2";
BODY = "Q_RES","I103": #LOCATION = "R709" !CDS_LOCATION = "R709" &SEC = "1" #&CDS_SEC = "1";
"A":   PN = "1"  !CDS_PN = "1";
"B":   PN = "2"  !CDS_PN = "2";
BODY = "Q_RES","I105": #LOCATION = "R701" !CDS_LOCATION = "R701" &SEC = "1" #&CDS_SEC = "1";
"A":   PN = "1"  !CDS_PN = "1";
"B":   PN = "2"  !CDS_PN = "2";
BODY = "Q_RES","I106": #LOCATION = "R699" !CDS_LOCATION = "R699" &SEC = "1" #&CDS_SEC = "1";
"A":   PN = "1"  !CDS_PN = "1";
"B":   PN = "2"  !CDS_PN = "2";
DRAWING = "@t6g_mb_lib.t6g(sch_1):page401";
BODY = "PT5161LRS","I1": #LOCATION = "U6014" !CDS_LOCATION = "U6014" &SEC = "3" #&CDS_SEC = "3";
"CLKREQ_N":   PN = "G35"  !CDS_PN = "G35";
"EE_CLK":   PN = "FF5"  !CDS_PN = "FF5";
"EE_DAT":   PN = "FJ3"  !CDS_PN = "FJ3";
"GPIO0":   PN = "FJ6"  !CDS_PN = "FJ6";
"GPIO1":   PN = "FJ23"  !CDS_PN = "FJ23";
"GPIO2":   PN = "FJ25"  !CDS_PN = "FJ25";
"GPIO3":   PN = "FJ28"  !CDS_PN = "FJ28";
"INT_N":   PN = "FJ31"  !CDS_PN = "FJ31";
"JTAG_TCK":   PN = "B3"  !CDS_PN = "B3";
"JTAG_TDI":   PN = "B6"  !CDS_PN = "B6";
"JTAG_TDO":   PN = "B9"  !CDS_PN = "B9";
"JTAG_TEST_MODE":   PN = "FF8"  !CDS_PN = "FF8";
"JTAG_TMS":   PN = "B12"  !CDS_PN = "B12";
"JTAG_TRST_N":   PN = "E8"  !CDS_PN = "E8";
"MODE":   PN = "FJ9"  !CDS_PN = "FJ9";
"PERST_N":   PN = "F2"  !CDS_PN = "F2";
"REFCLK_OUTN":   PN = "E18"  !CDS_PN = "E18";
"REFCLK_OUTP":   PN = "B16"  !CDS_PN = "B16";
"REFCLKN":   PN = "FF18"  !CDS_PN = "FF18";
"REFCLKP":   PN = "FJ16"  !CDS_PN = "FJ16";
"RESET_N":   PN = "FF11"  !CDS_PN = "FF11";
"RXDET_BYP":   PN = "E11"  !CDS_PN = "E11";
"SCAN_MODE":   PN = "FF33"  !CDS_PN = "FF33";
"SMB_ADDR1":   PN = "F34"  !CDS_PN = "F34";
"SMB_ADDR2":   PN = "B23"  !CDS_PN = "B23";
"SMB_ADDR3":   PN = "B25"  !CDS_PN = "B25";
"SMBCLK":   PN = "B31"  !CDS_PN = "B31";
"SMBDAT":   PN = "B28"  !CDS_PN = "B28";
"T_SENSE":   PN = "E30"  !CDS_PN = "E30";
"TEST0":   PN = "FF24"  !CDS_PN = "FF24";
"TEST1":   PN = "FF27"  !CDS_PN = "FF27";
"TEST2":   PN = "FF30"  !CDS_PN = "FF30";
BODY = "Q_RES","I8": #LOCATION = "R609" !CDS_LOCATION = "R609" #SEC = "1" !CDS_SEC = "1";
"A":   PN = "1"  !CDS_PN = "1";
"B":   PN = "2"  !CDS_PN = "2";
BODY = "Q_RES","I9": #LOCATION = "R599" !CDS_LOCATION = "R599" #SEC = "1" !CDS_SEC = "1";
"A":   PN = "1"  !CDS_PN = "1";
"B":   PN = "2"  !CDS_PN = "2";
BODY = "Q_RES","I13": #LOCATION = "R675" !CDS_LOCATION = "R675" &SEC = "1" #&CDS_SEC = "1";
"A":   PN = "1"  !CDS_PN = "1";
"B":   PN = "2"  !CDS_PN = "2";
BODY = "Q_RES","I19": #LOCATION = "R6812" !CDS_LOCATION = "R6812" &SEC = "1" #&CDS_SEC = "1";
"A":   PN = "1"  !CDS_PN = "1";
"B":   PN = "2"  !CDS_PN = "2";
BODY = "Q_RES","I20": #LOCATION = "R6813" !CDS_LOCATION = "R6813" &SEC = "1" #&CDS_SEC = "1";
"A":   PN = "1"  !CDS_PN = "1";
"B":   PN = "2"  !CDS_PN = "2";
BODY = "Q_RES","I23": #LOCATION = "R627" !CDS_LOCATION = "R627" &SEC = "1" #&CDS_SEC = "1";
"A":   PN = "1"  !CDS_PN = "1";
"B":   PN = "2"  !CDS_PN = "2";
BODY = "Q_RES","I24": #LOCATION = "R628" !CDS_LOCATION = "R628" &SEC = "1" #&CDS_SEC = "1";
"A":   PN = "1"  !CDS_PN = "1";
"B":   PN = "2"  !CDS_PN = "2";
BODY = "Q_RES","I25": #LOCATION = "R724" !CDS_LOCATION = "R724" &SEC = "1" #&CDS_SEC = "1";
"A":   PN = "1"  !CDS_PN = "1";
"B":   PN = "2"  !CDS_PN = "2";
BODY = "Q_RES","I26": #LOCATION = "R720" !CDS_LOCATION = "R720" &SEC = "1" #&CDS_SEC = "1";
"A":   PN = "1"  !CDS_PN = "1";
"B":   PN = "2"  !CDS_PN = "2";
BODY = "Q_RES","I27": #LOCATION = "R716" !CDS_LOCATION = "R716" &SEC = "1" #&CDS_SEC = "1";
"A":   PN = "1"  !CDS_PN = "1";
"B":   PN = "2"  !CDS_PN = "2";
BODY = "Q_RES","I29": #LOCATION = "R706" !CDS_LOCATION = "R706" &SEC = "1" #&CDS_SEC = "1";
"A":   PN = "1"  !CDS_PN = "1";
"B":   PN = "2"  !CDS_PN = "2";
BODY = "Q_RES","I32": #LOCATION = "R725" !CDS_LOCATION = "R725" &SEC = "1" #&CDS_SEC = "1";
"A":   PN = "1"  !CDS_PN = "1";
"B":   PN = "2"  !CDS_PN = "2";
BODY = "Q_RES","I33": #LOCATION = "R723" !CDS_LOCATION = "R723" &SEC = "1" #&CDS_SEC = "1";
"A":   PN = "1"  !CDS_PN = "1";
"B":   PN = "2"  !CDS_PN = "2";
BODY = "Q_RES","I34": #LOCATION = "R719" !CDS_LOCATION = "R719" &SEC = "1" #&CDS_SEC = "1";
"A":   PN = "1"  !CDS_PN = "1";
"B":   PN = "2"  !CDS_PN = "2";
BODY = "Q_RES","I35": #LOCATION = "R715" !CDS_LOCATION = "R715" &SEC = "1" #&CDS_SEC = "1";
"A":   PN = "1"  !CDS_PN = "1";
"B":   PN = "2"  !CDS_PN = "2";
BODY = "Q_RES","I36": #LOCATION = "R707" !CDS_LOCATION = "R707" &SEC = "1" #&CDS_SEC = "1";
"A":   PN = "1"  !CDS_PN = "1";
"B":   PN = "2"  !CDS_PN = "2";
BODY = "Q_RES","I54": #LOCATION = "R727" !CDS_LOCATION = "R727" &SEC = "1" #&CDS_SEC = "1";
"A":   PN = "1"  !CDS_PN = "1";
"B":   PN = "2"  !CDS_PN = "2";
BODY = "Q_RES","I55": #LOCATION = "R728" !CDS_LOCATION = "R728" &SEC = "1" #&CDS_SEC = "1";
"A":   PN = "1"  !CDS_PN = "1";
"B":   PN = "2"  !CDS_PN = "2";
BODY = "Q_RES","I62": #LOCATION = "R6708" !CDS_LOCATION = "R6708" #SEC = "1" !CDS_SEC = "1";
"A":   PN = "1"  !CDS_PN = "1";
"B":   PN = "2"  !CDS_PN = "2";
BODY = "Q_RES","I65": #LOCATION = "R6709" !CDS_LOCATION = "R6709" &SEC = "1" #&CDS_SEC = "1";
"A":   PN = "1"  !CDS_PN = "1";
"B":   PN = "2"  !CDS_PN = "2";
BODY = "Q_RES","I85": #LOCATION = "R6722" !CDS_LOCATION = "R6722" &SEC = "1" #&CDS_SEC = "1";
"A":   PN = "1"  !CDS_PN = "1";
"B":   PN = "2"  !CDS_PN = "2";
BODY = "Q_RES","I90": #LOCATION = "R726" !CDS_LOCATION = "R726" &SEC = "1" #&CDS_SEC = "1";
"A":   PN = "1"  !CDS_PN = "1";
"B":   PN = "2"  !CDS_PN = "2";
BODY = "Q_RES","I91": #LOCATION = "R6725" !CDS_LOCATION = "R6725" &SEC = "1" #&CDS_SEC = "1";
"A":   PN = "1"  !CDS_PN = "1";
"B":   PN = "2"  !CDS_PN = "2";
BODY = "Q_RES","I96": #LOCATION = "R6721" !CDS_LOCATION = "R6721" &SEC = "1" #&CDS_SEC = "1";
"A":   PN = "1"  !CDS_PN = "1";
"B":   PN = "2"  !CDS_PN = "2";
BODY = "Q_RES","I97": #LOCATION = "R6720" !CDS_LOCATION = "R6720" &SEC = "1" #&CDS_SEC = "1";
"A":   PN = "1"  !CDS_PN = "1";
"B":   PN = "2"  !CDS_PN = "2";
BODY = "Q_RES","I101": #LOCATION = "R6724" !CDS_LOCATION = "R6724" &SEC = "1" #&CDS_SEC = "1";
"A":   PN = "1"  !CDS_PN = "1";
"B":   PN = "2"  !CDS_PN = "2";
BODY = "Q_RES","I102": #LOCATION = "R6712" !CDS_LOCATION = "R6712" &SEC = "1" #&CDS_SEC = "1";
"A":   PN = "1"  !CDS_PN = "1";
"B":   PN = "2"  !CDS_PN = "2";
BODY = "Q_RES","I103": #LOCATION = "R6713" !CDS_LOCATION = "R6713" &SEC = "1" #&CDS_SEC = "1";
"A":   PN = "1"  !CDS_PN = "1";
"B":   PN = "2"  !CDS_PN = "2";
BODY = "Q_RES","I104": #LOCATION = "R6714" !CDS_LOCATION = "R6714" &SEC = "1" #&CDS_SEC = "1";
"A":   PN = "1"  !CDS_PN = "1";
"B":   PN = "2"  !CDS_PN = "2";
BODY = "Q_RES","I105": #LOCATION = "R6715" !CDS_LOCATION = "R6715" &SEC = "1" #&CDS_SEC = "1";
"A":   PN = "1"  !CDS_PN = "1";
"B":   PN = "2"  !CDS_PN = "2";
BODY = "Q_RES","I106": #LOCATION = "R6717" !CDS_LOCATION = "R6717" &SEC = "1" #&CDS_SEC = "1";
"A":   PN = "1"  !CDS_PN = "1";
"B":   PN = "2"  !CDS_PN = "2";
BODY = "Q_RES","I107": #LOCATION = "R6716" !CDS_LOCATION = "R6716" &SEC = "1" #&CDS_SEC = "1";
"A":   PN = "1"  !CDS_PN = "1";
"B":   PN = "2"  !CDS_PN = "2";
BODY = "Q_RES","I108": #LOCATION = "R1387" !CDS_LOCATION = "R1387" &SEC = "1" #&CDS_SEC = "1";
"A":   PN = "1"  !CDS_PN = "1";
"B":   PN = "2"  !CDS_PN = "2";
BODY = "Q_RES","I112": #LOCATION = "R1380" !CDS_LOCATION = "R1380" &SEC = "1" #&CDS_SEC = "1";
"A":   PN = "1"  !CDS_PN = "1";
"B":   PN = "2"  !CDS_PN = "2";
BODY = "Q_RES","I124": #LOCATION = "R1389" !CDS_LOCATION = "R1389" &SEC = "1" #&CDS_SEC = "1";
"A":   PN = "1"  !CDS_PN = "1";
"B":   PN = "2"  !CDS_PN = "2";
BODY = "Q_RES","I125": #LOCATION = "R1388" !CDS_LOCATION = "R1388" &SEC = "1" #&CDS_SEC = "1";
"A":   PN = "1"  !CDS_PN = "1";
"B":   PN = "2"  !CDS_PN = "2";
BODY = "Q_RES","I128": #LOCATION = "R6723" !CDS_LOCATION = "R6723" &SEC = "1" #&CDS_SEC = "1";
"A":   PN = "1"  !CDS_PN = "1";
"B":   PN = "2"  !CDS_PN = "2";
BODY = "Q_RES","I144": #LOCATION = "R1381" !CDS_LOCATION = "R1381" &SEC = "1" #&CDS_SEC = "1";
"A":   PN = "1"  !CDS_PN = "1";
"B":   PN = "2"  !CDS_PN = "2";
BODY = "Q_RES","I145": #LOCATION = "R1465" !CDS_LOCATION = "R1465" &SEC = "1" #&CDS_SEC = "1";
"A":   PN = "1"  !CDS_PN = "1";
"B":   PN = "2"  !CDS_PN = "2";
BODY = "Q_RES","I146": #LOCATION = "R1466" !CDS_LOCATION = "R1466" &SEC = "1" #&CDS_SEC = "1";
"A":   PN = "1"  !CDS_PN = "1";
"B":   PN = "2"  !CDS_PN = "2";
BODY = "Q_RES","I147": #LOCATION = "R1467" !CDS_LOCATION = "R1467" &SEC = "1" #&CDS_SEC = "1";
"A":   PN = "1"  !CDS_PN = "1";
"B":   PN = "2"  !CDS_PN = "2";
BODY = "Q_RES","I149": #LOCATION = "R1464" !CDS_LOCATION = "R1464" &SEC = "1" #&CDS_SEC = "1";
"A":   PN = "1"  !CDS_PN = "1";
"B":   PN = "2"  !CDS_PN = "2";
BODY = "Q_RES","I155": #LOCATION = "R674" !CDS_LOCATION = "R674" #SEC = "1" !CDS_SEC = "1";
"A":   PN = "1"  !CDS_PN = "1";
"B":   PN = "2"  !CDS_PN = "2";
DRAWING = "@t6g_mb_lib.t6g(sch_1):page402";
BODY = "PT5161LRS","I1": #LOCATION = "U6014" !CDS_LOCATION = "U6014" &SEC = "1" #&CDS_SEC = "1";
"A_PERN0":   PN = "N2"  !CDS_PN = "N2";
"A_PERN1":   PN = "Y2"  !CDS_PN = "Y2";
"A_PERN2":   PN = "AG2"  !CDS_PN = "AG2";
"A_PERN3":   PN = "AP2"  !CDS_PN = "AP2";
"A_PERN4":   PN = "BA2"  !CDS_PN = "BA2";
"A_PERN5":   PN = "BH2"  !CDS_PN = "BH2";
"A_PERN6":   PN = "BR2"  !CDS_PN = "BR2";
"A_PERN7":   PN = "CB2"  !CDS_PN = "CB2";
"A_PERP0":   PN = "R1"  !CDS_PN = "R1";
"A_PERP1":   PN = "AB1"  !CDS_PN = "AB1";
"A_PERP2":   PN = "AJ1"  !CDS_PN = "AJ1";
"A_PERP3":   PN = "AT1"  !CDS_PN = "AT1";
"A_PERP4":   PN = "BC1"  !CDS_PN = "BC1";
"A_PERP5":   PN = "BK1"  !CDS_PN = "BK1";
"A_PERP6":   PN = "BU1"  !CDS_PN = "BU1";
"A_PERP7":   PN = "CD1"  !CDS_PN = "CD1";
BODY = "PT5161LRS","I38": #LOCATION = "U6014" !CDS_LOCATION = "U6014" &SEC = "2" #&CDS_SEC = "2";
"A_PERN8":   PN = "CJ2"  !CDS_PN = "CJ2";
"A_PERN9":   PN = "CT2"  !CDS_PN = "CT2";
"A_PERN10":   PN = "DC2"  !CDS_PN = "DC2";
"A_PERN11":   PN = "DK2"  !CDS_PN = "DK2";
"A_PERN12":   PN = "DU2"  !CDS_PN = "DU2";
"A_PERN13":   PN = "ED2"  !CDS_PN = "ED2";
"A_PERN14":   PN = "EL2"  !CDS_PN = "EL2";
"A_PERN15":   PN = "EV2"  !CDS_PN = "EV2";
"A_PERP8":   PN = "CL1"  !CDS_PN = "CL1";
"A_PERP9":   PN = "CV1"  !CDS_PN = "CV1";
"A_PERP10":   PN = "DE1"  !CDS_PN = "DE1";
"A_PERP11":   PN = "DM1"  !CDS_PN = "DM1";
"A_PERP12":   PN = "DW1"  !CDS_PN = "DW1";
"A_PERP13":   PN = "EF1"  !CDS_PN = "EF1";
"A_PERP14":   PN = "EN1"  !CDS_PN = "EN1";
"A_PERP15":   PN = "EY1"  !CDS_PN = "EY1";
DRAWING = "@t6g_mb_lib.t6g(sch_1):page404";
BODY = "PT5161LRS","I1": #LOCATION = "U6011" !CDS_LOCATION = "U6011" &SEC = "8" #&CDS_SEC = "8";
"B_PERN0":   PN = "R35"  !CDS_PN = "R35";
"B_PERN1":   PN = "AB35"  !CDS_PN = "AB35";
"B_PERN2":   PN = "AJ35"  !CDS_PN = "AJ35";
"B_PERN3":   PN = "AT35"  !CDS_PN = "AT35";
"B_PERN4":   PN = "BC35"  !CDS_PN = "BC35";
"B_PERN5":   PN = "BK35"  !CDS_PN = "BK35";
"B_PERN6":   PN = "BU35"  !CDS_PN = "BU35";
"B_PERN7":   PN = "CD35"  !CDS_PN = "CD35";
"B_PERP0":   PN = "N34"  !CDS_PN = "N34";
"B_PERP1":   PN = "Y34"  !CDS_PN = "Y34";
"B_PERP2":   PN = "AG34"  !CDS_PN = "AG34";
"B_PERP3":   PN = "AP34"  !CDS_PN = "AP34";
"B_PERP4":   PN = "BA34"  !CDS_PN = "BA34";
"B_PERP5":   PN = "BH34"  !CDS_PN = "BH34";
"B_PERP6":   PN = "BR34"  !CDS_PN = "BR34";
"B_PERP7":   PN = "CB34"  !CDS_PN = "CB34";
BODY = "PT5161LRS","I38": #LOCATION = "U6011" !CDS_LOCATION = "U6011" &SEC = "9" #&CDS_SEC = "9";
"B_PERN8":   PN = "CL35"  !CDS_PN = "CL35";
"B_PERN9":   PN = "CV35"  !CDS_PN = "CV35";
"B_PERN10":   PN = "DE35"  !CDS_PN = "DE35";
"B_PERN11":   PN = "DM35"  !CDS_PN = "DM35";
"B_PERN12":   PN = "DW35"  !CDS_PN = "DW35";
"B_PERN13":   PN = "EF35"  !CDS_PN = "EF35";
"B_PERN14":   PN = "EN35"  !CDS_PN = "EN35";
"B_PERN15":   PN = "EY35"  !CDS_PN = "EY35";
"B_PERP8":   PN = "CJ34"  !CDS_PN = "CJ34";
"B_PERP9":   PN = "CT34"  !CDS_PN = "CT34";
"B_PERP10":   PN = "DC34"  !CDS_PN = "DC34";
"B_PERP11":   PN = "DK34"  !CDS_PN = "DK34";
"B_PERP12":   PN = "DU34"  !CDS_PN = "DU34";
"B_PERP13":   PN = "ED34"  !CDS_PN = "ED34";
"B_PERP14":   PN = "EL34"  !CDS_PN = "EL34";
"B_PERP15":   PN = "EV34"  !CDS_PN = "EV34";
DRAWING = "@t6g_mb_lib.t6g(sch_1):page405";
BODY = "PT5161LRS","I1": #LOCATION = "U6011" !CDS_LOCATION = "U6011" &SEC = "6" #&CDS_SEC = "6";
"A_PETN0":   PN = "P29"  !CDS_PN = "P29";
"A_PETN1":   PN = "AA29"  !CDS_PN = "AA29";
"A_PETN2":   PN = "AH29"  !CDS_PN = "AH29";
"A_PETN3":   PN = "AR29"  !CDS_PN = "AR29";
"A_PETN4":   PN = "BB29"  !CDS_PN = "BB29";
"A_PETN5":   PN = "BJ29"  !CDS_PN = "BJ29";
"A_PETN6":   PN = "BT29"  !CDS_PN = "BT29";
"A_PETN7":   PN = "CC29"  !CDS_PN = "CC29";
"A_PETP0":   PN = "M26"  !CDS_PN = "M26";
"A_PETP1":   PN = "W26"  !CDS_PN = "W26";
"A_PETP2":   PN = "AF26"  !CDS_PN = "AF26";
"A_PETP3":   PN = "AN26"  !CDS_PN = "AN26";
"A_PETP4":   PN = "AY26"  !CDS_PN = "AY26";
"A_PETP5":   PN = "BG26"  !CDS_PN = "BG26";
"A_PETP6":   PN = "BP26"  !CDS_PN = "BP26";
"A_PETP7":   PN = "CA26"  !CDS_PN = "CA26";
BODY = "PT5161LRS","I38": #LOCATION = "U6011" !CDS_LOCATION = "U6011" &SEC = "7" #&CDS_SEC = "7";
"A_PETN8":   PN = "CK29"  !CDS_PN = "CK29";
"A_PETN9":   PN = "CU29"  !CDS_PN = "CU29";
"A_PETN10":   PN = "DD29"  !CDS_PN = "DD29";
"A_PETN11":   PN = "DL29"  !CDS_PN = "DL29";
"A_PETN12":   PN = "DV29"  !CDS_PN = "DV29";
"A_PETN13":   PN = "EE29"  !CDS_PN = "EE29";
"A_PETN14":   PN = "EM29"  !CDS_PN = "EM29";
"A_PETN15":   PN = "EW29"  !CDS_PN = "EW29";
"A_PETP8":   PN = "CH26"  !CDS_PN = "CH26";
"A_PETP9":   PN = "CR26"  !CDS_PN = "CR26";
"A_PETP10":   PN = "DB26"  !CDS_PN = "DB26";
"A_PETP11":   PN = "DJ26"  !CDS_PN = "DJ26";
"A_PETP12":   PN = "DT26"  !CDS_PN = "DT26";
"A_PETP13":   PN = "EC26"  !CDS_PN = "EC26";
"A_PETP14":   PN = "EK26"  !CDS_PN = "EK26";
"A_PETP15":   PN = "EU26"  !CDS_PN = "EU26";
DRAWING = "@t6g_mb_lib.t6g(sch_1):page406";
BODY = "PT5161LRS","I1": #LOCATION = "U6011" !CDS_LOCATION = "U6011" &SEC = "1" #&CDS_SEC = "1";
"A_PERN0":   PN = "N2"  !CDS_PN = "N2";
"A_PERN1":   PN = "Y2"  !CDS_PN = "Y2";
"A_PERN2":   PN = "AG2"  !CDS_PN = "AG2";
"A_PERN3":   PN = "AP2"  !CDS_PN = "AP2";
"A_PERN4":   PN = "BA2"  !CDS_PN = "BA2";
"A_PERN5":   PN = "BH2"  !CDS_PN = "BH2";
"A_PERN6":   PN = "BR2"  !CDS_PN = "BR2";
"A_PERN7":   PN = "CB2"  !CDS_PN = "CB2";
"A_PERP0":   PN = "R1"  !CDS_PN = "R1";
"A_PERP1":   PN = "AB1"  !CDS_PN = "AB1";
"A_PERP2":   PN = "AJ1"  !CDS_PN = "AJ1";
"A_PERP3":   PN = "AT1"  !CDS_PN = "AT1";
"A_PERP4":   PN = "BC1"  !CDS_PN = "BC1";
"A_PERP5":   PN = "BK1"  !CDS_PN = "BK1";
"A_PERP6":   PN = "BU1"  !CDS_PN = "BU1";
"A_PERP7":   PN = "CD1"  !CDS_PN = "CD1";
BODY = "PT5161LRS","I38": #LOCATION = "U6011" !CDS_LOCATION = "U6011" &SEC = "2" #&CDS_SEC = "2";
"A_PERN8":   PN = "CJ2"  !CDS_PN = "CJ2";
"A_PERN9":   PN = "CT2"  !CDS_PN = "CT2";
"A_PERN10":   PN = "DC2"  !CDS_PN = "DC2";
"A_PERN11":   PN = "DK2"  !CDS_PN = "DK2";
"A_PERN12":   PN = "DU2"  !CDS_PN = "DU2";
"A_PERN13":   PN = "ED2"  !CDS_PN = "ED2";
"A_PERN14":   PN = "EL2"  !CDS_PN = "EL2";
"A_PERN15":   PN = "EV2"  !CDS_PN = "EV2";
"A_PERP8":   PN = "CL1"  !CDS_PN = "CL1";
"A_PERP9":   PN = "CV1"  !CDS_PN = "CV1";
"A_PERP10":   PN = "DE1"  !CDS_PN = "DE1";
"A_PERP11":   PN = "DM1"  !CDS_PN = "DM1";
"A_PERP12":   PN = "DW1"  !CDS_PN = "DW1";
"A_PERP13":   PN = "EF1"  !CDS_PN = "EF1";
"A_PERP14":   PN = "EN1"  !CDS_PN = "EN1";
"A_PERP15":   PN = "EY1"  !CDS_PN = "EY1";
DRAWING = "@t6g_mb_lib.t6g(sch_1):page407";
BODY = "Q_CAP_DIFFBUS","I15": #LOCATION = "C6548" !CDS_LOCATION = "C6548" &SEC = "1" #&CDS_SEC = "1";
"1":   PN = "1"  !CDS_PN = "1";
"2":   PN = "2"  !CDS_PN = "2";
BODY = "Q_CAP_DIFFBUS","I16": #LOCATION = "C6547" !CDS_LOCATION = "C6547" &SEC = "1" #&CDS_SEC = "1";
"1":   PN = "1"  !CDS_PN = "1";
"2":   PN = "2"  !CDS_PN = "2";
BODY = "Q_CAP_DIFFBUS","I18": #LOCATION = "C6545" !CDS_LOCATION = "C6545" &SEC = "1" #&CDS_SEC = "1";
"1":   PN = "1"  !CDS_PN = "1";
"2":   PN = "2"  !CDS_PN = "2";
BODY = "Q_CAP_DIFFBUS","I19": #LOCATION = "C6546" !CDS_LOCATION = "C6546" &SEC = "1" #&CDS_SEC = "1";
"1":   PN = "1"  !CDS_PN = "1";
"2":   PN = "2"  !CDS_PN = "2";
BODY = "Q_CAP_DIFFBUS","I20": #LOCATION = "C6543" !CDS_LOCATION = "C6543" &SEC = "1" #&CDS_SEC = "1";
"1":   PN = "1"  !CDS_PN = "1";
"2":   PN = "2"  !CDS_PN = "2";
BODY = "Q_CAP_DIFFBUS","I21": #LOCATION = "C6544" !CDS_LOCATION = "C6544" &SEC = "1" #&CDS_SEC = "1";
"1":   PN = "1"  !CDS_PN = "1";
"2":   PN = "2"  !CDS_PN = "2";
BODY = "Q_CAP_DIFFBUS","I22": #LOCATION = "C6541" !CDS_LOCATION = "C6541" &SEC = "1" #&CDS_SEC = "1";
"1":   PN = "1"  !CDS_PN = "1";
"2":   PN = "2"  !CDS_PN = "2";
BODY = "Q_CAP_DIFFBUS","I23": #LOCATION = "C6542" !CDS_LOCATION = "C6542" &SEC = "1" #&CDS_SEC = "1";
"1":   PN = "1"  !CDS_PN = "1";
"2":   PN = "2"  !CDS_PN = "2";
BODY = "Q_CAP_DIFFBUS","I24": #LOCATION = "C6540" !CDS_LOCATION = "C6540" &SEC = "1" #&CDS_SEC = "1";
"1":   PN = "1"  !CDS_PN = "1";
"2":   PN = "2"  !CDS_PN = "2";
BODY = "Q_CAP_DIFFBUS","I25": #LOCATION = "C6539" !CDS_LOCATION = "C6539" &SEC = "1" #&CDS_SEC = "1";
"1":   PN = "1"  !CDS_PN = "1";
"2":   PN = "2"  !CDS_PN = "2";
BODY = "Q_CAP_DIFFBUS","I26": #LOCATION = "C6538" !CDS_LOCATION = "C6538" &SEC = "1" #&CDS_SEC = "1";
"1":   PN = "1"  !CDS_PN = "1";
"2":   PN = "2"  !CDS_PN = "2";
BODY = "Q_CAP_DIFFBUS","I27": #LOCATION = "C6537" !CDS_LOCATION = "C6537" &SEC = "1" #&CDS_SEC = "1";
"1":   PN = "1"  !CDS_PN = "1";
"2":   PN = "2"  !CDS_PN = "2";
BODY = "PT5161LRS","I43": #LOCATION = "U6011" !CDS_LOCATION = "U6011" &SEC = "10" #&CDS_SEC = "10";
"B_PETN0":   PN = "P10"  !CDS_PN = "P10";
"B_PETN1":   PN = "AA10"  !CDS_PN = "AA10";
"B_PETN2":   PN = "AH10"  !CDS_PN = "AH10";
"B_PETN3":   PN = "AR10"  !CDS_PN = "AR10";
"B_PETN4":   PN = "BB10"  !CDS_PN = "BB10";
"B_PETN5":   PN = "BJ10"  !CDS_PN = "BJ10";
"B_PETN6":   PN = "BT10"  !CDS_PN = "BT10";
"B_PETN7":   PN = "CC10"  !CDS_PN = "CC10";
"B_PETP0":   PN = "M7"  !CDS_PN = "M7";
"B_PETP1":   PN = "W7"  !CDS_PN = "W7";
"B_PETP2":   PN = "AF7"  !CDS_PN = "AF7";
"B_PETP3":   PN = "AN7"  !CDS_PN = "AN7";
"B_PETP4":   PN = "AY7"  !CDS_PN = "AY7";
"B_PETP5":   PN = "BG7"  !CDS_PN = "BG7";
"B_PETP6":   PN = "BP7"  !CDS_PN = "BP7";
"B_PETP7":   PN = "CA7"  !CDS_PN = "CA7";
BODY = "Q_CAP_DIFFBUS","I44": #LOCATION = "C6536" !CDS_LOCATION = "C6536" &SEC = "1" #&CDS_SEC = "1";
"1":   PN = "1"  !CDS_PN = "1";
"2":   PN = "2"  !CDS_PN = "2";
BODY = "Q_CAP_DIFFBUS","I45": #LOCATION = "C6535" !CDS_LOCATION = "C6535" &SEC = "1" #&CDS_SEC = "1";
"1":   PN = "1"  !CDS_PN = "1";
"2":   PN = "2"  !CDS_PN = "2";
BODY = "Q_CAP_DIFFBUS","I46": #LOCATION = "C6533" !CDS_LOCATION = "C6533" &SEC = "1" #&CDS_SEC = "1";
"1":   PN = "1"  !CDS_PN = "1";
"2":   PN = "2"  !CDS_PN = "2";
BODY = "Q_CAP_DIFFBUS","I47": #LOCATION = "C6534" !CDS_LOCATION = "C6534" &SEC = "1" #&CDS_SEC = "1";
"1":   PN = "1"  !CDS_PN = "1";
"2":   PN = "2"  !CDS_PN = "2";
BODY = "Q_CAP_DIFFBUS","I86": #LOCATION = "C6564" !CDS_LOCATION = "C6564" &SEC = "1" #&CDS_SEC = "1";
"1":   PN = "1"  !CDS_PN = "1";
"2":   PN = "2"  !CDS_PN = "2";
BODY = "Q_CAP_DIFFBUS","I87": #LOCATION = "C6563" !CDS_LOCATION = "C6563" &SEC = "1" #&CDS_SEC = "1";
"1":   PN = "1"  !CDS_PN = "1";
"2":   PN = "2"  !CDS_PN = "2";
BODY = "Q_CAP_DIFFBUS","I88": #LOCATION = "C6562" !CDS_LOCATION = "C6562" &SEC = "1" #&CDS_SEC = "1";
"1":   PN = "1"  !CDS_PN = "1";
"2":   PN = "2"  !CDS_PN = "2";
BODY = "Q_CAP_DIFFBUS","I89": #LOCATION = "C6561" !CDS_LOCATION = "C6561" &SEC = "1" #&CDS_SEC = "1";
"1":   PN = "1"  !CDS_PN = "1";
"2":   PN = "2"  !CDS_PN = "2";
BODY = "Q_CAP_DIFFBUS","I90": #LOCATION = "C6560" !CDS_LOCATION = "C6560" &SEC = "1" #&CDS_SEC = "1";
"1":   PN = "1"  !CDS_PN = "1";
"2":   PN = "2"  !CDS_PN = "2";
BODY = "Q_CAP_DIFFBUS","I91": #LOCATION = "C6559" !CDS_LOCATION = "C6559" &SEC = "1" #&CDS_SEC = "1";
"1":   PN = "1"  !CDS_PN = "1";
"2":   PN = "2"  !CDS_PN = "2";
BODY = "Q_CAP_DIFFBUS","I92": #LOCATION = "C6558" !CDS_LOCATION = "C6558" &SEC = "1" #&CDS_SEC = "1";
"1":   PN = "1"  !CDS_PN = "1";
"2":   PN = "2"  !CDS_PN = "2";
BODY = "Q_CAP_DIFFBUS","I93": #LOCATION = "C6557" !CDS_LOCATION = "C6557" &SEC = "1" #&CDS_SEC = "1";
"1":   PN = "1"  !CDS_PN = "1";
"2":   PN = "2"  !CDS_PN = "2";
BODY = "Q_CAP_DIFFBUS","I94": #LOCATION = "C6556" !CDS_LOCATION = "C6556" &SEC = "1" #&CDS_SEC = "1";
"1":   PN = "1"  !CDS_PN = "1";
"2":   PN = "2"  !CDS_PN = "2";
BODY = "Q_CAP_DIFFBUS","I95": #LOCATION = "C6555" !CDS_LOCATION = "C6555" &SEC = "1" #&CDS_SEC = "1";
"1":   PN = "1"  !CDS_PN = "1";
"2":   PN = "2"  !CDS_PN = "2";
BODY = "Q_CAP_DIFFBUS","I96": #LOCATION = "C6553" !CDS_LOCATION = "C6553" &SEC = "1" #&CDS_SEC = "1";
"1":   PN = "1"  !CDS_PN = "1";
"2":   PN = "2"  !CDS_PN = "2";
BODY = "Q_CAP_DIFFBUS","I97": #LOCATION = "C6554" !CDS_LOCATION = "C6554" &SEC = "1" #&CDS_SEC = "1";
"1":   PN = "1"  !CDS_PN = "1";
"2":   PN = "2"  !CDS_PN = "2";
BODY = "Q_CAP_DIFFBUS","I102": #LOCATION = "C6551" !CDS_LOCATION = "C6551" &SEC = "1" #&CDS_SEC = "1";
"1":   PN = "1"  !CDS_PN = "1";
"2":   PN = "2"  !CDS_PN = "2";
BODY = "Q_CAP_DIFFBUS","I103": #LOCATION = "C6552" !CDS_LOCATION = "C6552" &SEC = "1" #&CDS_SEC = "1";
"1":   PN = "1"  !CDS_PN = "1";
"2":   PN = "2"  !CDS_PN = "2";
BODY = "Q_CAP_DIFFBUS","I104": #LOCATION = "C6550" !CDS_LOCATION = "C6550" &SEC = "1" #&CDS_SEC = "1";
"1":   PN = "1"  !CDS_PN = "1";
"2":   PN = "2"  !CDS_PN = "2";
BODY = "Q_CAP_DIFFBUS","I105": #LOCATION = "C6549" !CDS_LOCATION = "C6549" &SEC = "1" #&CDS_SEC = "1";
"1":   PN = "1"  !CDS_PN = "1";
"2":   PN = "2"  !CDS_PN = "2";
BODY = "PT5161LRS","I142": #LOCATION = "U6011" !CDS_LOCATION = "U6011" &SEC = "11" #&CDS_SEC = "11";
"B_PETN8":   PN = "CK10"  !CDS_PN = "CK10";
"B_PETN9":   PN = "CU10"  !CDS_PN = "CU10";
"B_PETN10":   PN = "DD10"  !CDS_PN = "DD10";
"B_PETN11":   PN = "DL10"  !CDS_PN = "DL10";
"B_PETN12":   PN = "DV10"  !CDS_PN = "DV10";
"B_PETN13":   PN = "EE10"  !CDS_PN = "EE10";
"B_PETN14":   PN = "EM10"  !CDS_PN = "EM10";
"B_PETN15":   PN = "EW10"  !CDS_PN = "EW10";
"B_PETP8":   PN = "CH7"  !CDS_PN = "CH7";
"B_PETP9":   PN = "CR7"  !CDS_PN = "CR7";
"B_PETP10":   PN = "DB7"  !CDS_PN = "DB7";
"B_PETP11":   PN = "DJ7"  !CDS_PN = "DJ7";
"B_PETP12":   PN = "DT7"  !CDS_PN = "DT7";
"B_PETP13":   PN = "EC7"  !CDS_PN = "EC7";
"B_PETP14":   PN = "EK7"  !CDS_PN = "EK7";
"B_PETP15":   PN = "EU7"  !CDS_PN = "EU7";
DRAWING = "@t6g_mb_lib.t6g(sch_1):page415";
BODY = "PT5161LRS","I37": #LOCATION = "U6012" !CDS_LOCATION = "U6012" &SEC = "9" #&CDS_SEC = "9";
"B_PERN8":   PN = "CL35"  !CDS_PN = "CL35";
"B_PERN9":   PN = "CV35"  !CDS_PN = "CV35";
"B_PERN10":   PN = "DE35"  !CDS_PN = "DE35";
"B_PERN11":   PN = "DM35"  !CDS_PN = "DM35";
"B_PERN12":   PN = "DW35"  !CDS_PN = "DW35";
"B_PERN13":   PN = "EF35"  !CDS_PN = "EF35";
"B_PERN14":   PN = "EN35"  !CDS_PN = "EN35";
"B_PERN15":   PN = "EY35"  !CDS_PN = "EY35";
"B_PERP8":   PN = "CJ34"  !CDS_PN = "CJ34";
"B_PERP9":   PN = "CT34"  !CDS_PN = "CT34";
"B_PERP10":   PN = "DC34"  !CDS_PN = "DC34";
"B_PERP11":   PN = "DK34"  !CDS_PN = "DK34";
"B_PERP12":   PN = "DU34"  !CDS_PN = "DU34";
"B_PERP13":   PN = "ED34"  !CDS_PN = "ED34";
"B_PERP14":   PN = "EL34"  !CDS_PN = "EL34";
"B_PERP15":   PN = "EV34"  !CDS_PN = "EV34";
BODY = "PT5161LRS","I38": #LOCATION = "U6012" !CDS_LOCATION = "U6012" &SEC = "8" #&CDS_SEC = "8";
"B_PERN0":   PN = "R35"  !CDS_PN = "R35";
"B_PERN1":   PN = "AB35"  !CDS_PN = "AB35";
"B_PERN2":   PN = "AJ35"  !CDS_PN = "AJ35";
"B_PERN3":   PN = "AT35"  !CDS_PN = "AT35";
"B_PERN4":   PN = "BC35"  !CDS_PN = "BC35";
"B_PERN5":   PN = "BK35"  !CDS_PN = "BK35";
"B_PERN6":   PN = "BU35"  !CDS_PN = "BU35";
"B_PERN7":   PN = "CD35"  !CDS_PN = "CD35";
"B_PERP0":   PN = "N34"  !CDS_PN = "N34";
"B_PERP1":   PN = "Y34"  !CDS_PN = "Y34";
"B_PERP2":   PN = "AG34"  !CDS_PN = "AG34";
"B_PERP3":   PN = "AP34"  !CDS_PN = "AP34";
"B_PERP4":   PN = "BA34"  !CDS_PN = "BA34";
"B_PERP5":   PN = "BH34"  !CDS_PN = "BH34";
"B_PERP6":   PN = "BR34"  !CDS_PN = "BR34";
"B_PERP7":   PN = "CB34"  !CDS_PN = "CB34";
DRAWING = "@t6g_mb_lib.t6g(sch_1):page416";
BODY = "PT5161LRS","I1": #LOCATION = "U6012" !CDS_LOCATION = "U6012" &SEC = "6" #&CDS_SEC = "6";
"A_PETN0":   PN = "P29"  !CDS_PN = "P29";
"A_PETN1":   PN = "AA29"  !CDS_PN = "AA29";
"A_PETN2":   PN = "AH29"  !CDS_PN = "AH29";
"A_PETN3":   PN = "AR29"  !CDS_PN = "AR29";
"A_PETN4":   PN = "BB29"  !CDS_PN = "BB29";
"A_PETN5":   PN = "BJ29"  !CDS_PN = "BJ29";
"A_PETN6":   PN = "BT29"  !CDS_PN = "BT29";
"A_PETN7":   PN = "CC29"  !CDS_PN = "CC29";
"A_PETP0":   PN = "M26"  !CDS_PN = "M26";
"A_PETP1":   PN = "W26"  !CDS_PN = "W26";
"A_PETP2":   PN = "AF26"  !CDS_PN = "AF26";
"A_PETP3":   PN = "AN26"  !CDS_PN = "AN26";
"A_PETP4":   PN = "AY26"  !CDS_PN = "AY26";
"A_PETP5":   PN = "BG26"  !CDS_PN = "BG26";
"A_PETP6":   PN = "BP26"  !CDS_PN = "BP26";
"A_PETP7":   PN = "CA26"  !CDS_PN = "CA26";
BODY = "PT5161LRS","I38": #LOCATION = "U6012" !CDS_LOCATION = "U6012" &SEC = "7" #&CDS_SEC = "7";
"A_PETN8":   PN = "CK29"  !CDS_PN = "CK29";
"A_PETN9":   PN = "CU29"  !CDS_PN = "CU29";
"A_PETN10":   PN = "DD29"  !CDS_PN = "DD29";
"A_PETN11":   PN = "DL29"  !CDS_PN = "DL29";
"A_PETN12":   PN = "DV29"  !CDS_PN = "DV29";
"A_PETN13":   PN = "EE29"  !CDS_PN = "EE29";
"A_PETN14":   PN = "EM29"  !CDS_PN = "EM29";
"A_PETN15":   PN = "EW29"  !CDS_PN = "EW29";
"A_PETP8":   PN = "CH26"  !CDS_PN = "CH26";
"A_PETP9":   PN = "CR26"  !CDS_PN = "CR26";
"A_PETP10":   PN = "DB26"  !CDS_PN = "DB26";
"A_PETP11":   PN = "DJ26"  !CDS_PN = "DJ26";
"A_PETP12":   PN = "DT26"  !CDS_PN = "DT26";
"A_PETP13":   PN = "EC26"  !CDS_PN = "EC26";
"A_PETP14":   PN = "EK26"  !CDS_PN = "EK26";
"A_PETP15":   PN = "EU26"  !CDS_PN = "EU26";
DRAWING = "@t6g_mb_lib.t6g(sch_1):page417";
BODY = "PT5161LRS","I1": #LOCATION = "U6012" !CDS_LOCATION = "U6012" &SEC = "1" #&CDS_SEC = "1";
"A_PERN0":   PN = "N2"  !CDS_PN = "N2";
"A_PERN1":   PN = "Y2"  !CDS_PN = "Y2";
"A_PERN2":   PN = "AG2"  !CDS_PN = "AG2";
"A_PERN3":   PN = "AP2"  !CDS_PN = "AP2";
"A_PERN4":   PN = "BA2"  !CDS_PN = "BA2";
"A_PERN5":   PN = "BH2"  !CDS_PN = "BH2";
"A_PERN6":   PN = "BR2"  !CDS_PN = "BR2";
"A_PERN7":   PN = "CB2"  !CDS_PN = "CB2";
"A_PERP0":   PN = "R1"  !CDS_PN = "R1";
"A_PERP1":   PN = "AB1"  !CDS_PN = "AB1";
"A_PERP2":   PN = "AJ1"  !CDS_PN = "AJ1";
"A_PERP3":   PN = "AT1"  !CDS_PN = "AT1";
"A_PERP4":   PN = "BC1"  !CDS_PN = "BC1";
"A_PERP5":   PN = "BK1"  !CDS_PN = "BK1";
"A_PERP6":   PN = "BU1"  !CDS_PN = "BU1";
"A_PERP7":   PN = "CD1"  !CDS_PN = "CD1";
BODY = "PT5161LRS","I38": #LOCATION = "U6012" !CDS_LOCATION = "U6012" &SEC = "2" #&CDS_SEC = "2";
"A_PERN8":   PN = "CJ2"  !CDS_PN = "CJ2";
"A_PERN9":   PN = "CT2"  !CDS_PN = "CT2";
"A_PERN10":   PN = "DC2"  !CDS_PN = "DC2";
"A_PERN11":   PN = "DK2"  !CDS_PN = "DK2";
"A_PERN12":   PN = "DU2"  !CDS_PN = "DU2";
"A_PERN13":   PN = "ED2"  !CDS_PN = "ED2";
"A_PERN14":   PN = "EL2"  !CDS_PN = "EL2";
"A_PERN15":   PN = "EV2"  !CDS_PN = "EV2";
"A_PERP8":   PN = "CL1"  !CDS_PN = "CL1";
"A_PERP9":   PN = "CV1"  !CDS_PN = "CV1";
"A_PERP10":   PN = "DE1"  !CDS_PN = "DE1";
"A_PERP11":   PN = "DM1"  !CDS_PN = "DM1";
"A_PERP12":   PN = "DW1"  !CDS_PN = "DW1";
"A_PERP13":   PN = "EF1"  !CDS_PN = "EF1";
"A_PERP14":   PN = "EN1"  !CDS_PN = "EN1";
"A_PERP15":   PN = "EY1"  !CDS_PN = "EY1";
DRAWING = "@t6g_mb_lib.t6g(sch_1):page418";
BODY = "Q_CAP_DIFFBUS","I17": #LOCATION = "C6580" !CDS_LOCATION = "C6580" &SEC = "1" #&CDS_SEC = "1";
"1":   PN = "1"  !CDS_PN = "1";
"2":   PN = "2"  !CDS_PN = "2";
BODY = "Q_CAP_DIFFBUS","I18": #LOCATION = "C6579" !CDS_LOCATION = "C6579" &SEC = "1" #&CDS_SEC = "1";
"1":   PN = "1"  !CDS_PN = "1";
"2":   PN = "2"  !CDS_PN = "2";
BODY = "Q_CAP_DIFFBUS","I19": #LOCATION = "C6577" !CDS_LOCATION = "C6577" &SEC = "1" #&CDS_SEC = "1";
"1":   PN = "1"  !CDS_PN = "1";
"2":   PN = "2"  !CDS_PN = "2";
BODY = "Q_CAP_DIFFBUS","I20": #LOCATION = "C6578" !CDS_LOCATION = "C6578" &SEC = "1" #&CDS_SEC = "1";
"1":   PN = "1"  !CDS_PN = "1";
"2":   PN = "2"  !CDS_PN = "2";
BODY = "Q_CAP_DIFFBUS","I25": #LOCATION = "C6575" !CDS_LOCATION = "C6575" &SEC = "1" #&CDS_SEC = "1";
"1":   PN = "1"  !CDS_PN = "1";
"2":   PN = "2"  !CDS_PN = "2";
BODY = "Q_CAP_DIFFBUS","I26": #LOCATION = "C6576" !CDS_LOCATION = "C6576" &SEC = "1" #&CDS_SEC = "1";
"1":   PN = "1"  !CDS_PN = "1";
"2":   PN = "2"  !CDS_PN = "2";
BODY = "Q_CAP_DIFFBUS","I27": #LOCATION = "C6573" !CDS_LOCATION = "C6573" &SEC = "1" #&CDS_SEC = "1";
"1":   PN = "1"  !CDS_PN = "1";
"2":   PN = "2"  !CDS_PN = "2";
BODY = "Q_CAP_DIFFBUS","I28": #LOCATION = "C6574" !CDS_LOCATION = "C6574" &SEC = "1" #&CDS_SEC = "1";
"1":   PN = "1"  !CDS_PN = "1";
"2":   PN = "2"  !CDS_PN = "2";
BODY = "Q_CAP_DIFFBUS","I29": #LOCATION = "C6572" !CDS_LOCATION = "C6572" &SEC = "1" #&CDS_SEC = "1";
"1":   PN = "1"  !CDS_PN = "1";
"2":   PN = "2"  !CDS_PN = "2";
BODY = "Q_CAP_DIFFBUS","I30": #LOCATION = "C6571" !CDS_LOCATION = "C6571" &SEC = "1" #&CDS_SEC = "1";
"1":   PN = "1"  !CDS_PN = "1";
"2":   PN = "2"  !CDS_PN = "2";
BODY = "Q_CAP_DIFFBUS","I31": #LOCATION = "C6570" !CDS_LOCATION = "C6570" &SEC = "1" #&CDS_SEC = "1";
"1":   PN = "1"  !CDS_PN = "1";
"2":   PN = "2"  !CDS_PN = "2";
BODY = "Q_CAP_DIFFBUS","I32": #LOCATION = "C6567" !CDS_LOCATION = "C6567" &SEC = "1" #&CDS_SEC = "1";
"1":   PN = "1"  !CDS_PN = "1";
"2":   PN = "2"  !CDS_PN = "2";
BODY = "Q_CAP_DIFFBUS","I33": #LOCATION = "C6568" !CDS_LOCATION = "C6568" &SEC = "1" #&CDS_SEC = "1";
"1":   PN = "1"  !CDS_PN = "1";
"2":   PN = "2"  !CDS_PN = "2";
BODY = "Q_CAP_DIFFBUS","I34": #LOCATION = "C6569" !CDS_LOCATION = "C6569" &SEC = "1" #&CDS_SEC = "1";
"1":   PN = "1"  !CDS_PN = "1";
"2":   PN = "2"  !CDS_PN = "2";
BODY = "PT5161LRS","I47": #LOCATION = "U6012" !CDS_LOCATION = "U6012" &SEC = "10" #&CDS_SEC = "10";
"B_PETN0":   PN = "P10"  !CDS_PN = "P10";
"B_PETN1":   PN = "AA10"  !CDS_PN = "AA10";
"B_PETN2":   PN = "AH10"  !CDS_PN = "AH10";
"B_PETN3":   PN = "AR10"  !CDS_PN = "AR10";
"B_PETN4":   PN = "BB10"  !CDS_PN = "BB10";
"B_PETN5":   PN = "BJ10"  !CDS_PN = "BJ10";
"B_PETN6":   PN = "BT10"  !CDS_PN = "BT10";
"B_PETN7":   PN = "CC10"  !CDS_PN = "CC10";
"B_PETP0":   PN = "M7"  !CDS_PN = "M7";
"B_PETP1":   PN = "W7"  !CDS_PN = "W7";
"B_PETP2":   PN = "AF7"  !CDS_PN = "AF7";
"B_PETP3":   PN = "AN7"  !CDS_PN = "AN7";
"B_PETP4":   PN = "AY7"  !CDS_PN = "AY7";
"B_PETP5":   PN = "BG7"  !CDS_PN = "BG7";
"B_PETP6":   PN = "BP7"  !CDS_PN = "BP7";
"B_PETP7":   PN = "CA7"  !CDS_PN = "CA7";
BODY = "Q_CAP_DIFFBUS","I48": #LOCATION = "C6566" !CDS_LOCATION = "C6566" &SEC = "1" #&CDS_SEC = "1";
"1":   PN = "1"  !CDS_PN = "1";
"2":   PN = "2"  !CDS_PN = "2";
BODY = "Q_CAP_DIFFBUS","I49": #LOCATION = "C6565" !CDS_LOCATION = "C6565" &SEC = "1" #&CDS_SEC = "1";
"1":   PN = "1"  !CDS_PN = "1";
"2":   PN = "2"  !CDS_PN = "2";
BODY = "Q_CAP_DIFFBUS","I88": #LOCATION = "C6596" !CDS_LOCATION = "C6596" &SEC = "1" #&CDS_SEC = "1";
"1":   PN = "1"  !CDS_PN = "1";
"2":   PN = "2"  !CDS_PN = "2";
BODY = "Q_CAP_DIFFBUS","I89": #LOCATION = "C6595" !CDS_LOCATION = "C6595" &SEC = "1" #&CDS_SEC = "1";
"1":   PN = "1"  !CDS_PN = "1";
"2":   PN = "2"  !CDS_PN = "2";
BODY = "Q_CAP_DIFFBUS","I90": #LOCATION = "C6594" !CDS_LOCATION = "C6594" &SEC = "1" #&CDS_SEC = "1";
"1":   PN = "1"  !CDS_PN = "1";
"2":   PN = "2"  !CDS_PN = "2";
BODY = "Q_CAP_DIFFBUS","I91": #LOCATION = "C6593" !CDS_LOCATION = "C6593" &SEC = "1" #&CDS_SEC = "1";
"1":   PN = "1"  !CDS_PN = "1";
"2":   PN = "2"  !CDS_PN = "2";
BODY = "Q_CAP_DIFFBUS","I92": #LOCATION = "C6592" !CDS_LOCATION = "C6592" &SEC = "1" #&CDS_SEC = "1";
"1":   PN = "1"  !CDS_PN = "1";
"2":   PN = "2"  !CDS_PN = "2";
BODY = "Q_CAP_DIFFBUS","I93": #LOCATION = "C6591" !CDS_LOCATION = "C6591" &SEC = "1" #&CDS_SEC = "1";
"1":   PN = "1"  !CDS_PN = "1";
"2":   PN = "2"  !CDS_PN = "2";
BODY = "Q_CAP_DIFFBUS","I94": #LOCATION = "C6590" !CDS_LOCATION = "C6590" &SEC = "1" #&CDS_SEC = "1";
"1":   PN = "1"  !CDS_PN = "1";
"2":   PN = "2"  !CDS_PN = "2";
BODY = "Q_CAP_DIFFBUS","I95": #LOCATION = "C6589" !CDS_LOCATION = "C6589" &SEC = "1" #&CDS_SEC = "1";
"1":   PN = "1"  !CDS_PN = "1";
"2":   PN = "2"  !CDS_PN = "2";
BODY = "Q_CAP_DIFFBUS","I96": #LOCATION = "C6588" !CDS_LOCATION = "C6588" &SEC = "1" #&CDS_SEC = "1";
"1":   PN = "1"  !CDS_PN = "1";
"2":   PN = "2"  !CDS_PN = "2";
BODY = "Q_CAP_DIFFBUS","I97": #LOCATION = "C6587" !CDS_LOCATION = "C6587" &SEC = "1" #&CDS_SEC = "1";
"1":   PN = "1"  !CDS_PN = "1";
"2":   PN = "2"  !CDS_PN = "2";
BODY = "Q_CAP_DIFFBUS","I98": #LOCATION = "C6586" !CDS_LOCATION = "C6586" &SEC = "1" #&CDS_SEC = "1";
"1":   PN = "1"  !CDS_PN = "1";
"2":   PN = "2"  !CDS_PN = "2";
BODY = "Q_CAP_DIFFBUS","I99": #LOCATION = "C6585" !CDS_LOCATION = "C6585" &SEC = "1" #&CDS_SEC = "1";
"1":   PN = "1"  !CDS_PN = "1";
"2":   PN = "2"  !CDS_PN = "2";
BODY = "Q_CAP_DIFFBUS","I100": #LOCATION = "C6584" !CDS_LOCATION = "C6584" &SEC = "1" #&CDS_SEC = "1";
"1":   PN = "1"  !CDS_PN = "1";
"2":   PN = "2"  !CDS_PN = "2";
BODY = "Q_CAP_DIFFBUS","I101": #LOCATION = "C6583" !CDS_LOCATION = "C6583" &SEC = "1" #&CDS_SEC = "1";
"1":   PN = "1"  !CDS_PN = "1";
"2":   PN = "2"  !CDS_PN = "2";
BODY = "Q_CAP_DIFFBUS","I104": #LOCATION = "C6581" !CDS_LOCATION = "C6581" &SEC = "1" #&CDS_SEC = "1";
"1":   PN = "1"  !CDS_PN = "1";
"2":   PN = "2"  !CDS_PN = "2";
BODY = "Q_CAP_DIFFBUS","I105": #LOCATION = "C6582" !CDS_LOCATION = "C6582" &SEC = "1" #&CDS_SEC = "1";
"1":   PN = "1"  !CDS_PN = "1";
"2":   PN = "2"  !CDS_PN = "2";
BODY = "PT5161LRS","I142": #LOCATION = "U6012" !CDS_LOCATION = "U6012" &SEC = "11" #&CDS_SEC = "11";
"B_PETN8":   PN = "CK10"  !CDS_PN = "CK10";
"B_PETN9":   PN = "CU10"  !CDS_PN = "CU10";
"B_PETN10":   PN = "DD10"  !CDS_PN = "DD10";
"B_PETN11":   PN = "DL10"  !CDS_PN = "DL10";
"B_PETN12":   PN = "DV10"  !CDS_PN = "DV10";
"B_PETN13":   PN = "EE10"  !CDS_PN = "EE10";
"B_PETN14":   PN = "EM10"  !CDS_PN = "EM10";
"B_PETN15":   PN = "EW10"  !CDS_PN = "EW10";
"B_PETP8":   PN = "CH7"  !CDS_PN = "CH7";
"B_PETP9":   PN = "CR7"  !CDS_PN = "CR7";
"B_PETP10":   PN = "DB7"  !CDS_PN = "DB7";
"B_PETP11":   PN = "DJ7"  !CDS_PN = "DJ7";
"B_PETP12":   PN = "DT7"  !CDS_PN = "DT7";
"B_PETP13":   PN = "EC7"  !CDS_PN = "EC7";
"B_PETP14":   PN = "EK7"  !CDS_PN = "EK7";
"B_PETP15":   PN = "EU7"  !CDS_PN = "EU7";
DRAWING = "@t6g_mb_lib.t6g(sch_1):page426";
BODY = "PT5161LRS","I1": #LOCATION = "U6013" !CDS_LOCATION = "U6013" &SEC = "8" #&CDS_SEC = "8";
"B_PERN0":   PN = "R35"  !CDS_PN = "R35";
"B_PERN1":   PN = "AB35"  !CDS_PN = "AB35";
"B_PERN2":   PN = "AJ35"  !CDS_PN = "AJ35";
"B_PERN3":   PN = "AT35"  !CDS_PN = "AT35";
"B_PERN4":   PN = "BC35"  !CDS_PN = "BC35";
"B_PERN5":   PN = "BK35"  !CDS_PN = "BK35";
"B_PERN6":   PN = "BU35"  !CDS_PN = "BU35";
"B_PERN7":   PN = "CD35"  !CDS_PN = "CD35";
"B_PERP0":   PN = "N34"  !CDS_PN = "N34";
"B_PERP1":   PN = "Y34"  !CDS_PN = "Y34";
"B_PERP2":   PN = "AG34"  !CDS_PN = "AG34";
"B_PERP3":   PN = "AP34"  !CDS_PN = "AP34";
"B_PERP4":   PN = "BA34"  !CDS_PN = "BA34";
"B_PERP5":   PN = "BH34"  !CDS_PN = "BH34";
"B_PERP6":   PN = "BR34"  !CDS_PN = "BR34";
"B_PERP7":   PN = "CB34"  !CDS_PN = "CB34";
BODY = "PT5161LRS","I38": #LOCATION = "U6013" !CDS_LOCATION = "U6013" &SEC = "9" #&CDS_SEC = "9";
"B_PERN8":   PN = "CL35"  !CDS_PN = "CL35";
"B_PERN9":   PN = "CV35"  !CDS_PN = "CV35";
"B_PERN10":   PN = "DE35"  !CDS_PN = "DE35";
"B_PERN11":   PN = "DM35"  !CDS_PN = "DM35";
"B_PERN12":   PN = "DW35"  !CDS_PN = "DW35";
"B_PERN13":   PN = "EF35"  !CDS_PN = "EF35";
"B_PERN14":   PN = "EN35"  !CDS_PN = "EN35";
"B_PERN15":   PN = "EY35"  !CDS_PN = "EY35";
"B_PERP8":   PN = "CJ34"  !CDS_PN = "CJ34";
"B_PERP9":   PN = "CT34"  !CDS_PN = "CT34";
"B_PERP10":   PN = "DC34"  !CDS_PN = "DC34";
"B_PERP11":   PN = "DK34"  !CDS_PN = "DK34";
"B_PERP12":   PN = "DU34"  !CDS_PN = "DU34";
"B_PERP13":   PN = "ED34"  !CDS_PN = "ED34";
"B_PERP14":   PN = "EL34"  !CDS_PN = "EL34";
"B_PERP15":   PN = "EV34"  !CDS_PN = "EV34";
DRAWING = "@t6g_mb_lib.t6g(sch_1):page427";
BODY = "PT5161LRS","I1": #LOCATION = "U6013" !CDS_LOCATION = "U6013" &SEC = "6" #&CDS_SEC = "6";
"A_PETN0":   PN = "P29"  !CDS_PN = "P29";
"A_PETN1":   PN = "AA29"  !CDS_PN = "AA29";
"A_PETN2":   PN = "AH29"  !CDS_PN = "AH29";
"A_PETN3":   PN = "AR29"  !CDS_PN = "AR29";
"A_PETN4":   PN = "BB29"  !CDS_PN = "BB29";
"A_PETN5":   PN = "BJ29"  !CDS_PN = "BJ29";
"A_PETN6":   PN = "BT29"  !CDS_PN = "BT29";
"A_PETN7":   PN = "CC29"  !CDS_PN = "CC29";
"A_PETP0":   PN = "M26"  !CDS_PN = "M26";
"A_PETP1":   PN = "W26"  !CDS_PN = "W26";
"A_PETP2":   PN = "AF26"  !CDS_PN = "AF26";
"A_PETP3":   PN = "AN26"  !CDS_PN = "AN26";
"A_PETP4":   PN = "AY26"  !CDS_PN = "AY26";
"A_PETP5":   PN = "BG26"  !CDS_PN = "BG26";
"A_PETP6":   PN = "BP26"  !CDS_PN = "BP26";
"A_PETP7":   PN = "CA26"  !CDS_PN = "CA26";
BODY = "PT5161LRS","I38": #LOCATION = "U6013" !CDS_LOCATION = "U6013" &SEC = "7" #&CDS_SEC = "7";
"A_PETN8":   PN = "CK29"  !CDS_PN = "CK29";
"A_PETN9":   PN = "CU29"  !CDS_PN = "CU29";
"A_PETN10":   PN = "DD29"  !CDS_PN = "DD29";
"A_PETN11":   PN = "DL29"  !CDS_PN = "DL29";
"A_PETN12":   PN = "DV29"  !CDS_PN = "DV29";
"A_PETN13":   PN = "EE29"  !CDS_PN = "EE29";
"A_PETN14":   PN = "EM29"  !CDS_PN = "EM29";
"A_PETN15":   PN = "EW29"  !CDS_PN = "EW29";
"A_PETP8":   PN = "CH26"  !CDS_PN = "CH26";
"A_PETP9":   PN = "CR26"  !CDS_PN = "CR26";
"A_PETP10":   PN = "DB26"  !CDS_PN = "DB26";
"A_PETP11":   PN = "DJ26"  !CDS_PN = "DJ26";
"A_PETP12":   PN = "DT26"  !CDS_PN = "DT26";
"A_PETP13":   PN = "EC26"  !CDS_PN = "EC26";
"A_PETP14":   PN = "EK26"  !CDS_PN = "EK26";
"A_PETP15":   PN = "EU26"  !CDS_PN = "EU26";
DRAWING = "@t6g_mb_lib.t6g(sch_1):page428";
BODY = "PT5161LRS","I1": #LOCATION = "U6013" !CDS_LOCATION = "U6013" &SEC = "1" #&CDS_SEC = "1";
"A_PERN0":   PN = "N2"  !CDS_PN = "N2";
"A_PERN1":   PN = "Y2"  !CDS_PN = "Y2";
"A_PERN2":   PN = "AG2"  !CDS_PN = "AG2";
"A_PERN3":   PN = "AP2"  !CDS_PN = "AP2";
"A_PERN4":   PN = "BA2"  !CDS_PN = "BA2";
"A_PERN5":   PN = "BH2"  !CDS_PN = "BH2";
"A_PERN6":   PN = "BR2"  !CDS_PN = "BR2";
"A_PERN7":   PN = "CB2"  !CDS_PN = "CB2";
"A_PERP0":   PN = "R1"  !CDS_PN = "R1";
"A_PERP1":   PN = "AB1"  !CDS_PN = "AB1";
"A_PERP2":   PN = "AJ1"  !CDS_PN = "AJ1";
"A_PERP3":   PN = "AT1"  !CDS_PN = "AT1";
"A_PERP4":   PN = "BC1"  !CDS_PN = "BC1";
"A_PERP5":   PN = "BK1"  !CDS_PN = "BK1";
"A_PERP6":   PN = "BU1"  !CDS_PN = "BU1";
"A_PERP7":   PN = "CD1"  !CDS_PN = "CD1";
BODY = "PT5161LRS","I38": #LOCATION = "U6013" !CDS_LOCATION = "U6013" &SEC = "2" #&CDS_SEC = "2";
"A_PERN8":   PN = "CJ2"  !CDS_PN = "CJ2";
"A_PERN9":   PN = "CT2"  !CDS_PN = "CT2";
"A_PERN10":   PN = "DC2"  !CDS_PN = "DC2";
"A_PERN11":   PN = "DK2"  !CDS_PN = "DK2";
"A_PERN12":   PN = "DU2"  !CDS_PN = "DU2";
"A_PERN13":   PN = "ED2"  !CDS_PN = "ED2";
"A_PERN14":   PN = "EL2"  !CDS_PN = "EL2";
"A_PERN15":   PN = "EV2"  !CDS_PN = "EV2";
"A_PERP8":   PN = "CL1"  !CDS_PN = "CL1";
"A_PERP9":   PN = "CV1"  !CDS_PN = "CV1";
"A_PERP10":   PN = "DE1"  !CDS_PN = "DE1";
"A_PERP11":   PN = "DM1"  !CDS_PN = "DM1";
"A_PERP12":   PN = "DW1"  !CDS_PN = "DW1";
"A_PERP13":   PN = "EF1"  !CDS_PN = "EF1";
"A_PERP14":   PN = "EN1"  !CDS_PN = "EN1";
"A_PERP15":   PN = "EY1"  !CDS_PN = "EY1";
DRAWING = "@t6g_mb_lib.t6g(sch_1):page429";
BODY = "Q_CAP_DIFFBUS","I19": #LOCATION = "C6611" !CDS_LOCATION = "C6611" &SEC = "1" #&CDS_SEC = "1";
"1":   PN = "1"  !CDS_PN = "1";
"2":   PN = "2"  !CDS_PN = "2";
BODY = "Q_CAP_DIFFBUS","I20": #LOCATION = "C6612" !CDS_LOCATION = "C6612" &SEC = "1" #&CDS_SEC = "1";
"1":   PN = "1"  !CDS_PN = "1";
"2":   PN = "2"  !CDS_PN = "2";
BODY = "Q_CAP_DIFFBUS","I21": #LOCATION = "C6610" !CDS_LOCATION = "C6610" &SEC = "1" #&CDS_SEC = "1";
"1":   PN = "1"  !CDS_PN = "1";
"2":   PN = "2"  !CDS_PN = "2";
BODY = "Q_CAP_DIFFBUS","I22": #LOCATION = "C6609" !CDS_LOCATION = "C6609" &SEC = "1" #&CDS_SEC = "1";
"1":   PN = "1"  !CDS_PN = "1";
"2":   PN = "2"  !CDS_PN = "2";
BODY = "Q_CAP_DIFFBUS","I23": #LOCATION = "C6608" !CDS_LOCATION = "C6608" &SEC = "1" #&CDS_SEC = "1";
"1":   PN = "1"  !CDS_PN = "1";
"2":   PN = "2"  !CDS_PN = "2";
BODY = "Q_CAP_DIFFBUS","I24": #LOCATION = "C6607" !CDS_LOCATION = "C6607" &SEC = "1" #&CDS_SEC = "1";
"1":   PN = "1"  !CDS_PN = "1";
"2":   PN = "2"  !CDS_PN = "2";
BODY = "Q_CAP_DIFFBUS","I31": #LOCATION = "C6606" !CDS_LOCATION = "C6606" &SEC = "1" #&CDS_SEC = "1";
"1":   PN = "1"  !CDS_PN = "1";
"2":   PN = "2"  !CDS_PN = "2";
BODY = "Q_CAP_DIFFBUS","I32": #LOCATION = "C6605" !CDS_LOCATION = "C6605" &SEC = "1" #&CDS_SEC = "1";
"1":   PN = "1"  !CDS_PN = "1";
"2":   PN = "2"  !CDS_PN = "2";
BODY = "Q_CAP_DIFFBUS","I33": #LOCATION = "C6604" !CDS_LOCATION = "C6604" &SEC = "1" #&CDS_SEC = "1";
"1":   PN = "1"  !CDS_PN = "1";
"2":   PN = "2"  !CDS_PN = "2";
BODY = "Q_CAP_DIFFBUS","I34": #LOCATION = "C6603" !CDS_LOCATION = "C6603" &SEC = "1" #&CDS_SEC = "1";
"1":   PN = "1"  !CDS_PN = "1";
"2":   PN = "2"  !CDS_PN = "2";
BODY = "Q_CAP_DIFFBUS","I35": #LOCATION = "C6602" !CDS_LOCATION = "C6602" &SEC = "1" #&CDS_SEC = "1";
"1":   PN = "1"  !CDS_PN = "1";
"2":   PN = "2"  !CDS_PN = "2";
BODY = "Q_CAP_DIFFBUS","I36": #LOCATION = "C6601" !CDS_LOCATION = "C6601" &SEC = "1" #&CDS_SEC = "1";
"1":   PN = "1"  !CDS_PN = "1";
"2":   PN = "2"  !CDS_PN = "2";
BODY = "Q_CAP_DIFFBUS","I37": #LOCATION = "C6600" !CDS_LOCATION = "C6600" &SEC = "1" #&CDS_SEC = "1";
"1":   PN = "1"  !CDS_PN = "1";
"2":   PN = "2"  !CDS_PN = "2";
BODY = "Q_CAP_DIFFBUS","I38": #LOCATION = "C6599" !CDS_LOCATION = "C6599" &SEC = "1" #&CDS_SEC = "1";
"1":   PN = "1"  !CDS_PN = "1";
"2":   PN = "2"  !CDS_PN = "2";
BODY = "Q_CAP_DIFFBUS","I39": #LOCATION = "C6598" !CDS_LOCATION = "C6598" &SEC = "1" #&CDS_SEC = "1";
"1":   PN = "1"  !CDS_PN = "1";
"2":   PN = "2"  !CDS_PN = "2";
BODY = "Q_CAP_DIFFBUS","I40": #LOCATION = "C6597" !CDS_LOCATION = "C6597" &SEC = "1" #&CDS_SEC = "1";
"1":   PN = "1"  !CDS_PN = "1";
"2":   PN = "2"  !CDS_PN = "2";
BODY = "PT5161LRS","I51": #LOCATION = "U6013" !CDS_LOCATION = "U6013" &SEC = "10" #&CDS_SEC = "10";
"B_PETN0":   PN = "P10"  !CDS_PN = "P10";
"B_PETN1":   PN = "AA10"  !CDS_PN = "AA10";
"B_PETN2":   PN = "AH10"  !CDS_PN = "AH10";
"B_PETN3":   PN = "AR10"  !CDS_PN = "AR10";
"B_PETN4":   PN = "BB10"  !CDS_PN = "BB10";
"B_PETN5":   PN = "BJ10"  !CDS_PN = "BJ10";
"B_PETN6":   PN = "BT10"  !CDS_PN = "BT10";
"B_PETN7":   PN = "CC10"  !CDS_PN = "CC10";
"B_PETP0":   PN = "M7"  !CDS_PN = "M7";
"B_PETP1":   PN = "W7"  !CDS_PN = "W7";
"B_PETP2":   PN = "AF7"  !CDS_PN = "AF7";
"B_PETP3":   PN = "AN7"  !CDS_PN = "AN7";
"B_PETP4":   PN = "AY7"  !CDS_PN = "AY7";
"B_PETP5":   PN = "BG7"  !CDS_PN = "BG7";
"B_PETP6":   PN = "BP7"  !CDS_PN = "BP7";
"B_PETP7":   PN = "CA7"  !CDS_PN = "CA7";
BODY = "Q_CAP_DIFFBUS","I90": #LOCATION = "C6628" !CDS_LOCATION = "C6628" &SEC = "1" #&CDS_SEC = "1";
"1":   PN = "1"  !CDS_PN = "1";
"2":   PN = "2"  !CDS_PN = "2";
BODY = "Q_CAP_DIFFBUS","I91": #LOCATION = "C6625" !CDS_LOCATION = "C6625" &SEC = "1" #&CDS_SEC = "1";
"1":   PN = "1"  !CDS_PN = "1";
"2":   PN = "2"  !CDS_PN = "2";
BODY = "Q_CAP_DIFFBUS","I92": #LOCATION = "C6626" !CDS_LOCATION = "C6626" &SEC = "1" #&CDS_SEC = "1";
"1":   PN = "1"  !CDS_PN = "1";
"2":   PN = "2"  !CDS_PN = "2";
BODY = "Q_CAP_DIFFBUS","I93": #LOCATION = "C6627" !CDS_LOCATION = "C6627" &SEC = "1" #&CDS_SEC = "1";
"1":   PN = "1"  !CDS_PN = "1";
"2":   PN = "2"  !CDS_PN = "2";
BODY = "Q_CAP_DIFFBUS","I94": #LOCATION = "C6623" !CDS_LOCATION = "C6623" &SEC = "1" #&CDS_SEC = "1";
"1":   PN = "1"  !CDS_PN = "1";
"2":   PN = "2"  !CDS_PN = "2";
BODY = "Q_CAP_DIFFBUS","I95": #LOCATION = "C6624" !CDS_LOCATION = "C6624" &SEC = "1" #&CDS_SEC = "1";
"1":   PN = "1"  !CDS_PN = "1";
"2":   PN = "2"  !CDS_PN = "2";
BODY = "Q_CAP_DIFFBUS","I96": #LOCATION = "C6621" !CDS_LOCATION = "C6621" &SEC = "1" #&CDS_SEC = "1";
"1":   PN = "1"  !CDS_PN = "1";
"2":   PN = "2"  !CDS_PN = "2";
BODY = "Q_CAP_DIFFBUS","I97": #LOCATION = "C6622" !CDS_LOCATION = "C6622" &SEC = "1" #&CDS_SEC = "1";
"1":   PN = "1"  !CDS_PN = "1";
"2":   PN = "2"  !CDS_PN = "2";
BODY = "Q_CAP_DIFFBUS","I98": #LOCATION = "C6620" !CDS_LOCATION = "C6620" &SEC = "1" #&CDS_SEC = "1";
"1":   PN = "1"  !CDS_PN = "1";
"2":   PN = "2"  !CDS_PN = "2";
BODY = "Q_CAP_DIFFBUS","I99": #LOCATION = "C6618" !CDS_LOCATION = "C6618" &SEC = "1" #&CDS_SEC = "1";
"1":   PN = "1"  !CDS_PN = "1";
"2":   PN = "2"  !CDS_PN = "2";
BODY = "Q_CAP_DIFFBUS","I100": #LOCATION = "C6619" !CDS_LOCATION = "C6619" &SEC = "1" #&CDS_SEC = "1";
"1":   PN = "1"  !CDS_PN = "1";
"2":   PN = "2"  !CDS_PN = "2";
BODY = "Q_CAP_DIFFBUS","I101": #LOCATION = "C6617" !CDS_LOCATION = "C6617" &SEC = "1" #&CDS_SEC = "1";
"1":   PN = "1"  !CDS_PN = "1";
"2":   PN = "2"  !CDS_PN = "2";
BODY = "Q_CAP_DIFFBUS","I102": #LOCATION = "C6615" !CDS_LOCATION = "C6615" &SEC = "1" #&CDS_SEC = "1";
"1":   PN = "1"  !CDS_PN = "1";
"2":   PN = "2"  !CDS_PN = "2";
BODY = "Q_CAP_DIFFBUS","I103": #LOCATION = "C6616" !CDS_LOCATION = "C6616" &SEC = "1" #&CDS_SEC = "1";
"1":   PN = "1"  !CDS_PN = "1";
"2":   PN = "2"  !CDS_PN = "2";
BODY = "Q_CAP_DIFFBUS","I104": #LOCATION = "C6614" !CDS_LOCATION = "C6614" &SEC = "1" #&CDS_SEC = "1";
"1":   PN = "1"  !CDS_PN = "1";
"2":   PN = "2"  !CDS_PN = "2";
BODY = "Q_CAP_DIFFBUS","I105": #LOCATION = "C6613" !CDS_LOCATION = "C6613" &SEC = "1" #&CDS_SEC = "1";
"1":   PN = "1"  !CDS_PN = "1";
"2":   PN = "2"  !CDS_PN = "2";
BODY = "PT5161LRS","I142": #LOCATION = "U6013" !CDS_LOCATION = "U6013" &SEC = "11" #&CDS_SEC = "11";
"B_PETN8":   PN = "CK10"  !CDS_PN = "CK10";
"B_PETN9":   PN = "CU10"  !CDS_PN = "CU10";
"B_PETN10":   PN = "DD10"  !CDS_PN = "DD10";
"B_PETN11":   PN = "DL10"  !CDS_PN = "DL10";
"B_PETN12":   PN = "DV10"  !CDS_PN = "DV10";
"B_PETN13":   PN = "EE10"  !CDS_PN = "EE10";
"B_PETN14":   PN = "EM10"  !CDS_PN = "EM10";
"B_PETN15":   PN = "EW10"  !CDS_PN = "EW10";
"B_PETP8":   PN = "CH7"  !CDS_PN = "CH7";
"B_PETP9":   PN = "CR7"  !CDS_PN = "CR7";
"B_PETP10":   PN = "DB7"  !CDS_PN = "DB7";
"B_PETP11":   PN = "DJ7"  !CDS_PN = "DJ7";
"B_PETP12":   PN = "DT7"  !CDS_PN = "DT7";
"B_PETP13":   PN = "EC7"  !CDS_PN = "EC7";
"B_PETP14":   PN = "EK7"  !CDS_PN = "EK7";
"B_PETP15":   PN = "EU7"  !CDS_PN = "EU7";
DRAWING = "@t6g_mb_lib.t6g(sch_1):page437";
BODY = "PT5161LRS","I1": #LOCATION = "U6014" !CDS_LOCATION = "U6014" &SEC = "8" #&CDS_SEC = "8";
"B_PERN0":   PN = "R35"  !CDS_PN = "R35";
"B_PERN1":   PN = "AB35"  !CDS_PN = "AB35";
"B_PERN2":   PN = "AJ35"  !CDS_PN = "AJ35";
"B_PERN3":   PN = "AT35"  !CDS_PN = "AT35";
"B_PERN4":   PN = "BC35"  !CDS_PN = "BC35";
"B_PERN5":   PN = "BK35"  !CDS_PN = "BK35";
"B_PERN6":   PN = "BU35"  !CDS_PN = "BU35";
"B_PERN7":   PN = "CD35"  !CDS_PN = "CD35";
"B_PERP0":   PN = "N34"  !CDS_PN = "N34";
"B_PERP1":   PN = "Y34"  !CDS_PN = "Y34";
"B_PERP2":   PN = "AG34"  !CDS_PN = "AG34";
"B_PERP3":   PN = "AP34"  !CDS_PN = "AP34";
"B_PERP4":   PN = "BA34"  !CDS_PN = "BA34";
"B_PERP5":   PN = "BH34"  !CDS_PN = "BH34";
"B_PERP6":   PN = "BR34"  !CDS_PN = "BR34";
"B_PERP7":   PN = "CB34"  !CDS_PN = "CB34";
BODY = "PT5161LRS","I38": #LOCATION = "U6014" !CDS_LOCATION = "U6014" &SEC = "9" #&CDS_SEC = "9";
"B_PERN8":   PN = "CL35"  !CDS_PN = "CL35";
"B_PERN9":   PN = "CV35"  !CDS_PN = "CV35";
"B_PERN10":   PN = "DE35"  !CDS_PN = "DE35";
"B_PERN11":   PN = "DM35"  !CDS_PN = "DM35";
"B_PERN12":   PN = "DW35"  !CDS_PN = "DW35";
"B_PERN13":   PN = "EF35"  !CDS_PN = "EF35";
"B_PERN14":   PN = "EN35"  !CDS_PN = "EN35";
"B_PERN15":   PN = "EY35"  !CDS_PN = "EY35";
"B_PERP8":   PN = "CJ34"  !CDS_PN = "CJ34";
"B_PERP9":   PN = "CT34"  !CDS_PN = "CT34";
"B_PERP10":   PN = "DC34"  !CDS_PN = "DC34";
"B_PERP11":   PN = "DK34"  !CDS_PN = "DK34";
"B_PERP12":   PN = "DU34"  !CDS_PN = "DU34";
"B_PERP13":   PN = "ED34"  !CDS_PN = "ED34";
"B_PERP14":   PN = "EL34"  !CDS_PN = "EL34";
"B_PERP15":   PN = "EV34"  !CDS_PN = "EV34";
DRAWING = "@t6g_mb_lib.t6g(sch_1):page438";
BODY = "PT5161LRS","I1": #LOCATION = "U6014" !CDS_LOCATION = "U6014" &SEC = "6" #&CDS_SEC = "6";
"A_PETN0":   PN = "P29"  !CDS_PN = "P29";
"A_PETN1":   PN = "AA29"  !CDS_PN = "AA29";
"A_PETN2":   PN = "AH29"  !CDS_PN = "AH29";
"A_PETN3":   PN = "AR29"  !CDS_PN = "AR29";
"A_PETN4":   PN = "BB29"  !CDS_PN = "BB29";
"A_PETN5":   PN = "BJ29"  !CDS_PN = "BJ29";
"A_PETN6":   PN = "BT29"  !CDS_PN = "BT29";
"A_PETN7":   PN = "CC29"  !CDS_PN = "CC29";
"A_PETP0":   PN = "M26"  !CDS_PN = "M26";
"A_PETP1":   PN = "W26"  !CDS_PN = "W26";
"A_PETP2":   PN = "AF26"  !CDS_PN = "AF26";
"A_PETP3":   PN = "AN26"  !CDS_PN = "AN26";
"A_PETP4":   PN = "AY26"  !CDS_PN = "AY26";
"A_PETP5":   PN = "BG26"  !CDS_PN = "BG26";
"A_PETP6":   PN = "BP26"  !CDS_PN = "BP26";
"A_PETP7":   PN = "CA26"  !CDS_PN = "CA26";
BODY = "PT5161LRS","I38": #LOCATION = "U6014" !CDS_LOCATION = "U6014" &SEC = "7" #&CDS_SEC = "7";
"A_PETN8":   PN = "CK29"  !CDS_PN = "CK29";
"A_PETN9":   PN = "CU29"  !CDS_PN = "CU29";
"A_PETN10":   PN = "DD29"  !CDS_PN = "DD29";
"A_PETN11":   PN = "DL29"  !CDS_PN = "DL29";
"A_PETN12":   PN = "DV29"  !CDS_PN = "DV29";
"A_PETN13":   PN = "EE29"  !CDS_PN = "EE29";
"A_PETN14":   PN = "EM29"  !CDS_PN = "EM29";
"A_PETN15":   PN = "EW29"  !CDS_PN = "EW29";
"A_PETP8":   PN = "CH26"  !CDS_PN = "CH26";
"A_PETP9":   PN = "CR26"  !CDS_PN = "CR26";
"A_PETP10":   PN = "DB26"  !CDS_PN = "DB26";
"A_PETP11":   PN = "DJ26"  !CDS_PN = "DJ26";
"A_PETP12":   PN = "DT26"  !CDS_PN = "DT26";
"A_PETP13":   PN = "EC26"  !CDS_PN = "EC26";
"A_PETP14":   PN = "EK26"  !CDS_PN = "EK26";
"A_PETP15":   PN = "EU26"  !CDS_PN = "EU26";
DRAWING = "@t6g_mb_lib.t6g(sch_1):page439";
BODY = "Q_CAP_DIFFBUS","I15": #LOCATION = "C6644" !CDS_LOCATION = "C6644" &SEC = "1" #&CDS_SEC = "1";
"1":   PN = "1"  !CDS_PN = "1";
"2":   PN = "2"  !CDS_PN = "2";
BODY = "Q_CAP_DIFFBUS","I16": #LOCATION = "C6643" !CDS_LOCATION = "C6643" &SEC = "1" #&CDS_SEC = "1";
"1":   PN = "1"  !CDS_PN = "1";
"2":   PN = "2"  !CDS_PN = "2";
BODY = "Q_CAP_DIFFBUS","I18": #LOCATION = "C6641" !CDS_LOCATION = "C6641" &SEC = "1" #&CDS_SEC = "1";
"1":   PN = "1"  !CDS_PN = "1";
"2":   PN = "2"  !CDS_PN = "2";
BODY = "Q_CAP_DIFFBUS","I19": #LOCATION = "C6642" !CDS_LOCATION = "C6642" &SEC = "1" #&CDS_SEC = "1";
"1":   PN = "1"  !CDS_PN = "1";
"2":   PN = "2"  !CDS_PN = "2";
BODY = "Q_CAP_DIFFBUS","I20": #LOCATION = "C6639" !CDS_LOCATION = "C6639" &SEC = "1" #&CDS_SEC = "1";
"1":   PN = "1"  !CDS_PN = "1";
"2":   PN = "2"  !CDS_PN = "2";
BODY = "Q_CAP_DIFFBUS","I21": #LOCATION = "C6640" !CDS_LOCATION = "C6640" &SEC = "1" #&CDS_SEC = "1";
"1":   PN = "1"  !CDS_PN = "1";
"2":   PN = "2"  !CDS_PN = "2";
BODY = "Q_CAP_DIFFBUS","I22": #LOCATION = "C6637" !CDS_LOCATION = "C6637" &SEC = "1" #&CDS_SEC = "1";
"1":   PN = "1"  !CDS_PN = "1";
"2":   PN = "2"  !CDS_PN = "2";
BODY = "Q_CAP_DIFFBUS","I23": #LOCATION = "C6638" !CDS_LOCATION = "C6638" &SEC = "1" #&CDS_SEC = "1";
"1":   PN = "1"  !CDS_PN = "1";
"2":   PN = "2"  !CDS_PN = "2";
BODY = "Q_CAP_DIFFBUS","I24": #LOCATION = "C6636" !CDS_LOCATION = "C6636" &SEC = "1" #&CDS_SEC = "1";
"1":   PN = "1"  !CDS_PN = "1";
"2":   PN = "2"  !CDS_PN = "2";
BODY = "Q_CAP_DIFFBUS","I25": #LOCATION = "C6635" !CDS_LOCATION = "C6635" &SEC = "1" #&CDS_SEC = "1";
"1":   PN = "1"  !CDS_PN = "1";
"2":   PN = "2"  !CDS_PN = "2";
BODY = "Q_CAP_DIFFBUS","I26": #LOCATION = "C6634" !CDS_LOCATION = "C6634" &SEC = "1" #&CDS_SEC = "1";
"1":   PN = "1"  !CDS_PN = "1";
"2":   PN = "2"  !CDS_PN = "2";
BODY = "Q_CAP_DIFFBUS","I27": #LOCATION = "C6633" !CDS_LOCATION = "C6633" &SEC = "1" #&CDS_SEC = "1";
"1":   PN = "1"  !CDS_PN = "1";
"2":   PN = "2"  !CDS_PN = "2";
BODY = "PT5161LRS","I43": #LOCATION = "U6014" !CDS_LOCATION = "U6014" &SEC = "10" #&CDS_SEC = "10";
"B_PETN0":   PN = "P10"  !CDS_PN = "P10";
"B_PETN1":   PN = "AA10"  !CDS_PN = "AA10";
"B_PETN2":   PN = "AH10"  !CDS_PN = "AH10";
"B_PETN3":   PN = "AR10"  !CDS_PN = "AR10";
"B_PETN4":   PN = "BB10"  !CDS_PN = "BB10";
"B_PETN5":   PN = "BJ10"  !CDS_PN = "BJ10";
"B_PETN6":   PN = "BT10"  !CDS_PN = "BT10";
"B_PETN7":   PN = "CC10"  !CDS_PN = "CC10";
"B_PETP0":   PN = "M7"  !CDS_PN = "M7";
"B_PETP1":   PN = "W7"  !CDS_PN = "W7";
"B_PETP2":   PN = "AF7"  !CDS_PN = "AF7";
"B_PETP3":   PN = "AN7"  !CDS_PN = "AN7";
"B_PETP4":   PN = "AY7"  !CDS_PN = "AY7";
"B_PETP5":   PN = "BG7"  !CDS_PN = "BG7";
"B_PETP6":   PN = "BP7"  !CDS_PN = "BP7";
"B_PETP7":   PN = "CA7"  !CDS_PN = "CA7";
BODY = "Q_CAP_DIFFBUS","I44": #LOCATION = "C6632" !CDS_LOCATION = "C6632" &SEC = "1" #&CDS_SEC = "1";
"1":   PN = "1"  !CDS_PN = "1";
"2":   PN = "2"  !CDS_PN = "2";
BODY = "Q_CAP_DIFFBUS","I45": #LOCATION = "C6631" !CDS_LOCATION = "C6631" &SEC = "1" #&CDS_SEC = "1";
"1":   PN = "1"  !CDS_PN = "1";
"2":   PN = "2"  !CDS_PN = "2";
BODY = "Q_CAP_DIFFBUS","I46": #LOCATION = "C6629" !CDS_LOCATION = "C6629" &SEC = "1" #&CDS_SEC = "1";
"1":   PN = "1"  !CDS_PN = "1";
"2":   PN = "2"  !CDS_PN = "2";
BODY = "Q_CAP_DIFFBUS","I47": #LOCATION = "C6630" !CDS_LOCATION = "C6630" &SEC = "1" #&CDS_SEC = "1";
"1":   PN = "1"  !CDS_PN = "1";
"2":   PN = "2"  !CDS_PN = "2";
BODY = "Q_CAP_DIFFBUS","I86": #LOCATION = "C6660" !CDS_LOCATION = "C6660" &SEC = "1" #&CDS_SEC = "1";
"1":   PN = "1"  !CDS_PN = "1";
"2":   PN = "2"  !CDS_PN = "2";
BODY = "Q_CAP_DIFFBUS","I87": #LOCATION = "C6659" !CDS_LOCATION = "C6659" &SEC = "1" #&CDS_SEC = "1";
"1":   PN = "1"  !CDS_PN = "1";
"2":   PN = "2"  !CDS_PN = "2";
BODY = "Q_CAP_DIFFBUS","I88": #LOCATION = "C6658" !CDS_LOCATION = "C6658" &SEC = "1" #&CDS_SEC = "1";
"1":   PN = "1"  !CDS_PN = "1";
"2":   PN = "2"  !CDS_PN = "2";
BODY = "Q_CAP_DIFFBUS","I89": #LOCATION = "C6657" !CDS_LOCATION = "C6657" &SEC = "1" #&CDS_SEC = "1";
"1":   PN = "1"  !CDS_PN = "1";
"2":   PN = "2"  !CDS_PN = "2";
BODY = "Q_CAP_DIFFBUS","I90": #LOCATION = "C6656" !CDS_LOCATION = "C6656" &SEC = "1" #&CDS_SEC = "1";
"1":   PN = "1"  !CDS_PN = "1";
"2":   PN = "2"  !CDS_PN = "2";
BODY = "Q_CAP_DIFFBUS","I91": #LOCATION = "C6655" !CDS_LOCATION = "C6655" &SEC = "1" #&CDS_SEC = "1";
"1":   PN = "1"  !CDS_PN = "1";
"2":   PN = "2"  !CDS_PN = "2";
BODY = "Q_CAP_DIFFBUS","I92": #LOCATION = "C6654" !CDS_LOCATION = "C6654" &SEC = "1" #&CDS_SEC = "1";
"1":   PN = "1"  !CDS_PN = "1";
"2":   PN = "2"  !CDS_PN = "2";
BODY = "Q_CAP_DIFFBUS","I93": #LOCATION = "C6653" !CDS_LOCATION = "C6653" &SEC = "1" #&CDS_SEC = "1";
"1":   PN = "1"  !CDS_PN = "1";
"2":   PN = "2"  !CDS_PN = "2";
BODY = "Q_CAP_DIFFBUS","I94": #LOCATION = "C6652" !CDS_LOCATION = "C6652" &SEC = "1" #&CDS_SEC = "1";
"1":   PN = "1"  !CDS_PN = "1";
"2":   PN = "2"  !CDS_PN = "2";
BODY = "Q_CAP_DIFFBUS","I95": #LOCATION = "C6651" !CDS_LOCATION = "C6651" &SEC = "1" #&CDS_SEC = "1";
"1":   PN = "1"  !CDS_PN = "1";
"2":   PN = "2"  !CDS_PN = "2";
BODY = "Q_CAP_DIFFBUS","I96": #LOCATION = "C6649" !CDS_LOCATION = "C6649" &SEC = "1" #&CDS_SEC = "1";
"1":   PN = "1"  !CDS_PN = "1";
"2":   PN = "2"  !CDS_PN = "2";
BODY = "Q_CAP_DIFFBUS","I97": #LOCATION = "C6650" !CDS_LOCATION = "C6650" &SEC = "1" #&CDS_SEC = "1";
"1":   PN = "1"  !CDS_PN = "1";
"2":   PN = "2"  !CDS_PN = "2";
BODY = "Q_CAP_DIFFBUS","I102": #LOCATION = "C6647" !CDS_LOCATION = "C6647" &SEC = "1" #&CDS_SEC = "1";
"1":   PN = "1"  !CDS_PN = "1";
"2":   PN = "2"  !CDS_PN = "2";
BODY = "Q_CAP_DIFFBUS","I103": #LOCATION = "C6648" !CDS_LOCATION = "C6648" &SEC = "1" #&CDS_SEC = "1";
"1":   PN = "1"  !CDS_PN = "1";
"2":   PN = "2"  !CDS_PN = "2";
BODY = "Q_CAP_DIFFBUS","I104": #LOCATION = "C6646" !CDS_LOCATION = "C6646" &SEC = "1" #&CDS_SEC = "1";
"1":   PN = "1"  !CDS_PN = "1";
"2":   PN = "2"  !CDS_PN = "2";
BODY = "Q_CAP_DIFFBUS","I105": #LOCATION = "C6645" !CDS_LOCATION = "C6645" &SEC = "1" #&CDS_SEC = "1";
"1":   PN = "1"  !CDS_PN = "1";
"2":   PN = "2"  !CDS_PN = "2";
BODY = "PT5161LRS","I142": #LOCATION = "U6014" !CDS_LOCATION = "U6014" &SEC = "11" #&CDS_SEC = "11";
"B_PETN8":   PN = "CK10"  !CDS_PN = "CK10";
"B_PETN9":   PN = "CU10"  !CDS_PN = "CU10";
"B_PETN10":   PN = "DD10"  !CDS_PN = "DD10";
"B_PETN11":   PN = "DL10"  !CDS_PN = "DL10";
"B_PETN12":   PN = "DV10"  !CDS_PN = "DV10";
"B_PETN13":   PN = "EE10"  !CDS_PN = "EE10";
"B_PETN14":   PN = "EM10"  !CDS_PN = "EM10";
"B_PETN15":   PN = "EW10"  !CDS_PN = "EW10";
"B_PETP8":   PN = "CH7"  !CDS_PN = "CH7";
"B_PETP9":   PN = "CR7"  !CDS_PN = "CR7";
"B_PETP10":   PN = "DB7"  !CDS_PN = "DB7";
"B_PETP11":   PN = "DJ7"  !CDS_PN = "DJ7";
"B_PETP12":   PN = "DT7"  !CDS_PN = "DT7";
"B_PETP13":   PN = "EC7"  !CDS_PN = "EC7";
"B_PETP14":   PN = "EK7"  !CDS_PN = "EK7";
"B_PETP15":   PN = "EU7"  !CDS_PN = "EU7";
DRAWING = "@t6g_mb_lib.t6g(sch_1):page447";
BODY = "PT5161LRS","I1": #LOCATION = "U6016" !CDS_LOCATION = "U6016" &SEC = "8" #&CDS_SEC = "8";
"B_PERN0":   PN = "R35"  !CDS_PN = "R35";
"B_PERN1":   PN = "AB35"  !CDS_PN = "AB35";
"B_PERN2":   PN = "AJ35"  !CDS_PN = "AJ35";
"B_PERN3":   PN = "AT35"  !CDS_PN = "AT35";
"B_PERN4":   PN = "BC35"  !CDS_PN = "BC35";
"B_PERN5":   PN = "BK35"  !CDS_PN = "BK35";
"B_PERN6":   PN = "BU35"  !CDS_PN = "BU35";
"B_PERN7":   PN = "CD35"  !CDS_PN = "CD35";
"B_PERP0":   PN = "N34"  !CDS_PN = "N34";
"B_PERP1":   PN = "Y34"  !CDS_PN = "Y34";
"B_PERP2":   PN = "AG34"  !CDS_PN = "AG34";
"B_PERP3":   PN = "AP34"  !CDS_PN = "AP34";
"B_PERP4":   PN = "BA34"  !CDS_PN = "BA34";
"B_PERP5":   PN = "BH34"  !CDS_PN = "BH34";
"B_PERP6":   PN = "BR34"  !CDS_PN = "BR34";
"B_PERP7":   PN = "CB34"  !CDS_PN = "CB34";
BODY = "PT5161LRS","I38": #LOCATION = "U6016" !CDS_LOCATION = "U6016" &SEC = "9" #&CDS_SEC = "9";
"B_PERN8":   PN = "CL35"  !CDS_PN = "CL35";
"B_PERN9":   PN = "CV35"  !CDS_PN = "CV35";
"B_PERN10":   PN = "DE35"  !CDS_PN = "DE35";
"B_PERN11":   PN = "DM35"  !CDS_PN = "DM35";
"B_PERN12":   PN = "DW35"  !CDS_PN = "DW35";
"B_PERN13":   PN = "EF35"  !CDS_PN = "EF35";
"B_PERN14":   PN = "EN35"  !CDS_PN = "EN35";
"B_PERN15":   PN = "EY35"  !CDS_PN = "EY35";
"B_PERP8":   PN = "CJ34"  !CDS_PN = "CJ34";
"B_PERP9":   PN = "CT34"  !CDS_PN = "CT34";
"B_PERP10":   PN = "DC34"  !CDS_PN = "DC34";
"B_PERP11":   PN = "DK34"  !CDS_PN = "DK34";
"B_PERP12":   PN = "DU34"  !CDS_PN = "DU34";
"B_PERP13":   PN = "ED34"  !CDS_PN = "ED34";
"B_PERP14":   PN = "EL34"  !CDS_PN = "EL34";
"B_PERP15":   PN = "EV34"  !CDS_PN = "EV34";
DRAWING = "@t6g_mb_lib.t6g(sch_1):page448";
BODY = "PT5161LRS","I1": #LOCATION = "U6016" !CDS_LOCATION = "U6016" &SEC = "6" #&CDS_SEC = "6";
"A_PETN0":   PN = "P29"  !CDS_PN = "P29";
"A_PETN1":   PN = "AA29"  !CDS_PN = "AA29";
"A_PETN2":   PN = "AH29"  !CDS_PN = "AH29";
"A_PETN3":   PN = "AR29"  !CDS_PN = "AR29";
"A_PETN4":   PN = "BB29"  !CDS_PN = "BB29";
"A_PETN5":   PN = "BJ29"  !CDS_PN = "BJ29";
"A_PETN6":   PN = "BT29"  !CDS_PN = "BT29";
"A_PETN7":   PN = "CC29"  !CDS_PN = "CC29";
"A_PETP0":   PN = "M26"  !CDS_PN = "M26";
"A_PETP1":   PN = "W26"  !CDS_PN = "W26";
"A_PETP2":   PN = "AF26"  !CDS_PN = "AF26";
"A_PETP3":   PN = "AN26"  !CDS_PN = "AN26";
"A_PETP4":   PN = "AY26"  !CDS_PN = "AY26";
"A_PETP5":   PN = "BG26"  !CDS_PN = "BG26";
"A_PETP6":   PN = "BP26"  !CDS_PN = "BP26";
"A_PETP7":   PN = "CA26"  !CDS_PN = "CA26";
BODY = "PT5161LRS","I38": #LOCATION = "U6016" !CDS_LOCATION = "U6016" &SEC = "7" #&CDS_SEC = "7";
"A_PETN8":   PN = "CK29"  !CDS_PN = "CK29";
"A_PETN9":   PN = "CU29"  !CDS_PN = "CU29";
"A_PETN10":   PN = "DD29"  !CDS_PN = "DD29";
"A_PETN11":   PN = "DL29"  !CDS_PN = "DL29";
"A_PETN12":   PN = "DV29"  !CDS_PN = "DV29";
"A_PETN13":   PN = "EE29"  !CDS_PN = "EE29";
"A_PETN14":   PN = "EM29"  !CDS_PN = "EM29";
"A_PETN15":   PN = "EW29"  !CDS_PN = "EW29";
"A_PETP8":   PN = "CH26"  !CDS_PN = "CH26";
"A_PETP9":   PN = "CR26"  !CDS_PN = "CR26";
"A_PETP10":   PN = "DB26"  !CDS_PN = "DB26";
"A_PETP11":   PN = "DJ26"  !CDS_PN = "DJ26";
"A_PETP12":   PN = "DT26"  !CDS_PN = "DT26";
"A_PETP13":   PN = "EC26"  !CDS_PN = "EC26";
"A_PETP14":   PN = "EK26"  !CDS_PN = "EK26";
"A_PETP15":   PN = "EU26"  !CDS_PN = "EU26";
DRAWING = "@t6g_mb_lib.t6g(sch_1):page449";
BODY = "PT5161LRS","I1": #LOCATION = "U6016" !CDS_LOCATION = "U6016" &SEC = "1" #&CDS_SEC = "1";
"A_PERN0":   PN = "N2"  !CDS_PN = "N2";
"A_PERN1":   PN = "Y2"  !CDS_PN = "Y2";
"A_PERN2":   PN = "AG2"  !CDS_PN = "AG2";
"A_PERN3":   PN = "AP2"  !CDS_PN = "AP2";
"A_PERN4":   PN = "BA2"  !CDS_PN = "BA2";
"A_PERN5":   PN = "BH2"  !CDS_PN = "BH2";
"A_PERN6":   PN = "BR2"  !CDS_PN = "BR2";
"A_PERN7":   PN = "CB2"  !CDS_PN = "CB2";
"A_PERP0":   PN = "R1"  !CDS_PN = "R1";
"A_PERP1":   PN = "AB1"  !CDS_PN = "AB1";
"A_PERP2":   PN = "AJ1"  !CDS_PN = "AJ1";
"A_PERP3":   PN = "AT1"  !CDS_PN = "AT1";
"A_PERP4":   PN = "BC1"  !CDS_PN = "BC1";
"A_PERP5":   PN = "BK1"  !CDS_PN = "BK1";
"A_PERP6":   PN = "BU1"  !CDS_PN = "BU1";
"A_PERP7":   PN = "CD1"  !CDS_PN = "CD1";
BODY = "PT5161LRS","I38": #LOCATION = "U6016" !CDS_LOCATION = "U6016" &SEC = "2" #&CDS_SEC = "2";
"A_PERN8":   PN = "CJ2"  !CDS_PN = "CJ2";
"A_PERN9":   PN = "CT2"  !CDS_PN = "CT2";
"A_PERN10":   PN = "DC2"  !CDS_PN = "DC2";
"A_PERN11":   PN = "DK2"  !CDS_PN = "DK2";
"A_PERN12":   PN = "DU2"  !CDS_PN = "DU2";
"A_PERN13":   PN = "ED2"  !CDS_PN = "ED2";
"A_PERN14":   PN = "EL2"  !CDS_PN = "EL2";
"A_PERN15":   PN = "EV2"  !CDS_PN = "EV2";
"A_PERP8":   PN = "CL1"  !CDS_PN = "CL1";
"A_PERP9":   PN = "CV1"  !CDS_PN = "CV1";
"A_PERP10":   PN = "DE1"  !CDS_PN = "DE1";
"A_PERP11":   PN = "DM1"  !CDS_PN = "DM1";
"A_PERP12":   PN = "DW1"  !CDS_PN = "DW1";
"A_PERP13":   PN = "EF1"  !CDS_PN = "EF1";
"A_PERP14":   PN = "EN1"  !CDS_PN = "EN1";
"A_PERP15":   PN = "EY1"  !CDS_PN = "EY1";
DRAWING = "@t6g_mb_lib.t6g(sch_1):page450";
BODY = "Q_CAP_DIFFBUS","I17": #LOCATION = "C6708" !CDS_LOCATION = "C6708" &SEC = "1" #&CDS_SEC = "1";
"1":   PN = "1"  !CDS_PN = "1";
"2":   PN = "2"  !CDS_PN = "2";
BODY = "Q_CAP_DIFFBUS","I18": #LOCATION = "C6707" !CDS_LOCATION = "C6707" &SEC = "1" #&CDS_SEC = "1";
"1":   PN = "1"  !CDS_PN = "1";
"2":   PN = "2"  !CDS_PN = "2";
BODY = "Q_CAP_DIFFBUS","I19": #LOCATION = "C6706" !CDS_LOCATION = "C6706" &SEC = "1" #&CDS_SEC = "1";
"1":   PN = "1"  !CDS_PN = "1";
"2":   PN = "2"  !CDS_PN = "2";
BODY = "Q_CAP_DIFFBUS","I20": #LOCATION = "C6705" !CDS_LOCATION = "C6705" &SEC = "1" #&CDS_SEC = "1";
"1":   PN = "1"  !CDS_PN = "1";
"2":   PN = "2"  !CDS_PN = "2";
BODY = "Q_CAP_DIFFBUS","I21": #LOCATION = "C6704" !CDS_LOCATION = "C6704" &SEC = "1" #&CDS_SEC = "1";
"1":   PN = "1"  !CDS_PN = "1";
"2":   PN = "2"  !CDS_PN = "2";
BODY = "Q_CAP_DIFFBUS","I22": #LOCATION = "C6703" !CDS_LOCATION = "C6703" &SEC = "1" #&CDS_SEC = "1";
"1":   PN = "1"  !CDS_PN = "1";
"2":   PN = "2"  !CDS_PN = "2";
BODY = "Q_CAP_DIFFBUS","I23": #LOCATION = "C6702" !CDS_LOCATION = "C6702" &SEC = "1" #&CDS_SEC = "1";
"1":   PN = "1"  !CDS_PN = "1";
"2":   PN = "2"  !CDS_PN = "2";
BODY = "Q_CAP_DIFFBUS","I24": #LOCATION = "C6701" !CDS_LOCATION = "C6701" &SEC = "1" #&CDS_SEC = "1";
"1":   PN = "1"  !CDS_PN = "1";
"2":   PN = "2"  !CDS_PN = "2";
BODY = "Q_CAP_DIFFBUS","I25": #LOCATION = "C6699" !CDS_LOCATION = "C6699" &SEC = "1" #&CDS_SEC = "1";
"1":   PN = "1"  !CDS_PN = "1";
"2":   PN = "2"  !CDS_PN = "2";
BODY = "Q_CAP_DIFFBUS","I26": #LOCATION = "C6700" !CDS_LOCATION = "C6700" &SEC = "1" #&CDS_SEC = "1";
"1":   PN = "1"  !CDS_PN = "1";
"2":   PN = "2"  !CDS_PN = "2";
BODY = "Q_CAP_DIFFBUS","I27": #LOCATION = "C6698" !CDS_LOCATION = "C6698" &SEC = "1" #&CDS_SEC = "1";
"1":   PN = "1"  !CDS_PN = "1";
"2":   PN = "2"  !CDS_PN = "2";
BODY = "Q_CAP_DIFFBUS","I28": #LOCATION = "C6696" !CDS_LOCATION = "C6696" &SEC = "1" #&CDS_SEC = "1";
"1":   PN = "1"  !CDS_PN = "1";
"2":   PN = "2"  !CDS_PN = "2";
BODY = "Q_CAP_DIFFBUS","I29": #LOCATION = "C6695" !CDS_LOCATION = "C6695" &SEC = "1" #&CDS_SEC = "1";
"1":   PN = "1"  !CDS_PN = "1";
"2":   PN = "2"  !CDS_PN = "2";
BODY = "Q_CAP_DIFFBUS","I30": #LOCATION = "C6697" !CDS_LOCATION = "C6697" &SEC = "1" #&CDS_SEC = "1";
"1":   PN = "1"  !CDS_PN = "1";
"2":   PN = "2"  !CDS_PN = "2";
BODY = "PT5161LRS","I33": #LOCATION = "U6016" !CDS_LOCATION = "U6016" &SEC = "10" #&CDS_SEC = "10";
"B_PETN0":   PN = "P10"  !CDS_PN = "P10";
"B_PETN1":   PN = "AA10"  !CDS_PN = "AA10";
"B_PETN2":   PN = "AH10"  !CDS_PN = "AH10";
"B_PETN3":   PN = "AR10"  !CDS_PN = "AR10";
"B_PETN4":   PN = "BB10"  !CDS_PN = "BB10";
"B_PETN5":   PN = "BJ10"  !CDS_PN = "BJ10";
"B_PETN6":   PN = "BT10"  !CDS_PN = "BT10";
"B_PETN7":   PN = "CC10"  !CDS_PN = "CC10";
"B_PETP0":   PN = "M7"  !CDS_PN = "M7";
"B_PETP1":   PN = "W7"  !CDS_PN = "W7";
"B_PETP2":   PN = "AF7"  !CDS_PN = "AF7";
"B_PETP3":   PN = "AN7"  !CDS_PN = "AN7";
"B_PETP4":   PN = "AY7"  !CDS_PN = "AY7";
"B_PETP5":   PN = "BG7"  !CDS_PN = "BG7";
"B_PETP6":   PN = "BP7"  !CDS_PN = "BP7";
"B_PETP7":   PN = "CA7"  !CDS_PN = "CA7";
BODY = "Q_CAP_DIFFBUS","I34": #LOCATION = "C6693" !CDS_LOCATION = "C6693" &SEC = "1" #&CDS_SEC = "1";
"1":   PN = "1"  !CDS_PN = "1";
"2":   PN = "2"  !CDS_PN = "2";
BODY = "Q_CAP_DIFFBUS","I35": #LOCATION = "C6694" !CDS_LOCATION = "C6694" &SEC = "1" #&CDS_SEC = "1";
"1":   PN = "1"  !CDS_PN = "1";
"2":   PN = "2"  !CDS_PN = "2";
BODY = "Q_CAP_DIFFBUS","I81": #LOCATION = "C6724" !CDS_LOCATION = "C6724" &SEC = "1" #&CDS_SEC = "1";
"1":   PN = "1"  !CDS_PN = "1";
"2":   PN = "2"  !CDS_PN = "2";
BODY = "Q_CAP_DIFFBUS","I82": #LOCATION = "C6723" !CDS_LOCATION = "C6723" &SEC = "1" #&CDS_SEC = "1";
"1":   PN = "1"  !CDS_PN = "1";
"2":   PN = "2"  !CDS_PN = "2";
BODY = "Q_CAP_DIFFBUS","I83": #LOCATION = "C6722" !CDS_LOCATION = "C6722" &SEC = "1" #&CDS_SEC = "1";
"1":   PN = "1"  !CDS_PN = "1";
"2":   PN = "2"  !CDS_PN = "2";
BODY = "Q_CAP_DIFFBUS","I84": #LOCATION = "C6721" !CDS_LOCATION = "C6721" &SEC = "1" #&CDS_SEC = "1";
"1":   PN = "1"  !CDS_PN = "1";
"2":   PN = "2"  !CDS_PN = "2";
BODY = "Q_CAP_DIFFBUS","I90": #LOCATION = "C6720" !CDS_LOCATION = "C6720" &SEC = "1" #&CDS_SEC = "1";
"1":   PN = "1"  !CDS_PN = "1";
"2":   PN = "2"  !CDS_PN = "2";
BODY = "Q_CAP_DIFFBUS","I91": #LOCATION = "C6719" !CDS_LOCATION = "C6719" &SEC = "1" #&CDS_SEC = "1";
"1":   PN = "1"  !CDS_PN = "1";
"2":   PN = "2"  !CDS_PN = "2";
BODY = "Q_CAP_DIFFBUS","I92": #LOCATION = "C6718" !CDS_LOCATION = "C6718" &SEC = "1" #&CDS_SEC = "1";
"1":   PN = "1"  !CDS_PN = "1";
"2":   PN = "2"  !CDS_PN = "2";
BODY = "Q_CAP_DIFFBUS","I93": #LOCATION = "C6717" !CDS_LOCATION = "C6717" &SEC = "1" #&CDS_SEC = "1";
"1":   PN = "1"  !CDS_PN = "1";
"2":   PN = "2"  !CDS_PN = "2";
BODY = "Q_CAP_DIFFBUS","I94": #LOCATION = "C6716" !CDS_LOCATION = "C6716" &SEC = "1" #&CDS_SEC = "1";
"1":   PN = "1"  !CDS_PN = "1";
"2":   PN = "2"  !CDS_PN = "2";
BODY = "Q_CAP_DIFFBUS","I95": #LOCATION = "C6715" !CDS_LOCATION = "C6715" &SEC = "1" #&CDS_SEC = "1";
"1":   PN = "1"  !CDS_PN = "1";
"2":   PN = "2"  !CDS_PN = "2";
BODY = "Q_CAP_DIFFBUS","I96": #LOCATION = "C6714" !CDS_LOCATION = "C6714" &SEC = "1" #&CDS_SEC = "1";
"1":   PN = "1"  !CDS_PN = "1";
"2":   PN = "2"  !CDS_PN = "2";
BODY = "Q_CAP_DIFFBUS","I97": #LOCATION = "C6713" !CDS_LOCATION = "C6713" &SEC = "1" #&CDS_SEC = "1";
"1":   PN = "1"  !CDS_PN = "1";
"2":   PN = "2"  !CDS_PN = "2";
BODY = "Q_CAP_DIFFBUS","I98": #LOCATION = "C6712" !CDS_LOCATION = "C6712" &SEC = "1" #&CDS_SEC = "1";
"1":   PN = "1"  !CDS_PN = "1";
"2":   PN = "2"  !CDS_PN = "2";
BODY = "Q_CAP_DIFFBUS","I99": #LOCATION = "C6711" !CDS_LOCATION = "C6711" &SEC = "1" #&CDS_SEC = "1";
"1":   PN = "1"  !CDS_PN = "1";
"2":   PN = "2"  !CDS_PN = "2";
BODY = "Q_CAP_DIFFBUS","I102": #LOCATION = "C6709" !CDS_LOCATION = "C6709" &SEC = "1" #&CDS_SEC = "1";
"1":   PN = "1"  !CDS_PN = "1";
"2":   PN = "2"  !CDS_PN = "2";
BODY = "Q_CAP_DIFFBUS","I103": #LOCATION = "C6710" !CDS_LOCATION = "C6710" &SEC = "1" #&CDS_SEC = "1";
"1":   PN = "1"  !CDS_PN = "1";
"2":   PN = "2"  !CDS_PN = "2";
BODY = "PT5161LRS","I142": #LOCATION = "U6016" !CDS_LOCATION = "U6016" &SEC = "11" #&CDS_SEC = "11";
"B_PETN8":   PN = "CK10"  !CDS_PN = "CK10";
"B_PETN9":   PN = "CU10"  !CDS_PN = "CU10";
"B_PETN10":   PN = "DD10"  !CDS_PN = "DD10";
"B_PETN11":   PN = "DL10"  !CDS_PN = "DL10";
"B_PETN12":   PN = "DV10"  !CDS_PN = "DV10";
"B_PETN13":   PN = "EE10"  !CDS_PN = "EE10";
"B_PETN14":   PN = "EM10"  !CDS_PN = "EM10";
"B_PETN15":   PN = "EW10"  !CDS_PN = "EW10";
"B_PETP8":   PN = "CH7"  !CDS_PN = "CH7";
"B_PETP9":   PN = "CR7"  !CDS_PN = "CR7";
"B_PETP10":   PN = "DB7"  !CDS_PN = "DB7";
"B_PETP11":   PN = "DJ7"  !CDS_PN = "DJ7";
"B_PETP12":   PN = "DT7"  !CDS_PN = "DT7";
"B_PETP13":   PN = "EC7"  !CDS_PN = "EC7";
"B_PETP14":   PN = "EK7"  !CDS_PN = "EK7";
"B_PETP15":   PN = "EU7"  !CDS_PN = "EU7";
DRAWING = "@t6g_mb_lib.t6g(sch_1):page458";
BODY = "PT5161LRS","I1": #LOCATION = "U6017" !CDS_LOCATION = "U6017" &SEC = "8" #&CDS_SEC = "8";
"B_PERN0":   PN = "R35"  !CDS_PN = "R35";
"B_PERN1":   PN = "AB35"  !CDS_PN = "AB35";
"B_PERN2":   PN = "AJ35"  !CDS_PN = "AJ35";
"B_PERN3":   PN = "AT35"  !CDS_PN = "AT35";
"B_PERN4":   PN = "BC35"  !CDS_PN = "BC35";
"B_PERN5":   PN = "BK35"  !CDS_PN = "BK35";
"B_PERN6":   PN = "BU35"  !CDS_PN = "BU35";
"B_PERN7":   PN = "CD35"  !CDS_PN = "CD35";
"B_PERP0":   PN = "N34"  !CDS_PN = "N34";
"B_PERP1":   PN = "Y34"  !CDS_PN = "Y34";
"B_PERP2":   PN = "AG34"  !CDS_PN = "AG34";
"B_PERP3":   PN = "AP34"  !CDS_PN = "AP34";
"B_PERP4":   PN = "BA34"  !CDS_PN = "BA34";
"B_PERP5":   PN = "BH34"  !CDS_PN = "BH34";
"B_PERP6":   PN = "BR34"  !CDS_PN = "BR34";
"B_PERP7":   PN = "CB34"  !CDS_PN = "CB34";
BODY = "PT5161LRS","I38": #LOCATION = "U6017" !CDS_LOCATION = "U6017" &SEC = "9" #&CDS_SEC = "9";
"B_PERN8":   PN = "CL35"  !CDS_PN = "CL35";
"B_PERN9":   PN = "CV35"  !CDS_PN = "CV35";
"B_PERN10":   PN = "DE35"  !CDS_PN = "DE35";
"B_PERN11":   PN = "DM35"  !CDS_PN = "DM35";
"B_PERN12":   PN = "DW35"  !CDS_PN = "DW35";
"B_PERN13":   PN = "EF35"  !CDS_PN = "EF35";
"B_PERN14":   PN = "EN35"  !CDS_PN = "EN35";
"B_PERN15":   PN = "EY35"  !CDS_PN = "EY35";
"B_PERP8":   PN = "CJ34"  !CDS_PN = "CJ34";
"B_PERP9":   PN = "CT34"  !CDS_PN = "CT34";
"B_PERP10":   PN = "DC34"  !CDS_PN = "DC34";
"B_PERP11":   PN = "DK34"  !CDS_PN = "DK34";
"B_PERP12":   PN = "DU34"  !CDS_PN = "DU34";
"B_PERP13":   PN = "ED34"  !CDS_PN = "ED34";
"B_PERP14":   PN = "EL34"  !CDS_PN = "EL34";
"B_PERP15":   PN = "EV34"  !CDS_PN = "EV34";
DRAWING = "@t6g_mb_lib.t6g(sch_1):page459";
BODY = "PT5161LRS","I1": #LOCATION = "U6017" !CDS_LOCATION = "U6017" &SEC = "6" #&CDS_SEC = "6";
"A_PETN0":   PN = "P29"  !CDS_PN = "P29";
"A_PETN1":   PN = "AA29"  !CDS_PN = "AA29";
"A_PETN2":   PN = "AH29"  !CDS_PN = "AH29";
"A_PETN3":   PN = "AR29"  !CDS_PN = "AR29";
"A_PETN4":   PN = "BB29"  !CDS_PN = "BB29";
"A_PETN5":   PN = "BJ29"  !CDS_PN = "BJ29";
"A_PETN6":   PN = "BT29"  !CDS_PN = "BT29";
"A_PETN7":   PN = "CC29"  !CDS_PN = "CC29";
"A_PETP0":   PN = "M26"  !CDS_PN = "M26";
"A_PETP1":   PN = "W26"  !CDS_PN = "W26";
"A_PETP2":   PN = "AF26"  !CDS_PN = "AF26";
"A_PETP3":   PN = "AN26"  !CDS_PN = "AN26";
"A_PETP4":   PN = "AY26"  !CDS_PN = "AY26";
"A_PETP5":   PN = "BG26"  !CDS_PN = "BG26";
"A_PETP6":   PN = "BP26"  !CDS_PN = "BP26";
"A_PETP7":   PN = "CA26"  !CDS_PN = "CA26";
BODY = "PT5161LRS","I38": #LOCATION = "U6017" !CDS_LOCATION = "U6017" &SEC = "7" #&CDS_SEC = "7";
"A_PETN8":   PN = "CK29"  !CDS_PN = "CK29";
"A_PETN9":   PN = "CU29"  !CDS_PN = "CU29";
"A_PETN10":   PN = "DD29"  !CDS_PN = "DD29";
"A_PETN11":   PN = "DL29"  !CDS_PN = "DL29";
"A_PETN12":   PN = "DV29"  !CDS_PN = "DV29";
"A_PETN13":   PN = "EE29"  !CDS_PN = "EE29";
"A_PETN14":   PN = "EM29"  !CDS_PN = "EM29";
"A_PETN15":   PN = "EW29"  !CDS_PN = "EW29";
"A_PETP8":   PN = "CH26"  !CDS_PN = "CH26";
"A_PETP9":   PN = "CR26"  !CDS_PN = "CR26";
"A_PETP10":   PN = "DB26"  !CDS_PN = "DB26";
"A_PETP11":   PN = "DJ26"  !CDS_PN = "DJ26";
"A_PETP12":   PN = "DT26"  !CDS_PN = "DT26";
"A_PETP13":   PN = "EC26"  !CDS_PN = "EC26";
"A_PETP14":   PN = "EK26"  !CDS_PN = "EK26";
"A_PETP15":   PN = "EU26"  !CDS_PN = "EU26";
DRAWING = "@t6g_mb_lib.t6g(sch_1):page460";
BODY = "PT5161LRS","I1": #LOCATION = "U6017" !CDS_LOCATION = "U6017" &SEC = "1" #&CDS_SEC = "1";
"A_PERN0":   PN = "N2"  !CDS_PN = "N2";
"A_PERN1":   PN = "Y2"  !CDS_PN = "Y2";
"A_PERN2":   PN = "AG2"  !CDS_PN = "AG2";
"A_PERN3":   PN = "AP2"  !CDS_PN = "AP2";
"A_PERN4":   PN = "BA2"  !CDS_PN = "BA2";
"A_PERN5":   PN = "BH2"  !CDS_PN = "BH2";
"A_PERN6":   PN = "BR2"  !CDS_PN = "BR2";
"A_PERN7":   PN = "CB2"  !CDS_PN = "CB2";
"A_PERP0":   PN = "R1"  !CDS_PN = "R1";
"A_PERP1":   PN = "AB1"  !CDS_PN = "AB1";
"A_PERP2":   PN = "AJ1"  !CDS_PN = "AJ1";
"A_PERP3":   PN = "AT1"  !CDS_PN = "AT1";
"A_PERP4":   PN = "BC1"  !CDS_PN = "BC1";
"A_PERP5":   PN = "BK1"  !CDS_PN = "BK1";
"A_PERP6":   PN = "BU1"  !CDS_PN = "BU1";
"A_PERP7":   PN = "CD1"  !CDS_PN = "CD1";
BODY = "PT5161LRS","I38": #LOCATION = "U6017" !CDS_LOCATION = "U6017" &SEC = "2" #&CDS_SEC = "2";
"A_PERN8":   PN = "CJ2"  !CDS_PN = "CJ2";
"A_PERN9":   PN = "CT2"  !CDS_PN = "CT2";
"A_PERN10":   PN = "DC2"  !CDS_PN = "DC2";
"A_PERN11":   PN = "DK2"  !CDS_PN = "DK2";
"A_PERN12":   PN = "DU2"  !CDS_PN = "DU2";
"A_PERN13":   PN = "ED2"  !CDS_PN = "ED2";
"A_PERN14":   PN = "EL2"  !CDS_PN = "EL2";
"A_PERN15":   PN = "EV2"  !CDS_PN = "EV2";
"A_PERP8":   PN = "CL1"  !CDS_PN = "CL1";
"A_PERP9":   PN = "CV1"  !CDS_PN = "CV1";
"A_PERP10":   PN = "DE1"  !CDS_PN = "DE1";
"A_PERP11":   PN = "DM1"  !CDS_PN = "DM1";
"A_PERP12":   PN = "DW1"  !CDS_PN = "DW1";
"A_PERP13":   PN = "EF1"  !CDS_PN = "EF1";
"A_PERP14":   PN = "EN1"  !CDS_PN = "EN1";
"A_PERP15":   PN = "EY1"  !CDS_PN = "EY1";
DRAWING = "@t6g_mb_lib.t6g(sch_1):page461";
BODY = "Q_CAP_DIFFBUS","I16": #LOCATION = "C6738" !CDS_LOCATION = "C6738" &SEC = "1" #&CDS_SEC = "1";
"1":   PN = "1"  !CDS_PN = "1";
"2":   PN = "2"  !CDS_PN = "2";
BODY = "Q_CAP_DIFFBUS","I17": #LOCATION = "C6739" !CDS_LOCATION = "C6739" &SEC = "1" #&CDS_SEC = "1";
"1":   PN = "1"  !CDS_PN = "1";
"2":   PN = "2"  !CDS_PN = "2";
BODY = "Q_CAP_DIFFBUS","I18": #LOCATION = "C6740" !CDS_LOCATION = "C6740" &SEC = "1" #&CDS_SEC = "1";
"1":   PN = "1"  !CDS_PN = "1";
"2":   PN = "2"  !CDS_PN = "2";
BODY = "Q_CAP_DIFFBUS","I22": #LOCATION = "C6737" !CDS_LOCATION = "C6737" &SEC = "1" #&CDS_SEC = "1";
"1":   PN = "1"  !CDS_PN = "1";
"2":   PN = "2"  !CDS_PN = "2";
BODY = "Q_CAP_DIFFBUS","I23": #LOCATION = "C6736" !CDS_LOCATION = "C6736" &SEC = "1" #&CDS_SEC = "1";
"1":   PN = "1"  !CDS_PN = "1";
"2":   PN = "2"  !CDS_PN = "2";
BODY = "Q_CAP_DIFFBUS","I24": #LOCATION = "C6735" !CDS_LOCATION = "C6735" &SEC = "1" #&CDS_SEC = "1";
"1":   PN = "1"  !CDS_PN = "1";
"2":   PN = "2"  !CDS_PN = "2";
BODY = "Q_CAP_DIFFBUS","I25": #LOCATION = "C6734" !CDS_LOCATION = "C6734" &SEC = "1" #&CDS_SEC = "1";
"1":   PN = "1"  !CDS_PN = "1";
"2":   PN = "2"  !CDS_PN = "2";
BODY = "Q_CAP_DIFFBUS","I26": #LOCATION = "C6733" !CDS_LOCATION = "C6733" &SEC = "1" #&CDS_SEC = "1";
"1":   PN = "1"  !CDS_PN = "1";
"2":   PN = "2"  !CDS_PN = "2";
BODY = "Q_CAP_DIFFBUS","I27": #LOCATION = "C6731" !CDS_LOCATION = "C6731" &SEC = "1" #&CDS_SEC = "1";
"1":   PN = "1"  !CDS_PN = "1";
"2":   PN = "2"  !CDS_PN = "2";
BODY = "Q_CAP_DIFFBUS","I28": #LOCATION = "C6732" !CDS_LOCATION = "C6732" &SEC = "1" #&CDS_SEC = "1";
"1":   PN = "1"  !CDS_PN = "1";
"2":   PN = "2"  !CDS_PN = "2";
BODY = "Q_CAP_DIFFBUS","I29": #LOCATION = "C6730" !CDS_LOCATION = "C6730" &SEC = "1" #&CDS_SEC = "1";
"1":   PN = "1"  !CDS_PN = "1";
"2":   PN = "2"  !CDS_PN = "2";
BODY = "Q_CAP_DIFFBUS","I30": #LOCATION = "C6728" !CDS_LOCATION = "C6728" &SEC = "1" #&CDS_SEC = "1";
"1":   PN = "1"  !CDS_PN = "1";
"2":   PN = "2"  !CDS_PN = "2";
BODY = "Q_CAP_DIFFBUS","I31": #LOCATION = "C6729" !CDS_LOCATION = "C6729" &SEC = "1" #&CDS_SEC = "1";
"1":   PN = "1"  !CDS_PN = "1";
"2":   PN = "2"  !CDS_PN = "2";
BODY = "Q_CAP_DIFFBUS","I32": #LOCATION = "C6727" !CDS_LOCATION = "C6727" &SEC = "1" #&CDS_SEC = "1";
"1":   PN = "1"  !CDS_PN = "1";
"2":   PN = "2"  !CDS_PN = "2";
BODY = "PT5161LRS","I46": #LOCATION = "U6017" !CDS_LOCATION = "U6017" &SEC = "10" #&CDS_SEC = "10";
"B_PETN0":   PN = "P10"  !CDS_PN = "P10";
"B_PETN1":   PN = "AA10"  !CDS_PN = "AA10";
"B_PETN2":   PN = "AH10"  !CDS_PN = "AH10";
"B_PETN3":   PN = "AR10"  !CDS_PN = "AR10";
"B_PETN4":   PN = "BB10"  !CDS_PN = "BB10";
"B_PETN5":   PN = "BJ10"  !CDS_PN = "BJ10";
"B_PETN6":   PN = "BT10"  !CDS_PN = "BT10";
"B_PETN7":   PN = "CC10"  !CDS_PN = "CC10";
"B_PETP0":   PN = "M7"  !CDS_PN = "M7";
"B_PETP1":   PN = "W7"  !CDS_PN = "W7";
"B_PETP2":   PN = "AF7"  !CDS_PN = "AF7";
"B_PETP3":   PN = "AN7"  !CDS_PN = "AN7";
"B_PETP4":   PN = "AY7"  !CDS_PN = "AY7";
"B_PETP5":   PN = "BG7"  !CDS_PN = "BG7";
"B_PETP6":   PN = "BP7"  !CDS_PN = "BP7";
"B_PETP7":   PN = "CA7"  !CDS_PN = "CA7";
BODY = "Q_CAP_DIFFBUS","I47": #LOCATION = "C6726" !CDS_LOCATION = "C6726" &SEC = "1" #&CDS_SEC = "1";
"1":   PN = "1"  !CDS_PN = "1";
"2":   PN = "2"  !CDS_PN = "2";
BODY = "Q_CAP_DIFFBUS","I48": #LOCATION = "C6725" !CDS_LOCATION = "C6725" &SEC = "1" #&CDS_SEC = "1";
"1":   PN = "1"  !CDS_PN = "1";
"2":   PN = "2"  !CDS_PN = "2";
BODY = "Q_CAP_DIFFBUS","I88": #LOCATION = "C6756" !CDS_LOCATION = "C6756" &SEC = "1" #&CDS_SEC = "1";
"1":   PN = "1"  !CDS_PN = "1";
"2":   PN = "2"  !CDS_PN = "2";
BODY = "Q_CAP_DIFFBUS","I89": #LOCATION = "C6755" !CDS_LOCATION = "C6755" &SEC = "1" #&CDS_SEC = "1";
"1":   PN = "1"  !CDS_PN = "1";
"2":   PN = "2"  !CDS_PN = "2";
BODY = "Q_CAP_DIFFBUS","I90": #LOCATION = "C6754" !CDS_LOCATION = "C6754" &SEC = "1" #&CDS_SEC = "1";
"1":   PN = "1"  !CDS_PN = "1";
"2":   PN = "2"  !CDS_PN = "2";
BODY = "Q_CAP_DIFFBUS","I91": #LOCATION = "C6753" !CDS_LOCATION = "C6753" &SEC = "1" #&CDS_SEC = "1";
"1":   PN = "1"  !CDS_PN = "1";
"2":   PN = "2"  !CDS_PN = "2";
BODY = "Q_CAP_DIFFBUS","I92": #LOCATION = "C6752" !CDS_LOCATION = "C6752" &SEC = "1" #&CDS_SEC = "1";
"1":   PN = "1"  !CDS_PN = "1";
"2":   PN = "2"  !CDS_PN = "2";
BODY = "Q_CAP_DIFFBUS","I93": #LOCATION = "C6751" !CDS_LOCATION = "C6751" &SEC = "1" #&CDS_SEC = "1";
"1":   PN = "1"  !CDS_PN = "1";
"2":   PN = "2"  !CDS_PN = "2";
BODY = "Q_CAP_DIFFBUS","I94": #LOCATION = "C6750" !CDS_LOCATION = "C6750" &SEC = "1" #&CDS_SEC = "1";
"1":   PN = "1"  !CDS_PN = "1";
"2":   PN = "2"  !CDS_PN = "2";
BODY = "Q_CAP_DIFFBUS","I95": #LOCATION = "C6749" !CDS_LOCATION = "C6749" &SEC = "1" #&CDS_SEC = "1";
"1":   PN = "1"  !CDS_PN = "1";
"2":   PN = "2"  !CDS_PN = "2";
BODY = "Q_CAP_DIFFBUS","I96": #LOCATION = "C6748" !CDS_LOCATION = "C6748" &SEC = "1" #&CDS_SEC = "1";
"1":   PN = "1"  !CDS_PN = "1";
"2":   PN = "2"  !CDS_PN = "2";
BODY = "Q_CAP_DIFFBUS","I97": #LOCATION = "C6747" !CDS_LOCATION = "C6747" &SEC = "1" #&CDS_SEC = "1";
"1":   PN = "1"  !CDS_PN = "1";
"2":   PN = "2"  !CDS_PN = "2";
BODY = "Q_CAP_DIFFBUS","I98": #LOCATION = "C6746" !CDS_LOCATION = "C6746" &SEC = "1" #&CDS_SEC = "1";
"1":   PN = "1"  !CDS_PN = "1";
"2":   PN = "2"  !CDS_PN = "2";
BODY = "Q_CAP_DIFFBUS","I99": #LOCATION = "C6745" !CDS_LOCATION = "C6745" &SEC = "1" #&CDS_SEC = "1";
"1":   PN = "1"  !CDS_PN = "1";
"2":   PN = "2"  !CDS_PN = "2";
BODY = "Q_CAP_DIFFBUS","I100": #LOCATION = "C6744" !CDS_LOCATION = "C6744" &SEC = "1" #&CDS_SEC = "1";
"1":   PN = "1"  !CDS_PN = "1";
"2":   PN = "2"  !CDS_PN = "2";
BODY = "Q_CAP_DIFFBUS","I101": #LOCATION = "C6743" !CDS_LOCATION = "C6743" &SEC = "1" #&CDS_SEC = "1";
"1":   PN = "1"  !CDS_PN = "1";
"2":   PN = "2"  !CDS_PN = "2";
BODY = "Q_CAP_DIFFBUS","I104": #LOCATION = "C6742" !CDS_LOCATION = "C6742" &SEC = "1" #&CDS_SEC = "1";
"1":   PN = "1"  !CDS_PN = "1";
"2":   PN = "2"  !CDS_PN = "2";
BODY = "Q_CAP_DIFFBUS","I105": #LOCATION = "C6741" !CDS_LOCATION = "C6741" &SEC = "1" #&CDS_SEC = "1";
"1":   PN = "1"  !CDS_PN = "1";
"2":   PN = "2"  !CDS_PN = "2";
BODY = "PT5161LRS","I142": #LOCATION = "U6017" !CDS_LOCATION = "U6017" &SEC = "11" #&CDS_SEC = "11";
"B_PETN8":   PN = "CK10"  !CDS_PN = "CK10";
"B_PETN9":   PN = "CU10"  !CDS_PN = "CU10";
"B_PETN10":   PN = "DD10"  !CDS_PN = "DD10";
"B_PETN11":   PN = "DL10"  !CDS_PN = "DL10";
"B_PETN12":   PN = "DV10"  !CDS_PN = "DV10";
"B_PETN13":   PN = "EE10"  !CDS_PN = "EE10";
"B_PETN14":   PN = "EM10"  !CDS_PN = "EM10";
"B_PETN15":   PN = "EW10"  !CDS_PN = "EW10";
"B_PETP8":   PN = "CH7"  !CDS_PN = "CH7";
"B_PETP9":   PN = "CR7"  !CDS_PN = "CR7";
"B_PETP10":   PN = "DB7"  !CDS_PN = "DB7";
"B_PETP11":   PN = "DJ7"  !CDS_PN = "DJ7";
"B_PETP12":   PN = "DT7"  !CDS_PN = "DT7";
"B_PETP13":   PN = "EC7"  !CDS_PN = "EC7";
"B_PETP14":   PN = "EK7"  !CDS_PN = "EK7";
"B_PETP15":   PN = "EU7"  !CDS_PN = "EU7";
DRAWING = "@t6g_mb_lib.t6g(sch_1):page160";
BODY = "Q_RES","I2": #LOCATION = "R4490" !CDS_LOCATION = "R4490" &SEC = "1" #&CDS_SEC = "1";
"A":   PN = "1"  !CDS_PN = "1";
"B":   PN = "2"  !CDS_PN = "2";
BODY = "Q_RES","I3": #LOCATION = "R4489" !CDS_LOCATION = "R4489" &SEC = "1" #&CDS_SEC = "1";
"A":   PN = "1"  !CDS_PN = "1";
"B":   PN = "2"  !CDS_PN = "2";
BODY = "Q_RES","I6": #LOCATION = "R4475" !CDS_LOCATION = "R4475" #SEC = "1" !CDS_SEC = "1";
"A":   PN = "1"  !CDS_PN = "1";
"B":   PN = "2"  !CDS_PN = "2";
BODY = "Q_CAP","I18": #LOCATION = "C78" !CDS_LOCATION = "C78" &SEC = "1" #&CDS_SEC = "1";
"A":   PN = "1"  !CDS_PN = "1";
"B":   PN = "2"  !CDS_PN = "2";
BODY = "Q_CAP","I20": #LOCATION = "C2334" !CDS_LOCATION = "C2334" &SEC = "1" #&CDS_SEC = "1";
"A":   PN = "1"  !CDS_PN = "1";
"B":   PN = "2"  !CDS_PN = "2";
BODY = "Q_INDUCTOR","I24": #LOCATION = "L20" !CDS_LOCATION = "L20" &SEC = "1" #&CDS_SEC = "1";
"1":   PN = "1"  !CDS_PN = "1";
"2":   PN = "2"  !CDS_PN = "2";
BODY = "Q_INDUCTOR","I26": #LOCATION = "L19" !CDS_LOCATION = "L19" &SEC = "1" #&CDS_SEC = "1";
"1":   PN = "1"  !CDS_PN = "1";
"2":   PN = "2"  !CDS_PN = "2";
BODY = "Q_RES","I27": #LOCATION = "R4493" !CDS_LOCATION = "R4493" #SEC = "1" !CDS_SEC = "1";
"A":   PN = "1"  !CDS_PN = "1";
"B":   PN = "2"  !CDS_PN = "2";
BODY = "Q_RES","I29": #LOCATION = "R4492" !CDS_LOCATION = "R4492" &SEC = "1" #&CDS_SEC = "1";
"A":   PN = "1"  !CDS_PN = "1";
"B":   PN = "2"  !CDS_PN = "2";
BODY = "Q_RES","I31": #LOCATION = "R4491" !CDS_LOCATION = "R4491" &SEC = "1" #&CDS_SEC = "1";
"A":   PN = "1"  !CDS_PN = "1";
"B":   PN = "2"  !CDS_PN = "2";
BODY = "Q_CAP","I40": #LOCATION = "C2329" !CDS_LOCATION = "C2329" &SEC = "1" #&CDS_SEC = "1";
"A":   PN = "1"  !CDS_PN = "1";
"B":   PN = "2"  !CDS_PN = "2";
BODY = "Q_CAP","I41": #LOCATION = "C79" !CDS_LOCATION = "C79" &SEC = "1" #&CDS_SEC = "1";
"A":   PN = "1"  !CDS_PN = "1";
"B":   PN = "2"  !CDS_PN = "2";
BODY = "Q_CAP","I44": #LOCATION = "C80" !CDS_LOCATION = "C80" &SEC = "1" #&CDS_SEC = "1";
"A":   PN = "1"  !CDS_PN = "1";
"B":   PN = "2"  !CDS_PN = "2";
BODY = "Q_CAP","I45": #LOCATION = "C81" !CDS_LOCATION = "C81" &SEC = "1" #&CDS_SEC = "1";
"A":   PN = "1"  !CDS_PN = "1";
"B":   PN = "2"  !CDS_PN = "2";
BODY = "Q_CAP","I47": #LOCATION = "C2339" !CDS_LOCATION = "C2339" &SEC = "1" #&CDS_SEC = "1";
"A":   PN = "1"  !CDS_PN = "1";
"B":   PN = "2"  !CDS_PN = "2";
BODY = "Q_RES","I52": #LOCATION = "R4518" !CDS_LOCATION = "R4518" &SEC = "1" #&CDS_SEC = "1";
"A":   PN = "1"  !CDS_PN = "1";
"B":   PN = "2"  !CDS_PN = "2";
BODY = "Q_RES","I53": #LOCATION = "R4519" !CDS_LOCATION = "R4519" &SEC = "1" #&CDS_SEC = "1";
"A":   PN = "1"  !CDS_PN = "1";
"B":   PN = "2"  !CDS_PN = "2";
BODY = "Q_RES","I55": #LOCATION = "R4520" !CDS_LOCATION = "R4520" &SEC = "1" #&CDS_SEC = "1";
"A":   PN = "1"  !CDS_PN = "1";
"B":   PN = "2"  !CDS_PN = "2";
BODY = "9ZXL0451EKILFT","I63": #LOCATION = "U314" !CDS_LOCATION = "U314" &SEC = "1" #&CDS_SEC = "1";
"^CKPWRGD_PD#":   PN = "1"  !CDS_PN = "1";
"^HIBW_BYPM_LOBW#":   PN = "32"  !CDS_PN = "32";
"DIF0":   PN = "13"  !CDS_PN = "13";
"DIF0#":   PN = "14"  !CDS_PN = "14";
"DIF1":   PN = "19"  !CDS_PN = "19";
"DIF1#":   PN = "20"  !CDS_PN = "20";
"DIF2":   PN = "22"  !CDS_PN = "22";
"DIF2#":   PN = "23"  !CDS_PN = "23";
"DIF3":   PN = "27"  !CDS_PN = "27";
"DIF3#":   PN = "28"  !CDS_PN = "28";
"DIF_IN":   PN = "3"  !CDS_PN = "3";
"DIF_IN#":   PN = "4"  !CDS_PN = "4";
"EPAD_GND":   PN = "33"  !CDS_PN = "33";
"FBOUT_NC":   PN = "9"  !CDS_PN = "9";
"FBOUT_NC#":   PN = "8"  !CDS_PN = "8";
"NC0":   PN = "10"  !CDS_PN = "10";
"NC1":   PN = "11"  !CDS_PN = "11";
"NC2":   PN = "17"  !CDS_PN = "17";
"NC3":   PN = "30"  !CDS_PN = "30";
"SMBCLK":   PN = "7"  !CDS_PN = "7";
"SMBDAT":   PN = "6"  !CDS_PN = "6";
"VDD0":   PN = "12"  !CDS_PN = "12";
"VDD1":   PN = "16"  !CDS_PN = "16";
"VDD2":   PN = "21"  !CDS_PN = "21";
"VDD3":   PN = "25"  !CDS_PN = "25";
"VDD4":   PN = "29"  !CDS_PN = "29";
"VDDA":   PN = "31"  !CDS_PN = "31";
"VDDR":   PN = "2"  !CDS_PN = "2";
"VOE0#":   PN = "15"  !CDS_PN = "15";
"VOE1#":   PN = "18"  !CDS_PN = "18";
"VOE2#":   PN = "24"  !CDS_PN = "24";
"VOE3#":   PN = "26"  !CDS_PN = "26";
"VSADR0_TRI":   PN = "5"  !CDS_PN = "5";
BODY = "Q_RES","I68": #LOCATION = "R6802" !CDS_LOCATION = "R6802" &SEC = "1" #&CDS_SEC = "1";
"A":   PN = "1"  !CDS_PN = "1";
"B":   PN = "2"  !CDS_PN = "2";
BODY = "Q_CAP","I69": #LOCATION = "C76" !CDS_LOCATION = "C76" &SEC = "1" #&CDS_SEC = "1";
"A":   PN = "1"  !CDS_PN = "1";
"B":   PN = "2"  !CDS_PN = "2";
BODY = "Q_CAP","I70": #LOCATION = "C77" !CDS_LOCATION = "C77" &SEC = "1" #&CDS_SEC = "1";
"A":   PN = "1"  !CDS_PN = "1";
"B":   PN = "2"  !CDS_PN = "2";
BODY = "Q_CAP","I71": #LOCATION = "C2328" !CDS_LOCATION = "C2328" &SEC = "1" #&CDS_SEC = "1";
"A":   PN = "1"  !CDS_PN = "1";
"B":   PN = "2"  !CDS_PN = "2";
BODY = "Q_RES","I73": #LOCATION = "R4476" !CDS_LOCATION = "R4476" &SEC = "1" #&CDS_SEC = "1";
"A":   PN = "1"  !CDS_PN = "1";
"B":   PN = "2"  !CDS_PN = "2";
DRAWING = "@t6g_mb_lib.t6g(sch_1):page379";
BODY = "Q_INDUCTOR","I2": #LOCATION = "L1" !CDS_LOCATION = "L1" &SEC = "1" #&CDS_SEC = "1";
"1":   PN = "1"  !CDS_PN = "1";
"2":   PN = "2"  !CDS_PN = "2";
BODY = "Q_RES","I15": #LOCATION = "R585" !CDS_LOCATION = "R585" &SEC = "1" #&CDS_SEC = "1";
"A":   PN = "1"  !CDS_PN = "1";
"B":   PN = "2"  !CDS_PN = "2";
BODY = "Q_RES","I17": #LOCATION = "R580" !CDS_LOCATION = "R580" &SEC = "1" #&CDS_SEC = "1";
"A":   PN = "1"  !CDS_PN = "1";
"B":   PN = "2"  !CDS_PN = "2";
BODY = "Q_RES","I20": #LOCATION = "R555" !CDS_LOCATION = "R555" &SEC = "1" #&CDS_SEC = "1";
"A":   PN = "1"  !CDS_PN = "1";
"B":   PN = "2"  !CDS_PN = "2";
BODY = "Q_RES","I21": #LOCATION = "R586" !CDS_LOCATION = "R586" &SEC = "1" #&CDS_SEC = "1";
"A":   PN = "1"  !CDS_PN = "1";
"B":   PN = "2"  !CDS_PN = "2";
BODY = "Q_CAP","I24": #LOCATION = "C68" !CDS_LOCATION = "C68" &SEC = "1" #&CDS_SEC = "1";
"A":   PN = "1"  !CDS_PN = "1";
"B":   PN = "2"  !CDS_PN = "2";
BODY = "Q_CAP","I26": #LOCATION = "C84" !CDS_LOCATION = "C84" &SEC = "1" #&CDS_SEC = "1";
"A":   PN = "1"  !CDS_PN = "1";
"B":   PN = "2"  !CDS_PN = "2";
BODY = "Q_INDUCTOR","I32": #LOCATION = "L2" !CDS_LOCATION = "L2" &SEC = "1" #&CDS_SEC = "1";
"1":   PN = "1"  !CDS_PN = "1";
"2":   PN = "2"  !CDS_PN = "2";
BODY = "Q_CAP","I34": #LOCATION = "C58" !CDS_LOCATION = "C58" &SEC = "1" #&CDS_SEC = "1";
"A":   PN = "1"  !CDS_PN = "1";
"B":   PN = "2"  !CDS_PN = "2";
BODY = "Q_CAP","I35": #LOCATION = "C90" !CDS_LOCATION = "C90" &SEC = "1" #&CDS_SEC = "1";
"A":   PN = "1"  !CDS_PN = "1";
"B":   PN = "2"  !CDS_PN = "2";
BODY = "Q_CAP","I36": #LOCATION = "C98" !CDS_LOCATION = "C98" &SEC = "1" #&CDS_SEC = "1";
"A":   PN = "1"  !CDS_PN = "1";
"B":   PN = "2"  !CDS_PN = "2";
BODY = "Q_RES","I49": #LOCATION = "R592" !CDS_LOCATION = "R592" &SEC = "1" #&CDS_SEC = "1";
"A":   PN = "1"  !CDS_PN = "1";
"B":   PN = "2"  !CDS_PN = "2";
BODY = "Q_RES","I50": #LOCATION = "R593" !CDS_LOCATION = "R593" &SEC = "1" #&CDS_SEC = "1";
"A":   PN = "1"  !CDS_PN = "1";
"B":   PN = "2"  !CDS_PN = "2";
BODY = "Q_RES","I51": #LOCATION = "R594" !CDS_LOCATION = "R594" &SEC = "1" #&CDS_SEC = "1";
"A":   PN = "1"  !CDS_PN = "1";
"B":   PN = "2"  !CDS_PN = "2";
BODY = "Q_CAP","I58": #LOCATION = "C99" !CDS_LOCATION = "C99" &SEC = "1" #&CDS_SEC = "1";
"A":   PN = "1"  !CDS_PN = "1";
"B":   PN = "2"  !CDS_PN = "2";
BODY = "Q_CAP","I60": #LOCATION = "C75" !CDS_LOCATION = "C75" &SEC = "1" #&CDS_SEC = "1";
"A":   PN = "1"  !CDS_PN = "1";
"B":   PN = "2"  !CDS_PN = "2";
BODY = "9ZXL0451EKILFT","I63": #LOCATION = "U10" !CDS_LOCATION = "U10" &SEC = "1" #&CDS_SEC = "1";
"^CKPWRGD_PD#":   PN = "1"  !CDS_PN = "1";
"^HIBW_BYPM_LOBW#":   PN = "32"  !CDS_PN = "32";
"DIF0":   PN = "13"  !CDS_PN = "13";
"DIF0#":   PN = "14"  !CDS_PN = "14";
"DIF1":   PN = "19"  !CDS_PN = "19";
"DIF1#":   PN = "20"  !CDS_PN = "20";
"DIF2":   PN = "22"  !CDS_PN = "22";
"DIF2#":   PN = "23"  !CDS_PN = "23";
"DIF3":   PN = "27"  !CDS_PN = "27";
"DIF3#":   PN = "28"  !CDS_PN = "28";
"DIF_IN":   PN = "3"  !CDS_PN = "3";
"DIF_IN#":   PN = "4"  !CDS_PN = "4";
"EPAD_GND":   PN = "33"  !CDS_PN = "33";
"FBOUT_NC":   PN = "9"  !CDS_PN = "9";
"FBOUT_NC#":   PN = "8"  !CDS_PN = "8";
"NC0":   PN = "10"  !CDS_PN = "10";
"NC1":   PN = "11"  !CDS_PN = "11";
"NC2":   PN = "17"  !CDS_PN = "17";
"NC3":   PN = "30"  !CDS_PN = "30";
"SMBCLK":   PN = "7"  !CDS_PN = "7";
"SMBDAT":   PN = "6"  !CDS_PN = "6";
"VDD0":   PN = "12"  !CDS_PN = "12";
"VDD1":   PN = "16"  !CDS_PN = "16";
"VDD2":   PN = "21"  !CDS_PN = "21";
"VDD3":   PN = "25"  !CDS_PN = "25";
"VDD4":   PN = "29"  !CDS_PN = "29";
"VDDA":   PN = "31"  !CDS_PN = "31";
"VDDR":   PN = "2"  !CDS_PN = "2";
"VOE0#":   PN = "15"  !CDS_PN = "15";
"VOE1#":   PN = "18"  !CDS_PN = "18";
"VOE2#":   PN = "24"  !CDS_PN = "24";
"VOE3#":   PN = "26"  !CDS_PN = "26";
"VSADR0_TRI":   PN = "5"  !CDS_PN = "5";
BODY = "Q_RES","I64": #LOCATION = "R579" !CDS_LOCATION = "R579" &SEC = "1" #&CDS_SEC = "1";
"A":   PN = "1"  !CDS_PN = "1";
"B":   PN = "2"  !CDS_PN = "2";
BODY = "Q_RES","I65": #LOCATION = "R578" !CDS_LOCATION = "R578" &SEC = "1" #&CDS_SEC = "1";
"A":   PN = "1"  !CDS_PN = "1";
"B":   PN = "2"  !CDS_PN = "2";
BODY = "Q_RES","I76": #LOCATION = "R6803" !CDS_LOCATION = "R6803" &SEC = "1" #&CDS_SEC = "1";
"A":   PN = "1"  !CDS_PN = "1";
"B":   PN = "2"  !CDS_PN = "2";
BODY = "Q_CAP","I77": #LOCATION = "C82" !CDS_LOCATION = "C82" &SEC = "1" #&CDS_SEC = "1";
"A":   PN = "1"  !CDS_PN = "1";
"B":   PN = "2"  !CDS_PN = "2";
BODY = "Q_CAP","I78": #LOCATION = "C83" !CDS_LOCATION = "C83" &SEC = "1" #&CDS_SEC = "1";
"A":   PN = "1"  !CDS_PN = "1";
"B":   PN = "2"  !CDS_PN = "2";
BODY = "Q_CAP","I79": #LOCATION = "C28" !CDS_LOCATION = "C28" &SEC = "1" #&CDS_SEC = "1";
"A":   PN = "1"  !CDS_PN = "1";
"B":   PN = "2"  !CDS_PN = "2";
BODY = "Q_RES","I81": #LOCATION = "R560" !CDS_LOCATION = "R560" &SEC = "1" #&CDS_SEC = "1";
"A":   PN = "1"  !CDS_PN = "1";
"B":   PN = "2"  !CDS_PN = "2";
DRAWING = "@t6g_mb_lib.t6g(sch_1):page419";
BODY = "Q_RES","I7": #LOCATION = "R1070" !CDS_LOCATION = "R1070" &SEC = "1" #&CDS_SEC = "1";
"A":   PN = "1"  !CDS_PN = "1";
"B":   PN = "2"  !CDS_PN = "2";
BODY = "Q_RES","I9": #LOCATION = "R1074" !CDS_LOCATION = "R1074" &SEC = "1" #&CDS_SEC = "1";
"A":   PN = "1"  !CDS_PN = "1";
"B":   PN = "2"  !CDS_PN = "2";
BODY = "Q_RES","I5": #LOCATION = "R1063" !CDS_LOCATION = "R1063" &SEC = "1" #&CDS_SEC = "1";
"A":   PN = "1"  !CDS_PN = "1";
"B":   PN = "2"  !CDS_PN = "2";
BODY = "Q_RES","I8": #LOCATION = "R1072" !CDS_LOCATION = "R1072" &SEC = "1" #&CDS_SEC = "1";
"A":   PN = "1"  !CDS_PN = "1";
"B":   PN = "2"  !CDS_PN = "2";
BODY = "Q_RES","I10": #LOCATION = "R1069" !CDS_LOCATION = "R1069" &SEC = "1" #&CDS_SEC = "1";
"A":   PN = "1"  !CDS_PN = "1";
"B":   PN = "2"  !CDS_PN = "2";
BODY = "Q_RES","I11": #LOCATION = "R1073" !CDS_LOCATION = "R1073" &SEC = "1" #&CDS_SEC = "1";
"A":   PN = "1"  !CDS_PN = "1";
"B":   PN = "2"  !CDS_PN = "2";
BODY = "Q_RES","I17": #LOCATION = "R631" !CDS_LOCATION = "R631" &SEC = "1" #&CDS_SEC = "1";
"A":   PN = "1"  !CDS_PN = "1";
"B":   PN = "2"  !CDS_PN = "2";
BODY = "Q_RES","I18": #LOCATION = "R634" !CDS_LOCATION = "R634" &SEC = "1" #&CDS_SEC = "1";
"A":   PN = "1"  !CDS_PN = "1";
"B":   PN = "2"  !CDS_PN = "2";
BODY = "Q_RES","I19": #LOCATION = "R613" !CDS_LOCATION = "R613" #SEC = "1" !CDS_SEC = "1";
"A":   PN = "1"  !CDS_PN = "1";
"B":   PN = "2"  !CDS_PN = "2";
BODY = "Q_RES","I20": #LOCATION = "R614" !CDS_LOCATION = "R614" #SEC = "1" !CDS_SEC = "1";
"A":   PN = "1"  !CDS_PN = "1";
"B":   PN = "2"  !CDS_PN = "2";
BODY = "Q_RES","I21": #LOCATION = "R681" !CDS_LOCATION = "R681" &SEC = "1" #&CDS_SEC = "1";
"A":   PN = "1"  !CDS_PN = "1";
"B":   PN = "2"  !CDS_PN = "2";
BODY = "Q_RES","I22": #LOCATION = "R680" !CDS_LOCATION = "R680" &SEC = "1" #&CDS_SEC = "1";
"A":   PN = "1"  !CDS_PN = "1";
"B":   PN = "2"  !CDS_PN = "2";
BODY = "Q_RES","I29": #LOCATION = "R1067" !CDS_LOCATION = "R1067" &SEC = "1" #&CDS_SEC = "1";
"A":   PN = "1"  !CDS_PN = "1";
"B":   PN = "2"  !CDS_PN = "2";
BODY = "Q_RES","I30": #LOCATION = "R1068" !CDS_LOCATION = "R1068" &SEC = "1" #&CDS_SEC = "1";
"A":   PN = "1"  !CDS_PN = "1";
"B":   PN = "2"  !CDS_PN = "2";
BODY = "Q_RES","I36": #LOCATION = "R1076" !CDS_LOCATION = "R1076" &SEC = "1" #&CDS_SEC = "1";
"A":   PN = "1"  !CDS_PN = "1";
"B":   PN = "2"  !CDS_PN = "2";
BODY = "Q_RES","I37": #LOCATION = "R1078" !CDS_LOCATION = "R1078" &SEC = "1" #&CDS_SEC = "1";
"A":   PN = "1"  !CDS_PN = "1";
"B":   PN = "2"  !CDS_PN = "2";
BODY = "Q_RES","I39": #LOCATION = "R1079" !CDS_LOCATION = "R1079" &SEC = "1" #&CDS_SEC = "1";
"A":   PN = "1"  !CDS_PN = "1";
"B":   PN = "2"  !CDS_PN = "2";
BODY = "Q_RES","I40": #LOCATION = "R1075" !CDS_LOCATION = "R1075" &SEC = "1" #&CDS_SEC = "1";
"A":   PN = "1"  !CDS_PN = "1";
"B":   PN = "2"  !CDS_PN = "2";
BODY = "Q_RES","I41": #LOCATION = "R1077" !CDS_LOCATION = "R1077" &SEC = "1" #&CDS_SEC = "1";
"A":   PN = "1"  !CDS_PN = "1";
"B":   PN = "2"  !CDS_PN = "2";
BODY = "Q_RES","I42": #LOCATION = "R1066" !CDS_LOCATION = "R1066" &SEC = "1" #&CDS_SEC = "1";
"A":   PN = "1"  !CDS_PN = "1";
"B":   PN = "2"  !CDS_PN = "2";
BODY = "Q_RES","I50": #LOCATION = "R1048" !CDS_LOCATION = "R1048" &SEC = "1" #&CDS_SEC = "1";
"A":   PN = "1"  !CDS_PN = "1";
"B":   PN = "2"  !CDS_PN = "2";
BODY = "Q_RES","I51": #LOCATION = "R1080" !CDS_LOCATION = "R1080" &SEC = "1" #&CDS_SEC = "1";
"A":   PN = "1"  !CDS_PN = "1";
"B":   PN = "2"  !CDS_PN = "2";
BODY = "Q_RES","I55": #LOCATION = "R1054" !CDS_LOCATION = "R1054" &SEC = "1" #&CDS_SEC = "1";
"A":   PN = "1"  !CDS_PN = "1";
"B":   PN = "2"  !CDS_PN = "2";
BODY = "Q_RES","I56": #LOCATION = "R1047" !CDS_LOCATION = "R1047" #SEC = "1" !CDS_SEC = "1";
"A":   PN = "1"  !CDS_PN = "1";
"B":   PN = "2"  !CDS_PN = "2";
BODY = "Q_RES","I65": #LOCATION = "R1056" !CDS_LOCATION = "R1056" &SEC = "1" #&CDS_SEC = "1";
"A":   PN = "1"  !CDS_PN = "1";
"B":   PN = "2"  !CDS_PN = "2";
BODY = "Q_RES","I66": #LOCATION = "R1058" !CDS_LOCATION = "R1058" &SEC = "1" #&CDS_SEC = "1";
"A":   PN = "1"  !CDS_PN = "1";
"B":   PN = "2"  !CDS_PN = "2";
BODY = "Q_RES","I67": #LOCATION = "R1055" !CDS_LOCATION = "R1055" &SEC = "1" #&CDS_SEC = "1";
"A":   PN = "1"  !CDS_PN = "1";
"B":   PN = "2"  !CDS_PN = "2";
BODY = "Q_RES","I68": #LOCATION = "R1057" !CDS_LOCATION = "R1057" &SEC = "1" #&CDS_SEC = "1";
"A":   PN = "1"  !CDS_PN = "1";
"B":   PN = "2"  !CDS_PN = "2";
BODY = "Q_RES","I69": #LOCATION = "R1060" !CDS_LOCATION = "R1060" &SEC = "1" #&CDS_SEC = "1";
"A":   PN = "1"  !CDS_PN = "1";
"B":   PN = "2"  !CDS_PN = "2";
BODY = "Q_RES","I70": #LOCATION = "R1059" !CDS_LOCATION = "R1059" &SEC = "1" #&CDS_SEC = "1";
"A":   PN = "1"  !CDS_PN = "1";
"B":   PN = "2"  !CDS_PN = "2";
BODY = "Q_RES","I76": #LOCATION = "R1062" !CDS_LOCATION = "R1062" &SEC = "1" #&CDS_SEC = "1";
"A":   PN = "1"  !CDS_PN = "1";
"B":   PN = "2"  !CDS_PN = "2";
BODY = "Q_RES","I77": #LOCATION = "R1061" !CDS_LOCATION = "R1061" &SEC = "1" #&CDS_SEC = "1";
"A":   PN = "1"  !CDS_PN = "1";
"B":   PN = "2"  !CDS_PN = "2";
BODY = "Q_RES","I78": #LOCATION = "R1065" !CDS_LOCATION = "R1065" &SEC = "1" #&CDS_SEC = "1";
"A":   PN = "1"  !CDS_PN = "1";
"B":   PN = "2"  !CDS_PN = "2";
BODY = "PT5161LRS","I83": #LOCATION = "U6012" !CDS_LOCATION = "U6012" &SEC = "3" #&CDS_SEC = "3";
"CLKREQ_N":   PN = "G35"  !CDS_PN = "G35";
"EE_CLK":   PN = "FF5"  !CDS_PN = "FF5";
"EE_DAT":   PN = "FJ3"  !CDS_PN = "FJ3";
"GPIO0":   PN = "FJ6"  !CDS_PN = "FJ6";
"GPIO1":   PN = "FJ23"  !CDS_PN = "FJ23";
"GPIO2":   PN = "FJ25"  !CDS_PN = "FJ25";
"GPIO3":   PN = "FJ28"  !CDS_PN = "FJ28";
"INT_N":   PN = "FJ31"  !CDS_PN = "FJ31";
"JTAG_TCK":   PN = "B3"  !CDS_PN = "B3";
"JTAG_TDI":   PN = "B6"  !CDS_PN = "B6";
"JTAG_TDO":   PN = "B9"  !CDS_PN = "B9";
"JTAG_TEST_MODE":   PN = "FF8"  !CDS_PN = "FF8";
"JTAG_TMS":   PN = "B12"  !CDS_PN = "B12";
"JTAG_TRST_N":   PN = "E8"  !CDS_PN = "E8";
"MODE":   PN = "FJ9"  !CDS_PN = "FJ9";
"PERST_N":   PN = "F2"  !CDS_PN = "F2";
"REFCLK_OUTN":   PN = "E18"  !CDS_PN = "E18";
"REFCLK_OUTP":   PN = "B16"  !CDS_PN = "B16";
"REFCLKN":   PN = "FF18"  !CDS_PN = "FF18";
"REFCLKP":   PN = "FJ16"  !CDS_PN = "FJ16";
"RESET_N":   PN = "FF11"  !CDS_PN = "FF11";
"RXDET_BYP":   PN = "E11"  !CDS_PN = "E11";
"SCAN_MODE":   PN = "FF33"  !CDS_PN = "FF33";
"SMB_ADDR1":   PN = "F34"  !CDS_PN = "F34";
"SMB_ADDR2":   PN = "B23"  !CDS_PN = "B23";
"SMB_ADDR3":   PN = "B25"  !CDS_PN = "B25";
"SMBCLK":   PN = "B31"  !CDS_PN = "B31";
"SMBDAT":   PN = "B28"  !CDS_PN = "B28";
"T_SENSE":   PN = "E30"  !CDS_PN = "E30";
"TEST0":   PN = "FF24"  !CDS_PN = "FF24";
"TEST1":   PN = "FF27"  !CDS_PN = "FF27";
"TEST2":   PN = "FF30"  !CDS_PN = "FF30";
BODY = "Q_RES","I84": #LOCATION = "R1400" !CDS_LOCATION = "R1400" &SEC = "1" #&CDS_SEC = "1";
"A":   PN = "1"  !CDS_PN = "1";
"B":   PN = "2"  !CDS_PN = "2";
BODY = "Q_RES","I95": #LOCATION = "R1406" !CDS_LOCATION = "R1406" &SEC = "1" #&CDS_SEC = "1";
"A":   PN = "1"  !CDS_PN = "1";
"B":   PN = "2"  !CDS_PN = "2";
BODY = "Q_RES","I96": #LOCATION = "R1405" !CDS_LOCATION = "R1405" &SEC = "1" #&CDS_SEC = "1";
"A":   PN = "1"  !CDS_PN = "1";
"B":   PN = "2"  !CDS_PN = "2";
BODY = "Q_RES","I99": #LOCATION = "R1404" !CDS_LOCATION = "R1404" &SEC = "1" #&CDS_SEC = "1";
"A":   PN = "1"  !CDS_PN = "1";
"B":   PN = "2"  !CDS_PN = "2";
BODY = "Q_RES","I102": #LOCATION = "R1064" !CDS_LOCATION = "R1064" &SEC = "1" #&CDS_SEC = "1";
"A":   PN = "1"  !CDS_PN = "1";
"B":   PN = "2"  !CDS_PN = "2";
BODY = "Q_RES","I116": #LOCATION = "R1476" !CDS_LOCATION = "R1476" &SEC = "1" #&CDS_SEC = "1";
"A":   PN = "1"  !CDS_PN = "1";
"B":   PN = "2"  !CDS_PN = "2";
BODY = "Q_RES","I117": #LOCATION = "R1477" !CDS_LOCATION = "R1477" &SEC = "1" #&CDS_SEC = "1";
"A":   PN = "1"  !CDS_PN = "1";
"B":   PN = "2"  !CDS_PN = "2";
BODY = "Q_RES","I118": #LOCATION = "R1478" !CDS_LOCATION = "R1478" &SEC = "1" #&CDS_SEC = "1";
"A":   PN = "1"  !CDS_PN = "1";
"B":   PN = "2"  !CDS_PN = "2";
BODY = "Q_RES","I120": #LOCATION = "R1401" !CDS_LOCATION = "R1401" &SEC = "1" #&CDS_SEC = "1";
"A":   PN = "1"  !CDS_PN = "1";
"B":   PN = "2"  !CDS_PN = "2";
BODY = "Q_RES","I121": #LOCATION = "R1479" !CDS_LOCATION = "R1479" &SEC = "1" #&CDS_SEC = "1";
"A":   PN = "1"  !CDS_PN = "1";
"B":   PN = "2"  !CDS_PN = "2";
DRAWING = "@t6g_mb_lib.t6g(sch_1):page430";
BODY = "Q_RES","I5": #LOCATION = "R1105" !CDS_LOCATION = "R1105" &SEC = "1" #&CDS_SEC = "1";
"A":   PN = "1"  !CDS_PN = "1";
"B":   PN = "2"  !CDS_PN = "2";
BODY = "Q_RES","I7": #LOCATION = "R1112" !CDS_LOCATION = "R1112" &SEC = "1" #&CDS_SEC = "1";
"A":   PN = "1"  !CDS_PN = "1";
"B":   PN = "2"  !CDS_PN = "2";
BODY = "Q_RES","I8": #LOCATION = "R1113" !CDS_LOCATION = "R1113" &SEC = "1" #&CDS_SEC = "1";
"A":   PN = "1"  !CDS_PN = "1";
"B":   PN = "2"  !CDS_PN = "2";
BODY = "Q_RES","I9": #LOCATION = "R1115" !CDS_LOCATION = "R1115" &SEC = "1" #&CDS_SEC = "1";
"A":   PN = "1"  !CDS_PN = "1";
"B":   PN = "2"  !CDS_PN = "2";
BODY = "Q_RES","I10": #LOCATION = "R1111" !CDS_LOCATION = "R1111" &SEC = "1" #&CDS_SEC = "1";
"A":   PN = "1"  !CDS_PN = "1";
"B":   PN = "2"  !CDS_PN = "2";
BODY = "Q_RES","I11": #LOCATION = "R1114" !CDS_LOCATION = "R1114" &SEC = "1" #&CDS_SEC = "1";
"A":   PN = "1"  !CDS_PN = "1";
"B":   PN = "2"  !CDS_PN = "2";
BODY = "Q_RES","I15": #LOCATION = "R616" !CDS_LOCATION = "R616" #SEC = "1" !CDS_SEC = "1";
"A":   PN = "1"  !CDS_PN = "1";
"B":   PN = "2"  !CDS_PN = "2";
BODY = "Q_RES","I18": #LOCATION = "R635" !CDS_LOCATION = "R635" &SEC = "1" #&CDS_SEC = "1";
"A":   PN = "1"  !CDS_PN = "1";
"B":   PN = "2"  !CDS_PN = "2";
BODY = "Q_RES","I19": #LOCATION = "R636" !CDS_LOCATION = "R636" &SEC = "1" #&CDS_SEC = "1";
"A":   PN = "1"  !CDS_PN = "1";
"B":   PN = "2"  !CDS_PN = "2";
BODY = "Q_RES","I20": #LOCATION = "R615" !CDS_LOCATION = "R615" #SEC = "1" !CDS_SEC = "1";
"A":   PN = "1"  !CDS_PN = "1";
"B":   PN = "2"  !CDS_PN = "2";
BODY = "Q_RES","I21": #LOCATION = "R686" !CDS_LOCATION = "R686" &SEC = "1" #&CDS_SEC = "1";
"A":   PN = "1"  !CDS_PN = "1";
"B":   PN = "2"  !CDS_PN = "2";
BODY = "Q_RES","I22": #LOCATION = "R684" !CDS_LOCATION = "R684" &SEC = "1" #&CDS_SEC = "1";
"A":   PN = "1"  !CDS_PN = "1";
"B":   PN = "2"  !CDS_PN = "2";
BODY = "Q_RES","I32": #LOCATION = "R1109" !CDS_LOCATION = "R1109" &SEC = "1" #&CDS_SEC = "1";
"A":   PN = "1"  !CDS_PN = "1";
"B":   PN = "2"  !CDS_PN = "2";
BODY = "Q_RES","I33": #LOCATION = "R1110" !CDS_LOCATION = "R1110" &SEC = "1" #&CDS_SEC = "1";
"A":   PN = "1"  !CDS_PN = "1";
"B":   PN = "2"  !CDS_PN = "2";
BODY = "Q_RES","I36": #LOCATION = "R1118" !CDS_LOCATION = "R1118" &SEC = "1" #&CDS_SEC = "1";
"A":   PN = "1"  !CDS_PN = "1";
"B":   PN = "2"  !CDS_PN = "2";
BODY = "Q_RES","I37": #LOCATION = "R1120" !CDS_LOCATION = "R1120" &SEC = "1" #&CDS_SEC = "1";
"A":   PN = "1"  !CDS_PN = "1";
"B":   PN = "2"  !CDS_PN = "2";
BODY = "Q_RES","I39": #LOCATION = "R1121" !CDS_LOCATION = "R1121" &SEC = "1" #&CDS_SEC = "1";
"A":   PN = "1"  !CDS_PN = "1";
"B":   PN = "2"  !CDS_PN = "2";
BODY = "Q_RES","I40": #LOCATION = "R1116" !CDS_LOCATION = "R1116" &SEC = "1" #&CDS_SEC = "1";
"A":   PN = "1"  !CDS_PN = "1";
"B":   PN = "2"  !CDS_PN = "2";
BODY = "Q_RES","I41": #LOCATION = "R1119" !CDS_LOCATION = "R1119" &SEC = "1" #&CDS_SEC = "1";
"A":   PN = "1"  !CDS_PN = "1";
"B":   PN = "2"  !CDS_PN = "2";
BODY = "Q_RES","I42": #LOCATION = "R1108" !CDS_LOCATION = "R1108" &SEC = "1" #&CDS_SEC = "1";
"A":   PN = "1"  !CDS_PN = "1";
"B":   PN = "2"  !CDS_PN = "2";
BODY = "Q_RES","I50": #LOCATION = "R1091" !CDS_LOCATION = "R1091" &SEC = "1" #&CDS_SEC = "1";
"A":   PN = "1"  !CDS_PN = "1";
"B":   PN = "2"  !CDS_PN = "2";
BODY = "Q_RES","I51": #LOCATION = "R1122" !CDS_LOCATION = "R1122" &SEC = "1" #&CDS_SEC = "1";
"A":   PN = "1"  !CDS_PN = "1";
"B":   PN = "2"  !CDS_PN = "2";
BODY = "Q_RES","I55": #LOCATION = "R1096" !CDS_LOCATION = "R1096" &SEC = "1" #&CDS_SEC = "1";
"A":   PN = "1"  !CDS_PN = "1";
"B":   PN = "2"  !CDS_PN = "2";
BODY = "Q_RES","I56": #LOCATION = "R1088" !CDS_LOCATION = "R1088" #SEC = "1" !CDS_SEC = "1";
"A":   PN = "1"  !CDS_PN = "1";
"B":   PN = "2"  !CDS_PN = "2";
BODY = "Q_RES","I65": #LOCATION = "R1098" !CDS_LOCATION = "R1098" &SEC = "1" #&CDS_SEC = "1";
"A":   PN = "1"  !CDS_PN = "1";
"B":   PN = "2"  !CDS_PN = "2";
BODY = "Q_RES","I66": #LOCATION = "R1100" !CDS_LOCATION = "R1100" &SEC = "1" #&CDS_SEC = "1";
"A":   PN = "1"  !CDS_PN = "1";
"B":   PN = "2"  !CDS_PN = "2";
BODY = "Q_RES","I67": #LOCATION = "R1097" !CDS_LOCATION = "R1097" &SEC = "1" #&CDS_SEC = "1";
"A":   PN = "1"  !CDS_PN = "1";
"B":   PN = "2"  !CDS_PN = "2";
BODY = "Q_RES","I68": #LOCATION = "R1099" !CDS_LOCATION = "R1099" &SEC = "1" #&CDS_SEC = "1";
"A":   PN = "1"  !CDS_PN = "1";
"B":   PN = "2"  !CDS_PN = "2";
BODY = "Q_RES","I69": #LOCATION = "R1102" !CDS_LOCATION = "R1102" &SEC = "1" #&CDS_SEC = "1";
"A":   PN = "1"  !CDS_PN = "1";
"B":   PN = "2"  !CDS_PN = "2";
BODY = "Q_RES","I70": #LOCATION = "R1101" !CDS_LOCATION = "R1101" &SEC = "1" #&CDS_SEC = "1";
"A":   PN = "1"  !CDS_PN = "1";
"B":   PN = "2"  !CDS_PN = "2";
BODY = "Q_RES","I74": #LOCATION = "R1103" !CDS_LOCATION = "R1103" &SEC = "1" #&CDS_SEC = "1";
"A":   PN = "1"  !CDS_PN = "1";
"B":   PN = "2"  !CDS_PN = "2";
BODY = "Q_RES","I75": #LOCATION = "R1104" !CDS_LOCATION = "R1104" &SEC = "1" #&CDS_SEC = "1";
"A":   PN = "1"  !CDS_PN = "1";
"B":   PN = "2"  !CDS_PN = "2";
BODY = "Q_RES","I79": #LOCATION = "R1107" !CDS_LOCATION = "R1107" &SEC = "1" #&CDS_SEC = "1";
"A":   PN = "1"  !CDS_PN = "1";
"B":   PN = "2"  !CDS_PN = "2";
BODY = "PT5161LRS","I83": #LOCATION = "U6013" !CDS_LOCATION = "U6013" &SEC = "3" #&CDS_SEC = "3";
"CLKREQ_N":   PN = "G35"  !CDS_PN = "G35";
"EE_CLK":   PN = "FF5"  !CDS_PN = "FF5";
"EE_DAT":   PN = "FJ3"  !CDS_PN = "FJ3";
"GPIO0":   PN = "FJ6"  !CDS_PN = "FJ6";
"GPIO1":   PN = "FJ23"  !CDS_PN = "FJ23";
"GPIO2":   PN = "FJ25"  !CDS_PN = "FJ25";
"GPIO3":   PN = "FJ28"  !CDS_PN = "FJ28";
"INT_N":   PN = "FJ31"  !CDS_PN = "FJ31";
"JTAG_TCK":   PN = "B3"  !CDS_PN = "B3";
"JTAG_TDI":   PN = "B6"  !CDS_PN = "B6";
"JTAG_TDO":   PN = "B9"  !CDS_PN = "B9";
"JTAG_TEST_MODE":   PN = "FF8"  !CDS_PN = "FF8";
"JTAG_TMS":   PN = "B12"  !CDS_PN = "B12";
"JTAG_TRST_N":   PN = "E8"  !CDS_PN = "E8";
"MODE":   PN = "FJ9"  !CDS_PN = "FJ9";
"PERST_N":   PN = "F2"  !CDS_PN = "F2";
"REFCLK_OUTN":   PN = "E18"  !CDS_PN = "E18";
"REFCLK_OUTP":   PN = "B16"  !CDS_PN = "B16";
"REFCLKN":   PN = "FF18"  !CDS_PN = "FF18";
"REFCLKP":   PN = "FJ16"  !CDS_PN = "FJ16";
"RESET_N":   PN = "FF11"  !CDS_PN = "FF11";
"RXDET_BYP":   PN = "E11"  !CDS_PN = "E11";
"SCAN_MODE":   PN = "FF33"  !CDS_PN = "FF33";
"SMB_ADDR1":   PN = "F34"  !CDS_PN = "F34";
"SMB_ADDR2":   PN = "B23"  !CDS_PN = "B23";
"SMB_ADDR3":   PN = "B25"  !CDS_PN = "B25";
"SMBCLK":   PN = "B31"  !CDS_PN = "B31";
"SMBDAT":   PN = "B28"  !CDS_PN = "B28";
"T_SENSE":   PN = "E30"  !CDS_PN = "E30";
"TEST0":   PN = "FF24"  !CDS_PN = "FF24";
"TEST1":   PN = "FF27"  !CDS_PN = "FF27";
"TEST2":   PN = "FF30"  !CDS_PN = "FF30";
BODY = "Q_RES","I85": #LOCATION = "R1408" !CDS_LOCATION = "R1408" &SEC = "1" #&CDS_SEC = "1";
"A":   PN = "1"  !CDS_PN = "1";
"B":   PN = "2"  !CDS_PN = "2";
BODY = "Q_RES","I96": #LOCATION = "R1414" !CDS_LOCATION = "R1414" &SEC = "1" #&CDS_SEC = "1";
"A":   PN = "1"  !CDS_PN = "1";
"B":   PN = "2"  !CDS_PN = "2";
BODY = "Q_RES","I97": #LOCATION = "R1413" !CDS_LOCATION = "R1413" &SEC = "1" #&CDS_SEC = "1";
"A":   PN = "1"  !CDS_PN = "1";
"B":   PN = "2"  !CDS_PN = "2";
BODY = "Q_RES","I101": #LOCATION = "R1412" !CDS_LOCATION = "R1412" &SEC = "1" #&CDS_SEC = "1";
"A":   PN = "1"  !CDS_PN = "1";
"B":   PN = "2"  !CDS_PN = "2";
BODY = "Q_RES","I102": #LOCATION = "R1106" !CDS_LOCATION = "R1106" &SEC = "1" #&CDS_SEC = "1";
"A":   PN = "1"  !CDS_PN = "1";
"B":   PN = "2"  !CDS_PN = "2";
BODY = "Q_RES","I112": #LOCATION = "R1482" !CDS_LOCATION = "R1482" &SEC = "1" #&CDS_SEC = "1";
"A":   PN = "1"  !CDS_PN = "1";
"B":   PN = "2"  !CDS_PN = "2";
BODY = "Q_RES","I113": #LOCATION = "R1483" !CDS_LOCATION = "R1483" &SEC = "1" #&CDS_SEC = "1";
"A":   PN = "1"  !CDS_PN = "1";
"B":   PN = "2"  !CDS_PN = "2";
BODY = "Q_RES","I117": #LOCATION = "R1409" !CDS_LOCATION = "R1409" &SEC = "1" #&CDS_SEC = "1";
"A":   PN = "1"  !CDS_PN = "1";
"B":   PN = "2"  !CDS_PN = "2";
BODY = "Q_RES","I118": #LOCATION = "R1484" !CDS_LOCATION = "R1484" &SEC = "1" #&CDS_SEC = "1";
"A":   PN = "1"  !CDS_PN = "1";
"B":   PN = "2"  !CDS_PN = "2";
BODY = "Q_RES","I119": #LOCATION = "R1485" !CDS_LOCATION = "R1485" &SEC = "1" #&CDS_SEC = "1";
"A":   PN = "1"  !CDS_PN = "1";
"B":   PN = "2"  !CDS_PN = "2";
DRAWING = "@t6g_mb_lib.t6g(sch_1):page327";
BODY = "CONN112_10137002101LF","I19": #LOCATION = "J106" !CDS_LOCATION = "J106" &SEC = "1" #&CDS_SEC = "1";
"A5":   PN = "A5"  !CDS_PN = "A5";
"A6":   PN = "A6"  !CDS_PN = "A6";
"A7":   PN = "A7"  !CDS_PN = "A7";
"A8":   PN = "A8"  !CDS_PN = "A8";
"B5":   PN = "B5"  !CDS_PN = "B5";
"B6":   PN = "B6"  !CDS_PN = "B6";
"B7":   PN = "B7"  !CDS_PN = "B7";
"B8":   PN = "B8"  !CDS_PN = "B8";
"C5":   PN = "C5"  !CDS_PN = "C5";
"C6":   PN = "C6"  !CDS_PN = "C6";
"C7":   PN = "C7"  !CDS_PN = "C7";
"C8":   PN = "C8"  !CDS_PN = "C8";
"D5":   PN = "D5"  !CDS_PN = "D5";
"D6":   PN = "D6"  !CDS_PN = "D6";
"D7":   PN = "D7"  !CDS_PN = "D7";
"D8":   PN = "D8"  !CDS_PN = "D8";
"E5":   PN = "E5"  !CDS_PN = "E5";
"E6":   PN = "E6"  !CDS_PN = "E6";
"E7":   PN = "E7"  !CDS_PN = "E7";
"E8":   PN = "E8"  !CDS_PN = "E8";
"F5":   PN = "F5"  !CDS_PN = "F5";
"F6":   PN = "F6"  !CDS_PN = "F6";
"F7":   PN = "F7"  !CDS_PN = "F7";
"F8":   PN = "F8"  !CDS_PN = "F8";
"G5":   PN = "G5"  !CDS_PN = "G5";
"G6":   PN = "G6"  !CDS_PN = "G6";
"G7":   PN = "G7"  !CDS_PN = "G7";
"G8":   PN = "G8"  !CDS_PN = "G8";
"H5":   PN = "H5"  !CDS_PN = "H5";
"H6":   PN = "H6"  !CDS_PN = "H6";
"H7":   PN = "H7"  !CDS_PN = "H7";
"H8":   PN = "H8"  !CDS_PN = "H8";
"I5":   PN = "I5"  !CDS_PN = "I5";
"I6":   PN = "I6"  !CDS_PN = "I6";
"I7":   PN = "I7"  !CDS_PN = "I7";
"I8":   PN = "I8"  !CDS_PN = "I8";
"J5":   PN = "J5"  !CDS_PN = "J5";
"J6":   PN = "J6"  !CDS_PN = "J6";
"J7":   PN = "J7"  !CDS_PN = "J7";
"J8":   PN = "J8"  !CDS_PN = "J8";
"K5":   PN = "K5"  !CDS_PN = "K5";
"K6":   PN = "K6"  !CDS_PN = "K6";
"K7":   PN = "K7"  !CDS_PN = "K7";
"K8":   PN = "K8"  !CDS_PN = "K8";
"L5":   PN = "L5"  !CDS_PN = "L5";
"L6":   PN = "L6"  !CDS_PN = "L6";
"L7":   PN = "L7"  !CDS_PN = "L7";
"L8":   PN = "L8"  !CDS_PN = "L8";
"M5":   PN = "M5"  !CDS_PN = "M5";
"M6":   PN = "M6"  !CDS_PN = "M6";
"M7":   PN = "M7"  !CDS_PN = "M7";
"M8":   PN = "M8"  !CDS_PN = "M8";
"N5":   PN = "N5"  !CDS_PN = "N5";
"N6":   PN = "N6"  !CDS_PN = "N6";
"N7":   PN = "N7"  !CDS_PN = "N7";
"N8":   PN = "N8"  !CDS_PN = "N8";
BODY = "CONN112_10137002101LF","I74": #LOCATION = "J106" !CDS_LOCATION = "J106" &SEC = "2" #&CDS_SEC = "2";
"A1":   PN = "A1"  !CDS_PN = "A1";
"A2":   PN = "A2"  !CDS_PN = "A2";
"A3":   PN = "A3"  !CDS_PN = "A3";
"A4":   PN = "A4"  !CDS_PN = "A4";
"B1":   PN = "B1"  !CDS_PN = "B1";
"B2":   PN = "B2"  !CDS_PN = "B2";
"B3":   PN = "B3"  !CDS_PN = "B3";
"B4":   PN = "B4"  !CDS_PN = "B4";
"C1":   PN = "C1"  !CDS_PN = "C1";
"C2":   PN = "C2"  !CDS_PN = "C2";
"C3":   PN = "C3"  !CDS_PN = "C3";
"C4":   PN = "C4"  !CDS_PN = "C4";
"D1":   PN = "D1"  !CDS_PN = "D1";
"D2":   PN = "D2"  !CDS_PN = "D2";
"D3":   PN = "D3"  !CDS_PN = "D3";
"D4":   PN = "D4"  !CDS_PN = "D4";
"E1":   PN = "E1"  !CDS_PN = "E1";
"E2":   PN = "E2"  !CDS_PN = "E2";
"E3":   PN = "E3"  !CDS_PN = "E3";
"E4":   PN = "E4"  !CDS_PN = "E4";
"F1":   PN = "F1"  !CDS_PN = "F1";
"F2":   PN = "F2"  !CDS_PN = "F2";
"F3":   PN = "F3"  !CDS_PN = "F3";
"F4":   PN = "F4"  !CDS_PN = "F4";
"G1":   PN = "G1"  !CDS_PN = "G1";
"G2":   PN = "G2"  !CDS_PN = "G2";
"G3":   PN = "G3"  !CDS_PN = "G3";
"G4":   PN = "G4"  !CDS_PN = "G4";
"H1":   PN = "H1"  !CDS_PN = "H1";
"H2":   PN = "H2"  !CDS_PN = "H2";
"H3":   PN = "H3"  !CDS_PN = "H3";
"H4":   PN = "H4"  !CDS_PN = "H4";
"I1":   PN = "I1"  !CDS_PN = "I1";
"I2":   PN = "I2"  !CDS_PN = "I2";
"I3":   PN = "I3"  !CDS_PN = "I3";
"I4":   PN = "I4"  !CDS_PN = "I4";
"J1":   PN = "J1"  !CDS_PN = "J1";
"J2":   PN = "J2"  !CDS_PN = "J2";
"J3":   PN = "J3"  !CDS_PN = "J3";
"J4":   PN = "J4"  !CDS_PN = "J4";
"K1":   PN = "K1"  !CDS_PN = "K1";
"K2":   PN = "K2"  !CDS_PN = "K2";
"K3":   PN = "K3"  !CDS_PN = "K3";
"K4":   PN = "K4"  !CDS_PN = "K4";
"L1":   PN = "L1"  !CDS_PN = "L1";
"L2":   PN = "L2"  !CDS_PN = "L2";
"L3":   PN = "L3"  !CDS_PN = "L3";
"L4":   PN = "L4"  !CDS_PN = "L4";
"M1":   PN = "M1"  !CDS_PN = "M1";
"M2":   PN = "M2"  !CDS_PN = "M2";
"M3":   PN = "M3"  !CDS_PN = "M3";
"M4":   PN = "M4"  !CDS_PN = "M4";
"N1":   PN = "N1"  !CDS_PN = "N1";
"N2":   PN = "N2"  !CDS_PN = "N2";
"N3":   PN = "N3"  !CDS_PN = "N3";
"N4":   PN = "N4"  !CDS_PN = "N4";
DRAWING = "@t6g_mb_lib.t6g(sch_1):page326";
BODY = "CONN112_10137002101LF","I75": #LOCATION = "J105" !CDS_LOCATION = "J105" &SEC = "2" #&CDS_SEC = "2";
"A1":   PN = "A1"  !CDS_PN = "A1";
"A2":   PN = "A2"  !CDS_PN = "A2";
"A3":   PN = "A3"  !CDS_PN = "A3";
"A4":   PN = "A4"  !CDS_PN = "A4";
"B1":   PN = "B1"  !CDS_PN = "B1";
"B2":   PN = "B2"  !CDS_PN = "B2";
"B3":   PN = "B3"  !CDS_PN = "B3";
"B4":   PN = "B4"  !CDS_PN = "B4";
"C1":   PN = "C1"  !CDS_PN = "C1";
"C2":   PN = "C2"  !CDS_PN = "C2";
"C3":   PN = "C3"  !CDS_PN = "C3";
"C4":   PN = "C4"  !CDS_PN = "C4";
"D1":   PN = "D1"  !CDS_PN = "D1";
"D2":   PN = "D2"  !CDS_PN = "D2";
"D3":   PN = "D3"  !CDS_PN = "D3";
"D4":   PN = "D4"  !CDS_PN = "D4";
"E1":   PN = "E1"  !CDS_PN = "E1";
"E2":   PN = "E2"  !CDS_PN = "E2";
"E3":   PN = "E3"  !CDS_PN = "E3";
"E4":   PN = "E4"  !CDS_PN = "E4";
"F1":   PN = "F1"  !CDS_PN = "F1";
"F2":   PN = "F2"  !CDS_PN = "F2";
"F3":   PN = "F3"  !CDS_PN = "F3";
"F4":   PN = "F4"  !CDS_PN = "F4";
"G1":   PN = "G1"  !CDS_PN = "G1";
"G2":   PN = "G2"  !CDS_PN = "G2";
"G3":   PN = "G3"  !CDS_PN = "G3";
"G4":   PN = "G4"  !CDS_PN = "G4";
"H1":   PN = "H1"  !CDS_PN = "H1";
"H2":   PN = "H2"  !CDS_PN = "H2";
"H3":   PN = "H3"  !CDS_PN = "H3";
"H4":   PN = "H4"  !CDS_PN = "H4";
"I1":   PN = "I1"  !CDS_PN = "I1";
"I2":   PN = "I2"  !CDS_PN = "I2";
"I3":   PN = "I3"  !CDS_PN = "I3";
"I4":   PN = "I4"  !CDS_PN = "I4";
"J1":   PN = "J1"  !CDS_PN = "J1";
"J2":   PN = "J2"  !CDS_PN = "J2";
"J3":   PN = "J3"  !CDS_PN = "J3";
"J4":   PN = "J4"  !CDS_PN = "J4";
"K1":   PN = "K1"  !CDS_PN = "K1";
"K2":   PN = "K2"  !CDS_PN = "K2";
"K3":   PN = "K3"  !CDS_PN = "K3";
"K4":   PN = "K4"  !CDS_PN = "K4";
"L1":   PN = "L1"  !CDS_PN = "L1";
"L2":   PN = "L2"  !CDS_PN = "L2";
"L3":   PN = "L3"  !CDS_PN = "L3";
"L4":   PN = "L4"  !CDS_PN = "L4";
"M1":   PN = "M1"  !CDS_PN = "M1";
"M2":   PN = "M2"  !CDS_PN = "M2";
"M3":   PN = "M3"  !CDS_PN = "M3";
"M4":   PN = "M4"  !CDS_PN = "M4";
"N1":   PN = "N1"  !CDS_PN = "N1";
"N2":   PN = "N2"  !CDS_PN = "N2";
"N3":   PN = "N3"  !CDS_PN = "N3";
"N4":   PN = "N4"  !CDS_PN = "N4";
BODY = "CONN112_10137002101LF","I76": #LOCATION = "J105" !CDS_LOCATION = "J105" &SEC = "1" #&CDS_SEC = "1";
"A5":   PN = "A5"  !CDS_PN = "A5";
"A6":   PN = "A6"  !CDS_PN = "A6";
"A7":   PN = "A7"  !CDS_PN = "A7";
"A8":   PN = "A8"  !CDS_PN = "A8";
"B5":   PN = "B5"  !CDS_PN = "B5";
"B6":   PN = "B6"  !CDS_PN = "B6";
"B7":   PN = "B7"  !CDS_PN = "B7";
"B8":   PN = "B8"  !CDS_PN = "B8";
"C5":   PN = "C5"  !CDS_PN = "C5";
"C6":   PN = "C6"  !CDS_PN = "C6";
"C7":   PN = "C7"  !CDS_PN = "C7";
"C8":   PN = "C8"  !CDS_PN = "C8";
"D5":   PN = "D5"  !CDS_PN = "D5";
"D6":   PN = "D6"  !CDS_PN = "D6";
"D7":   PN = "D7"  !CDS_PN = "D7";
"D8":   PN = "D8"  !CDS_PN = "D8";
"E5":   PN = "E5"  !CDS_PN = "E5";
"E6":   PN = "E6"  !CDS_PN = "E6";
"E7":   PN = "E7"  !CDS_PN = "E7";
"E8":   PN = "E8"  !CDS_PN = "E8";
"F5":   PN = "F5"  !CDS_PN = "F5";
"F6":   PN = "F6"  !CDS_PN = "F6";
"F7":   PN = "F7"  !CDS_PN = "F7";
"F8":   PN = "F8"  !CDS_PN = "F8";
"G5":   PN = "G5"  !CDS_PN = "G5";
"G6":   PN = "G6"  !CDS_PN = "G6";
"G7":   PN = "G7"  !CDS_PN = "G7";
"G8":   PN = "G8"  !CDS_PN = "G8";
"H5":   PN = "H5"  !CDS_PN = "H5";
"H6":   PN = "H6"  !CDS_PN = "H6";
"H7":   PN = "H7"  !CDS_PN = "H7";
"H8":   PN = "H8"  !CDS_PN = "H8";
"I5":   PN = "I5"  !CDS_PN = "I5";
"I6":   PN = "I6"  !CDS_PN = "I6";
"I7":   PN = "I7"  !CDS_PN = "I7";
"I8":   PN = "I8"  !CDS_PN = "I8";
"J5":   PN = "J5"  !CDS_PN = "J5";
"J6":   PN = "J6"  !CDS_PN = "J6";
"J7":   PN = "J7"  !CDS_PN = "J7";
"J8":   PN = "J8"  !CDS_PN = "J8";
"K5":   PN = "K5"  !CDS_PN = "K5";
"K6":   PN = "K6"  !CDS_PN = "K6";
"K7":   PN = "K7"  !CDS_PN = "K7";
"K8":   PN = "K8"  !CDS_PN = "K8";
"L5":   PN = "L5"  !CDS_PN = "L5";
"L6":   PN = "L6"  !CDS_PN = "L6";
"L7":   PN = "L7"  !CDS_PN = "L7";
"L8":   PN = "L8"  !CDS_PN = "L8";
"M5":   PN = "M5"  !CDS_PN = "M5";
"M6":   PN = "M6"  !CDS_PN = "M6";
"M7":   PN = "M7"  !CDS_PN = "M7";
"M8":   PN = "M8"  !CDS_PN = "M8";
"N5":   PN = "N5"  !CDS_PN = "N5";
"N6":   PN = "N6"  !CDS_PN = "N6";
"N7":   PN = "N7"  !CDS_PN = "N7";
"N8":   PN = "N8"  !CDS_PN = "N8";
DRAWING = "@t6g_mb_lib.t6g(sch_1):page317";
BODY = "CONN112_10137002101LF","I49": #LOCATION = "J107" !CDS_LOCATION = "J107" &SEC = "2" #&CDS_SEC = "2";
"A1":   PN = "A1"  !CDS_PN = "A1";
"A2":   PN = "A2"  !CDS_PN = "A2";
"A3":   PN = "A3"  !CDS_PN = "A3";
"A4":   PN = "A4"  !CDS_PN = "A4";
"B1":   PN = "B1"  !CDS_PN = "B1";
"B2":   PN = "B2"  !CDS_PN = "B2";
"B3":   PN = "B3"  !CDS_PN = "B3";
"B4":   PN = "B4"  !CDS_PN = "B4";
"C1":   PN = "C1"  !CDS_PN = "C1";
"C2":   PN = "C2"  !CDS_PN = "C2";
"C3":   PN = "C3"  !CDS_PN = "C3";
"C4":   PN = "C4"  !CDS_PN = "C4";
"D1":   PN = "D1"  !CDS_PN = "D1";
"D2":   PN = "D2"  !CDS_PN = "D2";
"D3":   PN = "D3"  !CDS_PN = "D3";
"D4":   PN = "D4"  !CDS_PN = "D4";
"E1":   PN = "E1"  !CDS_PN = "E1";
"E2":   PN = "E2"  !CDS_PN = "E2";
"E3":   PN = "E3"  !CDS_PN = "E3";
"E4":   PN = "E4"  !CDS_PN = "E4";
"F1":   PN = "F1"  !CDS_PN = "F1";
"F2":   PN = "F2"  !CDS_PN = "F2";
"F3":   PN = "F3"  !CDS_PN = "F3";
"F4":   PN = "F4"  !CDS_PN = "F4";
"G1":   PN = "G1"  !CDS_PN = "G1";
"G2":   PN = "G2"  !CDS_PN = "G2";
"G3":   PN = "G3"  !CDS_PN = "G3";
"G4":   PN = "G4"  !CDS_PN = "G4";
"H1":   PN = "H1"  !CDS_PN = "H1";
"H2":   PN = "H2"  !CDS_PN = "H2";
"H3":   PN = "H3"  !CDS_PN = "H3";
"H4":   PN = "H4"  !CDS_PN = "H4";
"I1":   PN = "I1"  !CDS_PN = "I1";
"I2":   PN = "I2"  !CDS_PN = "I2";
"I3":   PN = "I3"  !CDS_PN = "I3";
"I4":   PN = "I4"  !CDS_PN = "I4";
"J1":   PN = "J1"  !CDS_PN = "J1";
"J2":   PN = "J2"  !CDS_PN = "J2";
"J3":   PN = "J3"  !CDS_PN = "J3";
"J4":   PN = "J4"  !CDS_PN = "J4";
"K1":   PN = "K1"  !CDS_PN = "K1";
"K2":   PN = "K2"  !CDS_PN = "K2";
"K3":   PN = "K3"  !CDS_PN = "K3";
"K4":   PN = "K4"  !CDS_PN = "K4";
"L1":   PN = "L1"  !CDS_PN = "L1";
"L2":   PN = "L2"  !CDS_PN = "L2";
"L3":   PN = "L3"  !CDS_PN = "L3";
"L4":   PN = "L4"  !CDS_PN = "L4";
"M1":   PN = "M1"  !CDS_PN = "M1";
"M2":   PN = "M2"  !CDS_PN = "M2";
"M3":   PN = "M3"  !CDS_PN = "M3";
"M4":   PN = "M4"  !CDS_PN = "M4";
"N1":   PN = "N1"  !CDS_PN = "N1";
"N2":   PN = "N2"  !CDS_PN = "N2";
"N3":   PN = "N3"  !CDS_PN = "N3";
"N4":   PN = "N4"  !CDS_PN = "N4";
BODY = "CONN112_10137002101LF","I70": #LOCATION = "J107" !CDS_LOCATION = "J107" &SEC = "1" #&CDS_SEC = "1";
"A5":   PN = "A5"  !CDS_PN = "A5";
"A6":   PN = "A6"  !CDS_PN = "A6";
"A7":   PN = "A7"  !CDS_PN = "A7";
"A8":   PN = "A8"  !CDS_PN = "A8";
"B5":   PN = "B5"  !CDS_PN = "B5";
"B6":   PN = "B6"  !CDS_PN = "B6";
"B7":   PN = "B7"  !CDS_PN = "B7";
"B8":   PN = "B8"  !CDS_PN = "B8";
"C5":   PN = "C5"  !CDS_PN = "C5";
"C6":   PN = "C6"  !CDS_PN = "C6";
"C7":   PN = "C7"  !CDS_PN = "C7";
"C8":   PN = "C8"  !CDS_PN = "C8";
"D5":   PN = "D5"  !CDS_PN = "D5";
"D6":   PN = "D6"  !CDS_PN = "D6";
"D7":   PN = "D7"  !CDS_PN = "D7";
"D8":   PN = "D8"  !CDS_PN = "D8";
"E5":   PN = "E5"  !CDS_PN = "E5";
"E6":   PN = "E6"  !CDS_PN = "E6";
"E7":   PN = "E7"  !CDS_PN = "E7";
"E8":   PN = "E8"  !CDS_PN = "E8";
"F5":   PN = "F5"  !CDS_PN = "F5";
"F6":   PN = "F6"  !CDS_PN = "F6";
"F7":   PN = "F7"  !CDS_PN = "F7";
"F8":   PN = "F8"  !CDS_PN = "F8";
"G5":   PN = "G5"  !CDS_PN = "G5";
"G6":   PN = "G6"  !CDS_PN = "G6";
"G7":   PN = "G7"  !CDS_PN = "G7";
"G8":   PN = "G8"  !CDS_PN = "G8";
"H5":   PN = "H5"  !CDS_PN = "H5";
"H6":   PN = "H6"  !CDS_PN = "H6";
"H7":   PN = "H7"  !CDS_PN = "H7";
"H8":   PN = "H8"  !CDS_PN = "H8";
"I5":   PN = "I5"  !CDS_PN = "I5";
"I6":   PN = "I6"  !CDS_PN = "I6";
"I7":   PN = "I7"  !CDS_PN = "I7";
"I8":   PN = "I8"  !CDS_PN = "I8";
"J5":   PN = "J5"  !CDS_PN = "J5";
"J6":   PN = "J6"  !CDS_PN = "J6";
"J7":   PN = "J7"  !CDS_PN = "J7";
"J8":   PN = "J8"  !CDS_PN = "J8";
"K5":   PN = "K5"  !CDS_PN = "K5";
"K6":   PN = "K6"  !CDS_PN = "K6";
"K7":   PN = "K7"  !CDS_PN = "K7";
"K8":   PN = "K8"  !CDS_PN = "K8";
"L5":   PN = "L5"  !CDS_PN = "L5";
"L6":   PN = "L6"  !CDS_PN = "L6";
"L7":   PN = "L7"  !CDS_PN = "L7";
"L8":   PN = "L8"  !CDS_PN = "L8";
"M5":   PN = "M5"  !CDS_PN = "M5";
"M6":   PN = "M6"  !CDS_PN = "M6";
"M7":   PN = "M7"  !CDS_PN = "M7";
"M8":   PN = "M8"  !CDS_PN = "M8";
"N5":   PN = "N5"  !CDS_PN = "N5";
"N6":   PN = "N6"  !CDS_PN = "N6";
"N7":   PN = "N7"  !CDS_PN = "N7";
"N8":   PN = "N8"  !CDS_PN = "N8";
DRAWING = "@t6g_mb_lib.t6g(sch_1):page320";
BODY = "CONN112_10137002101LF","I15": #LOCATION = "J108" !CDS_LOCATION = "J108" &SEC = "1" #&CDS_SEC = "1";
"A5":   PN = "A5"  !CDS_PN = "A5";
"A6":   PN = "A6"  !CDS_PN = "A6";
"A7":   PN = "A7"  !CDS_PN = "A7";
"A8":   PN = "A8"  !CDS_PN = "A8";
"B5":   PN = "B5"  !CDS_PN = "B5";
"B6":   PN = "B6"  !CDS_PN = "B6";
"B7":   PN = "B7"  !CDS_PN = "B7";
"B8":   PN = "B8"  !CDS_PN = "B8";
"C5":   PN = "C5"  !CDS_PN = "C5";
"C6":   PN = "C6"  !CDS_PN = "C6";
"C7":   PN = "C7"  !CDS_PN = "C7";
"C8":   PN = "C8"  !CDS_PN = "C8";
"D5":   PN = "D5"  !CDS_PN = "D5";
"D6":   PN = "D6"  !CDS_PN = "D6";
"D7":   PN = "D7"  !CDS_PN = "D7";
"D8":   PN = "D8"  !CDS_PN = "D8";
"E5":   PN = "E5"  !CDS_PN = "E5";
"E6":   PN = "E6"  !CDS_PN = "E6";
"E7":   PN = "E7"  !CDS_PN = "E7";
"E8":   PN = "E8"  !CDS_PN = "E8";
"F5":   PN = "F5"  !CDS_PN = "F5";
"F6":   PN = "F6"  !CDS_PN = "F6";
"F7":   PN = "F7"  !CDS_PN = "F7";
"F8":   PN = "F8"  !CDS_PN = "F8";
"G5":   PN = "G5"  !CDS_PN = "G5";
"G6":   PN = "G6"  !CDS_PN = "G6";
"G7":   PN = "G7"  !CDS_PN = "G7";
"G8":   PN = "G8"  !CDS_PN = "G8";
"H5":   PN = "H5"  !CDS_PN = "H5";
"H6":   PN = "H6"  !CDS_PN = "H6";
"H7":   PN = "H7"  !CDS_PN = "H7";
"H8":   PN = "H8"  !CDS_PN = "H8";
"I5":   PN = "I5"  !CDS_PN = "I5";
"I6":   PN = "I6"  !CDS_PN = "I6";
"I7":   PN = "I7"  !CDS_PN = "I7";
"I8":   PN = "I8"  !CDS_PN = "I8";
"J5":   PN = "J5"  !CDS_PN = "J5";
"J6":   PN = "J6"  !CDS_PN = "J6";
"J7":   PN = "J7"  !CDS_PN = "J7";
"J8":   PN = "J8"  !CDS_PN = "J8";
"K5":   PN = "K5"  !CDS_PN = "K5";
"K6":   PN = "K6"  !CDS_PN = "K6";
"K7":   PN = "K7"  !CDS_PN = "K7";
"K8":   PN = "K8"  !CDS_PN = "K8";
"L5":   PN = "L5"  !CDS_PN = "L5";
"L6":   PN = "L6"  !CDS_PN = "L6";
"L7":   PN = "L7"  !CDS_PN = "L7";
"L8":   PN = "L8"  !CDS_PN = "L8";
"M5":   PN = "M5"  !CDS_PN = "M5";
"M6":   PN = "M6"  !CDS_PN = "M6";
"M7":   PN = "M7"  !CDS_PN = "M7";
"M8":   PN = "M8"  !CDS_PN = "M8";
"N5":   PN = "N5"  !CDS_PN = "N5";
"N6":   PN = "N6"  !CDS_PN = "N6";
"N7":   PN = "N7"  !CDS_PN = "N7";
"N8":   PN = "N8"  !CDS_PN = "N8";
BODY = "CONN112_10137002101LF","I72": #LOCATION = "J108" !CDS_LOCATION = "J108" &SEC = "2" #&CDS_SEC = "2";
"A1":   PN = "A1"  !CDS_PN = "A1";
"A2":   PN = "A2"  !CDS_PN = "A2";
"A3":   PN = "A3"  !CDS_PN = "A3";
"A4":   PN = "A4"  !CDS_PN = "A4";
"B1":   PN = "B1"  !CDS_PN = "B1";
"B2":   PN = "B2"  !CDS_PN = "B2";
"B3":   PN = "B3"  !CDS_PN = "B3";
"B4":   PN = "B4"  !CDS_PN = "B4";
"C1":   PN = "C1"  !CDS_PN = "C1";
"C2":   PN = "C2"  !CDS_PN = "C2";
"C3":   PN = "C3"  !CDS_PN = "C3";
"C4":   PN = "C4"  !CDS_PN = "C4";
"D1":   PN = "D1"  !CDS_PN = "D1";
"D2":   PN = "D2"  !CDS_PN = "D2";
"D3":   PN = "D3"  !CDS_PN = "D3";
"D4":   PN = "D4"  !CDS_PN = "D4";
"E1":   PN = "E1"  !CDS_PN = "E1";
"E2":   PN = "E2"  !CDS_PN = "E2";
"E3":   PN = "E3"  !CDS_PN = "E3";
"E4":   PN = "E4"  !CDS_PN = "E4";
"F1":   PN = "F1"  !CDS_PN = "F1";
"F2":   PN = "F2"  !CDS_PN = "F2";
"F3":   PN = "F3"  !CDS_PN = "F3";
"F4":   PN = "F4"  !CDS_PN = "F4";
"G1":   PN = "G1"  !CDS_PN = "G1";
"G2":   PN = "G2"  !CDS_PN = "G2";
"G3":   PN = "G3"  !CDS_PN = "G3";
"G4":   PN = "G4"  !CDS_PN = "G4";
"H1":   PN = "H1"  !CDS_PN = "H1";
"H2":   PN = "H2"  !CDS_PN = "H2";
"H3":   PN = "H3"  !CDS_PN = "H3";
"H4":   PN = "H4"  !CDS_PN = "H4";
"I1":   PN = "I1"  !CDS_PN = "I1";
"I2":   PN = "I2"  !CDS_PN = "I2";
"I3":   PN = "I3"  !CDS_PN = "I3";
"I4":   PN = "I4"  !CDS_PN = "I4";
"J1":   PN = "J1"  !CDS_PN = "J1";
"J2":   PN = "J2"  !CDS_PN = "J2";
"J3":   PN = "J3"  !CDS_PN = "J3";
"J4":   PN = "J4"  !CDS_PN = "J4";
"K1":   PN = "K1"  !CDS_PN = "K1";
"K2":   PN = "K2"  !CDS_PN = "K2";
"K3":   PN = "K3"  !CDS_PN = "K3";
"K4":   PN = "K4"  !CDS_PN = "K4";
"L1":   PN = "L1"  !CDS_PN = "L1";
"L2":   PN = "L2"  !CDS_PN = "L2";
"L3":   PN = "L3"  !CDS_PN = "L3";
"L4":   PN = "L4"  !CDS_PN = "L4";
"M1":   PN = "M1"  !CDS_PN = "M1";
"M2":   PN = "M2"  !CDS_PN = "M2";
"M3":   PN = "M3"  !CDS_PN = "M3";
"M4":   PN = "M4"  !CDS_PN = "M4";
"N1":   PN = "N1"  !CDS_PN = "N1";
"N2":   PN = "N2"  !CDS_PN = "N2";
"N3":   PN = "N3"  !CDS_PN = "N3";
"N4":   PN = "N4"  !CDS_PN = "N4";
DRAWING = "@t6g_mb_lib.t6g(sch_1):page319";
BODY = "CONN112_10137002101LF","I16": #LOCATION = "J109" !CDS_LOCATION = "J109" &SEC = "1" #&CDS_SEC = "1";
"A5":   PN = "A5"  !CDS_PN = "A5";
"A6":   PN = "A6"  !CDS_PN = "A6";
"A7":   PN = "A7"  !CDS_PN = "A7";
"A8":   PN = "A8"  !CDS_PN = "A8";
"B5":   PN = "B5"  !CDS_PN = "B5";
"B6":   PN = "B6"  !CDS_PN = "B6";
"B7":   PN = "B7"  !CDS_PN = "B7";
"B8":   PN = "B8"  !CDS_PN = "B8";
"C5":   PN = "C5"  !CDS_PN = "C5";
"C6":   PN = "C6"  !CDS_PN = "C6";
"C7":   PN = "C7"  !CDS_PN = "C7";
"C8":   PN = "C8"  !CDS_PN = "C8";
"D5":   PN = "D5"  !CDS_PN = "D5";
"D6":   PN = "D6"  !CDS_PN = "D6";
"D7":   PN = "D7"  !CDS_PN = "D7";
"D8":   PN = "D8"  !CDS_PN = "D8";
"E5":   PN = "E5"  !CDS_PN = "E5";
"E6":   PN = "E6"  !CDS_PN = "E6";
"E7":   PN = "E7"  !CDS_PN = "E7";
"E8":   PN = "E8"  !CDS_PN = "E8";
"F5":   PN = "F5"  !CDS_PN = "F5";
"F6":   PN = "F6"  !CDS_PN = "F6";
"F7":   PN = "F7"  !CDS_PN = "F7";
"F8":   PN = "F8"  !CDS_PN = "F8";
"G5":   PN = "G5"  !CDS_PN = "G5";
"G6":   PN = "G6"  !CDS_PN = "G6";
"G7":   PN = "G7"  !CDS_PN = "G7";
"G8":   PN = "G8"  !CDS_PN = "G8";
"H5":   PN = "H5"  !CDS_PN = "H5";
"H6":   PN = "H6"  !CDS_PN = "H6";
"H7":   PN = "H7"  !CDS_PN = "H7";
"H8":   PN = "H8"  !CDS_PN = "H8";
"I5":   PN = "I5"  !CDS_PN = "I5";
"I6":   PN = "I6"  !CDS_PN = "I6";
"I7":   PN = "I7"  !CDS_PN = "I7";
"I8":   PN = "I8"  !CDS_PN = "I8";
"J5":   PN = "J5"  !CDS_PN = "J5";
"J6":   PN = "J6"  !CDS_PN = "J6";
"J7":   PN = "J7"  !CDS_PN = "J7";
"J8":   PN = "J8"  !CDS_PN = "J8";
"K5":   PN = "K5"  !CDS_PN = "K5";
"K6":   PN = "K6"  !CDS_PN = "K6";
"K7":   PN = "K7"  !CDS_PN = "K7";
"K8":   PN = "K8"  !CDS_PN = "K8";
"L5":   PN = "L5"  !CDS_PN = "L5";
"L6":   PN = "L6"  !CDS_PN = "L6";
"L7":   PN = "L7"  !CDS_PN = "L7";
"L8":   PN = "L8"  !CDS_PN = "L8";
"M5":   PN = "M5"  !CDS_PN = "M5";
"M6":   PN = "M6"  !CDS_PN = "M6";
"M7":   PN = "M7"  !CDS_PN = "M7";
"M8":   PN = "M8"  !CDS_PN = "M8";
"N5":   PN = "N5"  !CDS_PN = "N5";
"N6":   PN = "N6"  !CDS_PN = "N6";
"N7":   PN = "N7"  !CDS_PN = "N7";
"N8":   PN = "N8"  !CDS_PN = "N8";
BODY = "CONN112_10137002101LF","I76": #LOCATION = "J109" !CDS_LOCATION = "J109" &SEC = "2" #&CDS_SEC = "2";
"A1":   PN = "A1"  !CDS_PN = "A1";
"A2":   PN = "A2"  !CDS_PN = "A2";
"A3":   PN = "A3"  !CDS_PN = "A3";
"A4":   PN = "A4"  !CDS_PN = "A4";
"B1":   PN = "B1"  !CDS_PN = "B1";
"B2":   PN = "B2"  !CDS_PN = "B2";
"B3":   PN = "B3"  !CDS_PN = "B3";
"B4":   PN = "B4"  !CDS_PN = "B4";
"C1":   PN = "C1"  !CDS_PN = "C1";
"C2":   PN = "C2"  !CDS_PN = "C2";
"C3":   PN = "C3"  !CDS_PN = "C3";
"C4":   PN = "C4"  !CDS_PN = "C4";
"D1":   PN = "D1"  !CDS_PN = "D1";
"D2":   PN = "D2"  !CDS_PN = "D2";
"D3":   PN = "D3"  !CDS_PN = "D3";
"D4":   PN = "D4"  !CDS_PN = "D4";
"E1":   PN = "E1"  !CDS_PN = "E1";
"E2":   PN = "E2"  !CDS_PN = "E2";
"E3":   PN = "E3"  !CDS_PN = "E3";
"E4":   PN = "E4"  !CDS_PN = "E4";
"F1":   PN = "F1"  !CDS_PN = "F1";
"F2":   PN = "F2"  !CDS_PN = "F2";
"F3":   PN = "F3"  !CDS_PN = "F3";
"F4":   PN = "F4"  !CDS_PN = "F4";
"G1":   PN = "G1"  !CDS_PN = "G1";
"G2":   PN = "G2"  !CDS_PN = "G2";
"G3":   PN = "G3"  !CDS_PN = "G3";
"G4":   PN = "G4"  !CDS_PN = "G4";
"H1":   PN = "H1"  !CDS_PN = "H1";
"H2":   PN = "H2"  !CDS_PN = "H2";
"H3":   PN = "H3"  !CDS_PN = "H3";
"H4":   PN = "H4"  !CDS_PN = "H4";
"I1":   PN = "I1"  !CDS_PN = "I1";
"I2":   PN = "I2"  !CDS_PN = "I2";
"I3":   PN = "I3"  !CDS_PN = "I3";
"I4":   PN = "I4"  !CDS_PN = "I4";
"J1":   PN = "J1"  !CDS_PN = "J1";
"J2":   PN = "J2"  !CDS_PN = "J2";
"J3":   PN = "J3"  !CDS_PN = "J3";
"J4":   PN = "J4"  !CDS_PN = "J4";
"K1":   PN = "K1"  !CDS_PN = "K1";
"K2":   PN = "K2"  !CDS_PN = "K2";
"K3":   PN = "K3"  !CDS_PN = "K3";
"K4":   PN = "K4"  !CDS_PN = "K4";
"L1":   PN = "L1"  !CDS_PN = "L1";
"L2":   PN = "L2"  !CDS_PN = "L2";
"L3":   PN = "L3"  !CDS_PN = "L3";
"L4":   PN = "L4"  !CDS_PN = "L4";
"M1":   PN = "M1"  !CDS_PN = "M1";
"M2":   PN = "M2"  !CDS_PN = "M2";
"M3":   PN = "M3"  !CDS_PN = "M3";
"M4":   PN = "M4"  !CDS_PN = "M4";
"N1":   PN = "N1"  !CDS_PN = "N1";
"N2":   PN = "N2"  !CDS_PN = "N2";
"N3":   PN = "N3"  !CDS_PN = "N3";
"N4":   PN = "N4"  !CDS_PN = "N4";
DRAWING = "@t6g_mb_lib.t6g(sch_1):page318";
BODY = "CONN112_10137002101LF","I16": #LOCATION = "J110" !CDS_LOCATION = "J110" &SEC = "1" #&CDS_SEC = "1";
"A5":   PN = "A5"  !CDS_PN = "A5";
"A6":   PN = "A6"  !CDS_PN = "A6";
"A7":   PN = "A7"  !CDS_PN = "A7";
"A8":   PN = "A8"  !CDS_PN = "A8";
"B5":   PN = "B5"  !CDS_PN = "B5";
"B6":   PN = "B6"  !CDS_PN = "B6";
"B7":   PN = "B7"  !CDS_PN = "B7";
"B8":   PN = "B8"  !CDS_PN = "B8";
"C5":   PN = "C5"  !CDS_PN = "C5";
"C6":   PN = "C6"  !CDS_PN = "C6";
"C7":   PN = "C7"  !CDS_PN = "C7";
"C8":   PN = "C8"  !CDS_PN = "C8";
"D5":   PN = "D5"  !CDS_PN = "D5";
"D6":   PN = "D6"  !CDS_PN = "D6";
"D7":   PN = "D7"  !CDS_PN = "D7";
"D8":   PN = "D8"  !CDS_PN = "D8";
"E5":   PN = "E5"  !CDS_PN = "E5";
"E6":   PN = "E6"  !CDS_PN = "E6";
"E7":   PN = "E7"  !CDS_PN = "E7";
"E8":   PN = "E8"  !CDS_PN = "E8";
"F5":   PN = "F5"  !CDS_PN = "F5";
"F6":   PN = "F6"  !CDS_PN = "F6";
"F7":   PN = "F7"  !CDS_PN = "F7";
"F8":   PN = "F8"  !CDS_PN = "F8";
"G5":   PN = "G5"  !CDS_PN = "G5";
"G6":   PN = "G6"  !CDS_PN = "G6";
"G7":   PN = "G7"  !CDS_PN = "G7";
"G8":   PN = "G8"  !CDS_PN = "G8";
"H5":   PN = "H5"  !CDS_PN = "H5";
"H6":   PN = "H6"  !CDS_PN = "H6";
"H7":   PN = "H7"  !CDS_PN = "H7";
"H8":   PN = "H8"  !CDS_PN = "H8";
"I5":   PN = "I5"  !CDS_PN = "I5";
"I6":   PN = "I6"  !CDS_PN = "I6";
"I7":   PN = "I7"  !CDS_PN = "I7";
"I8":   PN = "I8"  !CDS_PN = "I8";
"J5":   PN = "J5"  !CDS_PN = "J5";
"J6":   PN = "J6"  !CDS_PN = "J6";
"J7":   PN = "J7"  !CDS_PN = "J7";
"J8":   PN = "J8"  !CDS_PN = "J8";
"K5":   PN = "K5"  !CDS_PN = "K5";
"K6":   PN = "K6"  !CDS_PN = "K6";
"K7":   PN = "K7"  !CDS_PN = "K7";
"K8":   PN = "K8"  !CDS_PN = "K8";
"L5":   PN = "L5"  !CDS_PN = "L5";
"L6":   PN = "L6"  !CDS_PN = "L6";
"L7":   PN = "L7"  !CDS_PN = "L7";
"L8":   PN = "L8"  !CDS_PN = "L8";
"M5":   PN = "M5"  !CDS_PN = "M5";
"M6":   PN = "M6"  !CDS_PN = "M6";
"M7":   PN = "M7"  !CDS_PN = "M7";
"M8":   PN = "M8"  !CDS_PN = "M8";
"N5":   PN = "N5"  !CDS_PN = "N5";
"N6":   PN = "N6"  !CDS_PN = "N6";
"N7":   PN = "N7"  !CDS_PN = "N7";
"N8":   PN = "N8"  !CDS_PN = "N8";
BODY = "CONN112_10137002101LF","I76": #LOCATION = "J110" !CDS_LOCATION = "J110" &SEC = "2" #&CDS_SEC = "2";
"A1":   PN = "A1"  !CDS_PN = "A1";
"A2":   PN = "A2"  !CDS_PN = "A2";
"A3":   PN = "A3"  !CDS_PN = "A3";
"A4":   PN = "A4"  !CDS_PN = "A4";
"B1":   PN = "B1"  !CDS_PN = "B1";
"B2":   PN = "B2"  !CDS_PN = "B2";
"B3":   PN = "B3"  !CDS_PN = "B3";
"B4":   PN = "B4"  !CDS_PN = "B4";
"C1":   PN = "C1"  !CDS_PN = "C1";
"C2":   PN = "C2"  !CDS_PN = "C2";
"C3":   PN = "C3"  !CDS_PN = "C3";
"C4":   PN = "C4"  !CDS_PN = "C4";
"D1":   PN = "D1"  !CDS_PN = "D1";
"D2":   PN = "D2"  !CDS_PN = "D2";
"D3":   PN = "D3"  !CDS_PN = "D3";
"D4":   PN = "D4"  !CDS_PN = "D4";
"E1":   PN = "E1"  !CDS_PN = "E1";
"E2":   PN = "E2"  !CDS_PN = "E2";
"E3":   PN = "E3"  !CDS_PN = "E3";
"E4":   PN = "E4"  !CDS_PN = "E4";
"F1":   PN = "F1"  !CDS_PN = "F1";
"F2":   PN = "F2"  !CDS_PN = "F2";
"F3":   PN = "F3"  !CDS_PN = "F3";
"F4":   PN = "F4"  !CDS_PN = "F4";
"G1":   PN = "G1"  !CDS_PN = "G1";
"G2":   PN = "G2"  !CDS_PN = "G2";
"G3":   PN = "G3"  !CDS_PN = "G3";
"G4":   PN = "G4"  !CDS_PN = "G4";
"H1":   PN = "H1"  !CDS_PN = "H1";
"H2":   PN = "H2"  !CDS_PN = "H2";
"H3":   PN = "H3"  !CDS_PN = "H3";
"H4":   PN = "H4"  !CDS_PN = "H4";
"I1":   PN = "I1"  !CDS_PN = "I1";
"I2":   PN = "I2"  !CDS_PN = "I2";
"I3":   PN = "I3"  !CDS_PN = "I3";
"I4":   PN = "I4"  !CDS_PN = "I4";
"J1":   PN = "J1"  !CDS_PN = "J1";
"J2":   PN = "J2"  !CDS_PN = "J2";
"J3":   PN = "J3"  !CDS_PN = "J3";
"J4":   PN = "J4"  !CDS_PN = "J4";
"K1":   PN = "K1"  !CDS_PN = "K1";
"K2":   PN = "K2"  !CDS_PN = "K2";
"K3":   PN = "K3"  !CDS_PN = "K3";
"K4":   PN = "K4"  !CDS_PN = "K4";
"L1":   PN = "L1"  !CDS_PN = "L1";
"L2":   PN = "L2"  !CDS_PN = "L2";
"L3":   PN = "L3"  !CDS_PN = "L3";
"L4":   PN = "L4"  !CDS_PN = "L4";
"M1":   PN = "M1"  !CDS_PN = "M1";
"M2":   PN = "M2"  !CDS_PN = "M2";
"M3":   PN = "M3"  !CDS_PN = "M3";
"M4":   PN = "M4"  !CDS_PN = "M4";
"N1":   PN = "N1"  !CDS_PN = "N1";
"N2":   PN = "N2"  !CDS_PN = "N2";
"N3":   PN = "N3"  !CDS_PN = "N3";
"N4":   PN = "N4"  !CDS_PN = "N4";
DRAWING = "@t6g_mb_lib.t6g(sch_1):page328";
BODY = "CONN112_10137002101LF","I38": #LOCATION = "J111" !CDS_LOCATION = "J111" &SEC = "1" #&CDS_SEC = "1";
"A5":   PN = "A5"  !CDS_PN = "A5";
"A6":   PN = "A6"  !CDS_PN = "A6";
"A7":   PN = "A7"  !CDS_PN = "A7";
"A8":   PN = "A8"  !CDS_PN = "A8";
"B5":   PN = "B5"  !CDS_PN = "B5";
"B6":   PN = "B6"  !CDS_PN = "B6";
"B7":   PN = "B7"  !CDS_PN = "B7";
"B8":   PN = "B8"  !CDS_PN = "B8";
"C5":   PN = "C5"  !CDS_PN = "C5";
"C6":   PN = "C6"  !CDS_PN = "C6";
"C7":   PN = "C7"  !CDS_PN = "C7";
"C8":   PN = "C8"  !CDS_PN = "C8";
"D5":   PN = "D5"  !CDS_PN = "D5";
"D6":   PN = "D6"  !CDS_PN = "D6";
"D7":   PN = "D7"  !CDS_PN = "D7";
"D8":   PN = "D8"  !CDS_PN = "D8";
"E5":   PN = "E5"  !CDS_PN = "E5";
"E6":   PN = "E6"  !CDS_PN = "E6";
"E7":   PN = "E7"  !CDS_PN = "E7";
"E8":   PN = "E8"  !CDS_PN = "E8";
"F5":   PN = "F5"  !CDS_PN = "F5";
"F6":   PN = "F6"  !CDS_PN = "F6";
"F7":   PN = "F7"  !CDS_PN = "F7";
"F8":   PN = "F8"  !CDS_PN = "F8";
"G5":   PN = "G5"  !CDS_PN = "G5";
"G6":   PN = "G6"  !CDS_PN = "G6";
"G7":   PN = "G7"  !CDS_PN = "G7";
"G8":   PN = "G8"  !CDS_PN = "G8";
"H5":   PN = "H5"  !CDS_PN = "H5";
"H6":   PN = "H6"  !CDS_PN = "H6";
"H7":   PN = "H7"  !CDS_PN = "H7";
"H8":   PN = "H8"  !CDS_PN = "H8";
"I5":   PN = "I5"  !CDS_PN = "I5";
"I6":   PN = "I6"  !CDS_PN = "I6";
"I7":   PN = "I7"  !CDS_PN = "I7";
"I8":   PN = "I8"  !CDS_PN = "I8";
"J5":   PN = "J5"  !CDS_PN = "J5";
"J6":   PN = "J6"  !CDS_PN = "J6";
"J7":   PN = "J7"  !CDS_PN = "J7";
"J8":   PN = "J8"  !CDS_PN = "J8";
"K5":   PN = "K5"  !CDS_PN = "K5";
"K6":   PN = "K6"  !CDS_PN = "K6";
"K7":   PN = "K7"  !CDS_PN = "K7";
"K8":   PN = "K8"  !CDS_PN = "K8";
"L5":   PN = "L5"  !CDS_PN = "L5";
"L6":   PN = "L6"  !CDS_PN = "L6";
"L7":   PN = "L7"  !CDS_PN = "L7";
"L8":   PN = "L8"  !CDS_PN = "L8";
"M5":   PN = "M5"  !CDS_PN = "M5";
"M6":   PN = "M6"  !CDS_PN = "M6";
"M7":   PN = "M7"  !CDS_PN = "M7";
"M8":   PN = "M8"  !CDS_PN = "M8";
"N5":   PN = "N5"  !CDS_PN = "N5";
"N6":   PN = "N6"  !CDS_PN = "N6";
"N7":   PN = "N7"  !CDS_PN = "N7";
"N8":   PN = "N8"  !CDS_PN = "N8";
BODY = "CONN112_10137002101LF","I76": #LOCATION = "J111" !CDS_LOCATION = "J111" &SEC = "2" #&CDS_SEC = "2";
"A1":   PN = "A1"  !CDS_PN = "A1";
"A2":   PN = "A2"  !CDS_PN = "A2";
"A3":   PN = "A3"  !CDS_PN = "A3";
"A4":   PN = "A4"  !CDS_PN = "A4";
"B1":   PN = "B1"  !CDS_PN = "B1";
"B2":   PN = "B2"  !CDS_PN = "B2";
"B3":   PN = "B3"  !CDS_PN = "B3";
"B4":   PN = "B4"  !CDS_PN = "B4";
"C1":   PN = "C1"  !CDS_PN = "C1";
"C2":   PN = "C2"  !CDS_PN = "C2";
"C3":   PN = "C3"  !CDS_PN = "C3";
"C4":   PN = "C4"  !CDS_PN = "C4";
"D1":   PN = "D1"  !CDS_PN = "D1";
"D2":   PN = "D2"  !CDS_PN = "D2";
"D3":   PN = "D3"  !CDS_PN = "D3";
"D4":   PN = "D4"  !CDS_PN = "D4";
"E1":   PN = "E1"  !CDS_PN = "E1";
"E2":   PN = "E2"  !CDS_PN = "E2";
"E3":   PN = "E3"  !CDS_PN = "E3";
"E4":   PN = "E4"  !CDS_PN = "E4";
"F1":   PN = "F1"  !CDS_PN = "F1";
"F2":   PN = "F2"  !CDS_PN = "F2";
"F3":   PN = "F3"  !CDS_PN = "F3";
"F4":   PN = "F4"  !CDS_PN = "F4";
"G1":   PN = "G1"  !CDS_PN = "G1";
"G2":   PN = "G2"  !CDS_PN = "G2";
"G3":   PN = "G3"  !CDS_PN = "G3";
"G4":   PN = "G4"  !CDS_PN = "G4";
"H1":   PN = "H1"  !CDS_PN = "H1";
"H2":   PN = "H2"  !CDS_PN = "H2";
"H3":   PN = "H3"  !CDS_PN = "H3";
"H4":   PN = "H4"  !CDS_PN = "H4";
"I1":   PN = "I1"  !CDS_PN = "I1";
"I2":   PN = "I2"  !CDS_PN = "I2";
"I3":   PN = "I3"  !CDS_PN = "I3";
"I4":   PN = "I4"  !CDS_PN = "I4";
"J1":   PN = "J1"  !CDS_PN = "J1";
"J2":   PN = "J2"  !CDS_PN = "J2";
"J3":   PN = "J3"  !CDS_PN = "J3";
"J4":   PN = "J4"  !CDS_PN = "J4";
"K1":   PN = "K1"  !CDS_PN = "K1";
"K2":   PN = "K2"  !CDS_PN = "K2";
"K3":   PN = "K3"  !CDS_PN = "K3";
"K4":   PN = "K4"  !CDS_PN = "K4";
"L1":   PN = "L1"  !CDS_PN = "L1";
"L2":   PN = "L2"  !CDS_PN = "L2";
"L3":   PN = "L3"  !CDS_PN = "L3";
"L4":   PN = "L4"  !CDS_PN = "L4";
"M1":   PN = "M1"  !CDS_PN = "M1";
"M2":   PN = "M2"  !CDS_PN = "M2";
"M3":   PN = "M3"  !CDS_PN = "M3";
"M4":   PN = "M4"  !CDS_PN = "M4";
"N1":   PN = "N1"  !CDS_PN = "N1";
"N2":   PN = "N2"  !CDS_PN = "N2";
"N3":   PN = "N3"  !CDS_PN = "N3";
"N4":   PN = "N4"  !CDS_PN = "N4";
DRAWING = "@t6g_mb_lib.t6g(sch_1):page329";
BODY = "CONN160_10131762101LF","I7": #LOCATION = "J112" !CDS_LOCATION = "J112" &SEC = "1" #&CDS_SEC = "1";
"A5":   PN = "A5"  !CDS_PN = "A5";
"A6":   PN = "A6"  !CDS_PN = "A6";
"A7":   PN = "A7"  !CDS_PN = "A7";
"A8":   PN = "A8"  !CDS_PN = "A8";
"B5":   PN = "B5"  !CDS_PN = "B5";
"B6":   PN = "B6"  !CDS_PN = "B6";
"B7":   PN = "B7"  !CDS_PN = "B7";
"B8":   PN = "B8"  !CDS_PN = "B8";
"C5":   PN = "C5"  !CDS_PN = "C5";
"C6":   PN = "C6"  !CDS_PN = "C6";
"C7":   PN = "C7"  !CDS_PN = "C7";
"C8":   PN = "C8"  !CDS_PN = "C8";
"D5":   PN = "D5"  !CDS_PN = "D5";
"D6":   PN = "D6"  !CDS_PN = "D6";
"D7":   PN = "D7"  !CDS_PN = "D7";
"D8":   PN = "D8"  !CDS_PN = "D8";
"E5":   PN = "E5"  !CDS_PN = "E5";
"E6":   PN = "E6"  !CDS_PN = "E6";
"E7":   PN = "E7"  !CDS_PN = "E7";
"E8":   PN = "E8"  !CDS_PN = "E8";
"F5":   PN = "F5"  !CDS_PN = "F5";
"F6":   PN = "F6"  !CDS_PN = "F6";
"F7":   PN = "F7"  !CDS_PN = "F7";
"F8":   PN = "F8"  !CDS_PN = "F8";
"G5":   PN = "G5"  !CDS_PN = "G5";
"G6":   PN = "G6"  !CDS_PN = "G6";
"G7":   PN = "G7"  !CDS_PN = "G7";
"G8":   PN = "G8"  !CDS_PN = "G8";
"H5":   PN = "H5"  !CDS_PN = "H5";
"H6":   PN = "H6"  !CDS_PN = "H6";
"H7":   PN = "H7"  !CDS_PN = "H7";
"H8":   PN = "H8"  !CDS_PN = "H8";
"I5":   PN = "I5"  !CDS_PN = "I5";
"I6":   PN = "I6"  !CDS_PN = "I6";
"I7":   PN = "I7"  !CDS_PN = "I7";
"I8":   PN = "I8"  !CDS_PN = "I8";
"J5":   PN = "J5"  !CDS_PN = "J5";
"J6":   PN = "J6"  !CDS_PN = "J6";
"J7":   PN = "J7"  !CDS_PN = "J7";
"J8":   PN = "J8"  !CDS_PN = "J8";
"K5":   PN = "K5"  !CDS_PN = "K5";
"K6":   PN = "K6"  !CDS_PN = "K6";
"K7":   PN = "K7"  !CDS_PN = "K7";
"K8":   PN = "K8"  !CDS_PN = "K8";
"L5":   PN = "L5"  !CDS_PN = "L5";
"L6":   PN = "L6"  !CDS_PN = "L6";
"L7":   PN = "L7"  !CDS_PN = "L7";
"L8":   PN = "L8"  !CDS_PN = "L8";
"M5":   PN = "M5"  !CDS_PN = "M5";
"M6":   PN = "M6"  !CDS_PN = "M6";
"M7":   PN = "M7"  !CDS_PN = "M7";
"M8":   PN = "M8"  !CDS_PN = "M8";
"N5":   PN = "N5"  !CDS_PN = "N5";
"N6":   PN = "N6"  !CDS_PN = "N6";
"N7":   PN = "N7"  !CDS_PN = "N7";
"N8":   PN = "N8"  !CDS_PN = "N8";
"O5":   PN = "O5"  !CDS_PN = "O5";
"O6":   PN = "O6"  !CDS_PN = "O6";
"O7":   PN = "O7"  !CDS_PN = "O7";
"O8":   PN = "O8"  !CDS_PN = "O8";
"P5":   PN = "P5"  !CDS_PN = "P5";
"P6":   PN = "P6"  !CDS_PN = "P6";
"P7":   PN = "P7"  !CDS_PN = "P7";
"P8":   PN = "P8"  !CDS_PN = "P8";
"Q5":   PN = "Q5"  !CDS_PN = "Q5";
"Q6":   PN = "Q6"  !CDS_PN = "Q6";
"Q7":   PN = "Q7"  !CDS_PN = "Q7";
"Q8":   PN = "Q8"  !CDS_PN = "Q8";
"R5":   PN = "R5"  !CDS_PN = "R5";
"R6":   PN = "R6"  !CDS_PN = "R6";
"R7":   PN = "R7"  !CDS_PN = "R7";
"R8":   PN = "R8"  !CDS_PN = "R8";
"S5":   PN = "S5"  !CDS_PN = "S5";
"S6":   PN = "S6"  !CDS_PN = "S6";
"S7":   PN = "S7"  !CDS_PN = "S7";
"S8":   PN = "S8"  !CDS_PN = "S8";
"T5":   PN = "T5"  !CDS_PN = "T5";
"T6":   PN = "T6"  !CDS_PN = "T6";
"T7":   PN = "T7"  !CDS_PN = "T7";
"T8":   PN = "T8"  !CDS_PN = "T8";
BODY = "CONN160_10131762101LF","I102": #LOCATION = "J112" !CDS_LOCATION = "J112" &SEC = "2" #&CDS_SEC = "2";
"A1":   PN = "A1"  !CDS_PN = "A1";
"A2":   PN = "A2"  !CDS_PN = "A2";
"A3":   PN = "A3"  !CDS_PN = "A3";
"A4":   PN = "A4"  !CDS_PN = "A4";
"B1":   PN = "B1"  !CDS_PN = "B1";
"B2":   PN = "B2"  !CDS_PN = "B2";
"B3":   PN = "B3"  !CDS_PN = "B3";
"B4":   PN = "B4"  !CDS_PN = "B4";
"C1":   PN = "C1"  !CDS_PN = "C1";
"C2":   PN = "C2"  !CDS_PN = "C2";
"C3":   PN = "C3"  !CDS_PN = "C3";
"C4":   PN = "C4"  !CDS_PN = "C4";
"D1":   PN = "D1"  !CDS_PN = "D1";
"D2":   PN = "D2"  !CDS_PN = "D2";
"D3":   PN = "D3"  !CDS_PN = "D3";
"D4":   PN = "D4"  !CDS_PN = "D4";
"E1":   PN = "E1"  !CDS_PN = "E1";
"E2":   PN = "E2"  !CDS_PN = "E2";
"E3":   PN = "E3"  !CDS_PN = "E3";
"E4":   PN = "E4"  !CDS_PN = "E4";
"F1":   PN = "F1"  !CDS_PN = "F1";
"F2":   PN = "F2"  !CDS_PN = "F2";
"F3":   PN = "F3"  !CDS_PN = "F3";
"F4":   PN = "F4"  !CDS_PN = "F4";
"G1":   PN = "G1"  !CDS_PN = "G1";
"G2":   PN = "G2"  !CDS_PN = "G2";
"G3":   PN = "G3"  !CDS_PN = "G3";
"G4":   PN = "G4"  !CDS_PN = "G4";
"H1":   PN = "H1"  !CDS_PN = "H1";
"H2":   PN = "H2"  !CDS_PN = "H2";
"H3":   PN = "H3"  !CDS_PN = "H3";
"H4":   PN = "H4"  !CDS_PN = "H4";
"I1":   PN = "I1"  !CDS_PN = "I1";
"I2":   PN = "I2"  !CDS_PN = "I2";
"I3":   PN = "I3"  !CDS_PN = "I3";
"I4":   PN = "I4"  !CDS_PN = "I4";
"J1":   PN = "J1"  !CDS_PN = "J1";
"J2":   PN = "J2"  !CDS_PN = "J2";
"J3":   PN = "J3"  !CDS_PN = "J3";
"J4":   PN = "J4"  !CDS_PN = "J4";
"K1":   PN = "K1"  !CDS_PN = "K1";
"K2":   PN = "K2"  !CDS_PN = "K2";
"K3":   PN = "K3"  !CDS_PN = "K3";
"K4":   PN = "K4"  !CDS_PN = "K4";
"L1":   PN = "L1"  !CDS_PN = "L1";
"L2":   PN = "L2"  !CDS_PN = "L2";
"L3":   PN = "L3"  !CDS_PN = "L3";
"L4":   PN = "L4"  !CDS_PN = "L4";
"M1":   PN = "M1"  !CDS_PN = "M1";
"M2":   PN = "M2"  !CDS_PN = "M2";
"M3":   PN = "M3"  !CDS_PN = "M3";
"M4":   PN = "M4"  !CDS_PN = "M4";
"N1":   PN = "N1"  !CDS_PN = "N1";
"N2":   PN = "N2"  !CDS_PN = "N2";
"N3":   PN = "N3"  !CDS_PN = "N3";
"N4":   PN = "N4"  !CDS_PN = "N4";
"O1":   PN = "O1"  !CDS_PN = "O1";
"O2":   PN = "O2"  !CDS_PN = "O2";
"O3":   PN = "O3"  !CDS_PN = "O3";
"O4":   PN = "O4"  !CDS_PN = "O4";
"P1":   PN = "P1"  !CDS_PN = "P1";
"P2":   PN = "P2"  !CDS_PN = "P2";
"P3":   PN = "P3"  !CDS_PN = "P3";
"P4":   PN = "P4"  !CDS_PN = "P4";
"Q1":   PN = "Q1"  !CDS_PN = "Q1";
"Q2":   PN = "Q2"  !CDS_PN = "Q2";
"Q3":   PN = "Q3"  !CDS_PN = "Q3";
"Q4":   PN = "Q4"  !CDS_PN = "Q4";
"R1":   PN = "R1"  !CDS_PN = "R1";
"R2":   PN = "R2"  !CDS_PN = "R2";
"R3":   PN = "R3"  !CDS_PN = "R3";
"R4":   PN = "R4"  !CDS_PN = "R4";
"S1":   PN = "S1"  !CDS_PN = "S1";
"S2":   PN = "S2"  !CDS_PN = "S2";
"S3":   PN = "S3"  !CDS_PN = "S3";
"S4":   PN = "S4"  !CDS_PN = "S4";
"T1":   PN = "T1"  !CDS_PN = "T1";
"T2":   PN = "T2"  !CDS_PN = "T2";
"T3":   PN = "T3"  !CDS_PN = "T3";
"T4":   PN = "T4"  !CDS_PN = "T4";
DRAWING = "@t6g_mb_lib.t6g(sch_1):page387";
BODY = "M24M02DRMN6TP","I3": #LOCATION = "U11" !CDS_LOCATION = "U11" &SEC = "1" #&CDS_SEC = "1";
"DU1":   PN = "1"  !CDS_PN = "1";
"DU2":   PN = "2"  !CDS_PN = "2";
"E2":   PN = "3"  !CDS_PN = "3";
"SCL":   PN = "6"  !CDS_PN = "6";
"SDA":   PN = "5"  !CDS_PN = "5";
"VCC":   PN = "8"  !CDS_PN = "8";
"VSS":   PN = "4"  !CDS_PN = "4";
"WC_N":   PN = "7"  !CDS_PN = "7";
BODY = "Q_RES","I6": #LOCATION = "R668" !CDS_LOCATION = "R668" &SEC = "1" #&CDS_SEC = "1";
"A":   PN = "1"  !CDS_PN = "1";
"B":   PN = "2"  !CDS_PN = "2";
BODY = "Q_RES","I7": #LOCATION = "R669" !CDS_LOCATION = "R669" &SEC = "1" #&CDS_SEC = "1";
"A":   PN = "1"  !CDS_PN = "1";
"B":   PN = "2"  !CDS_PN = "2";
BODY = "Q_CAP","I21": #LOCATION = "C7510" !CDS_LOCATION = "C7510" &SEC = "1" #&CDS_SEC = "1";
"A":   PN = "1"  !CDS_PN = "1";
"B":   PN = "2"  !CDS_PN = "2";
BODY = "Q_RES","I24": #LOCATION = "R6822" !CDS_LOCATION = "R6822" &SEC = "1" #&CDS_SEC = "1";
"A":   PN = "1"  !CDS_PN = "1";
"B":   PN = "2"  !CDS_PN = "2";
DRAWING = "@t6g_mb_lib.t6g(sch_1):page410";
BODY = "M24M02DRMN6TP","I5": #LOCATION = "U15" !CDS_LOCATION = "U15" &SEC = "1" #&CDS_SEC = "1";
"DU1":   PN = "1"  !CDS_PN = "1";
"DU2":   PN = "2"  !CDS_PN = "2";
"E2":   PN = "3"  !CDS_PN = "3";
"SCL":   PN = "6"  !CDS_PN = "6";
"SDA":   PN = "5"  !CDS_PN = "5";
"VCC":   PN = "8"  !CDS_PN = "8";
"VSS":   PN = "4"  !CDS_PN = "4";
"WC_N":   PN = "7"  !CDS_PN = "7";
BODY = "Q_RES","I6": #LOCATION = "R678" !CDS_LOCATION = "R678" &SEC = "1" #&CDS_SEC = "1";
"A":   PN = "1"  !CDS_PN = "1";
"B":   PN = "2"  !CDS_PN = "2";
BODY = "Q_RES","I7": #LOCATION = "R679" !CDS_LOCATION = "R679" &SEC = "1" #&CDS_SEC = "1";
"A":   PN = "1"  !CDS_PN = "1";
"B":   PN = "2"  !CDS_PN = "2";
BODY = "Q_RES","I20": #LOCATION = "R1044" !CDS_LOCATION = "R1044" &SEC = "1" #&CDS_SEC = "1";
"A":   PN = "1"  !CDS_PN = "1";
"B":   PN = "2"  !CDS_PN = "2";
BODY = "Q_CAP","I24": #LOCATION = "C664" !CDS_LOCATION = "C664" &SEC = "1" #&CDS_SEC = "1";
"A":   PN = "1"  !CDS_PN = "1";
"B":   PN = "2"  !CDS_PN = "2";
DRAWING = "@t6g_mb_lib.t6g(sch_1):page421";
BODY = "Q_RES","I3": #LOCATION = "R682" !CDS_LOCATION = "R682" &SEC = "1" #&CDS_SEC = "1";
"A":   PN = "1"  !CDS_PN = "1";
"B":   PN = "2"  !CDS_PN = "2";
BODY = "Q_RES","I4": #LOCATION = "R683" !CDS_LOCATION = "R683" &SEC = "1" #&CDS_SEC = "1";
"A":   PN = "1"  !CDS_PN = "1";
"B":   PN = "2"  !CDS_PN = "2";
BODY = "M24M02DRMN6TP","I5": #LOCATION = "U16" !CDS_LOCATION = "U16" &SEC = "1" #&CDS_SEC = "1";
"DU1":   PN = "1"  !CDS_PN = "1";
"DU2":   PN = "2"  !CDS_PN = "2";
"E2":   PN = "3"  !CDS_PN = "3";
"SCL":   PN = "6"  !CDS_PN = "6";
"SDA":   PN = "5"  !CDS_PN = "5";
"VCC":   PN = "8"  !CDS_PN = "8";
"VSS":   PN = "4"  !CDS_PN = "4";
"WC_N":   PN = "7"  !CDS_PN = "7";
BODY = "Q_RES","I18": #LOCATION = "R1085" !CDS_LOCATION = "R1085" &SEC = "1" #&CDS_SEC = "1";
"A":   PN = "1"  !CDS_PN = "1";
"B":   PN = "2"  !CDS_PN = "2";
BODY = "Q_CAP","I23": #LOCATION = "C989" !CDS_LOCATION = "C989" &SEC = "1" #&CDS_SEC = "1";
"A":   PN = "1"  !CDS_PN = "1";
"B":   PN = "2"  !CDS_PN = "2";
DRAWING = "@t6g_mb_lib.t6g(sch_1):page432";
BODY = "Q_RES","I3": #LOCATION = "R687" !CDS_LOCATION = "R687" &SEC = "1" #&CDS_SEC = "1";
"A":   PN = "1"  !CDS_PN = "1";
"B":   PN = "2"  !CDS_PN = "2";
BODY = "Q_RES","I4": #LOCATION = "R688" !CDS_LOCATION = "R688" &SEC = "1" #&CDS_SEC = "1";
"A":   PN = "1"  !CDS_PN = "1";
"B":   PN = "2"  !CDS_PN = "2";
BODY = "M24M02DRMN6TP","I5": #LOCATION = "U17" !CDS_LOCATION = "U17" &SEC = "1" #&CDS_SEC = "1";
"DU1":   PN = "1"  !CDS_PN = "1";
"DU2":   PN = "2"  !CDS_PN = "2";
"E2":   PN = "3"  !CDS_PN = "3";
"SCL":   PN = "6"  !CDS_PN = "6";
"SDA":   PN = "5"  !CDS_PN = "5";
"VCC":   PN = "8"  !CDS_PN = "8";
"VSS":   PN = "4"  !CDS_PN = "4";
"WC_N":   PN = "7"  !CDS_PN = "7";
BODY = "Q_RES","I18": #LOCATION = "R1127" !CDS_LOCATION = "R1127" &SEC = "1" #&CDS_SEC = "1";
"A":   PN = "1"  !CDS_PN = "1";
"B":   PN = "2"  !CDS_PN = "2";
BODY = "Q_CAP","I23": #LOCATION = "C1057" !CDS_LOCATION = "C1057" &SEC = "1" #&CDS_SEC = "1";
"A":   PN = "1"  !CDS_PN = "1";
"B":   PN = "2"  !CDS_PN = "2";
DRAWING = "@t6g_mb_lib.t6g(sch_1):page399";
BODY = "Q_RES","I3": #LOCATION = "R672" !CDS_LOCATION = "R672" &SEC = "1" #&CDS_SEC = "1";
"A":   PN = "1"  !CDS_PN = "1";
"B":   PN = "2"  !CDS_PN = "2";
BODY = "Q_RES","I4": #LOCATION = "R673" !CDS_LOCATION = "R673" &SEC = "1" #&CDS_SEC = "1";
"A":   PN = "1"  !CDS_PN = "1";
"B":   PN = "2"  !CDS_PN = "2";
BODY = "M24M02DRMN6TP","I5": #LOCATION = "U12" !CDS_LOCATION = "U12" &SEC = "1" #&CDS_SEC = "1";
"DU1":   PN = "1"  !CDS_PN = "1";
"DU2":   PN = "2"  !CDS_PN = "2";
"E2":   PN = "3"  !CDS_PN = "3";
"SCL":   PN = "6"  !CDS_PN = "6";
"SDA":   PN = "5"  !CDS_PN = "5";
"VCC":   PN = "8"  !CDS_PN = "8";
"VSS":   PN = "4"  !CDS_PN = "4";
"WC_N":   PN = "7"  !CDS_PN = "7";
BODY = "Q_CAP","I11": #LOCATION = "C7501" !CDS_LOCATION = "C7501" &SEC = "1" #&CDS_SEC = "1";
"A":   PN = "1"  !CDS_PN = "1";
"B":   PN = "2"  !CDS_PN = "2";
BODY = "Q_RES","I13": #LOCATION = "R6788" !CDS_LOCATION = "R6788" &SEC = "1" #&CDS_SEC = "1";
"A":   PN = "1"  !CDS_PN = "1";
"B":   PN = "2"  !CDS_PN = "2";
DRAWING = "@t6g_mb_lib.t6g(sch_1):page442";
BODY = "Q_RES","I3": #LOCATION = "R690" !CDS_LOCATION = "R690" &SEC = "1" #&CDS_SEC = "1";
"A":   PN = "1"  !CDS_PN = "1";
"B":   PN = "2"  !CDS_PN = "2";
BODY = "Q_RES","I4": #LOCATION = "R689" !CDS_LOCATION = "R689" &SEC = "1" #&CDS_SEC = "1";
"A":   PN = "1"  !CDS_PN = "1";
"B":   PN = "2"  !CDS_PN = "2";
BODY = "M24M02DRMN6TP","I5": #LOCATION = "U19" !CDS_LOCATION = "U19" &SEC = "1" #&CDS_SEC = "1";
"DU1":   PN = "1"  !CDS_PN = "1";
"DU2":   PN = "2"  !CDS_PN = "2";
"E2":   PN = "3"  !CDS_PN = "3";
"SCL":   PN = "6"  !CDS_PN = "6";
"SDA":   PN = "5"  !CDS_PN = "5";
"VCC":   PN = "8"  !CDS_PN = "8";
"VSS":   PN = "4"  !CDS_PN = "4";
"WC_N":   PN = "7"  !CDS_PN = "7";
BODY = "Q_RES","I19": #LOCATION = "R6789" !CDS_LOCATION = "R6789" &SEC = "1" #&CDS_SEC = "1";
"A":   PN = "1"  !CDS_PN = "1";
"B":   PN = "2"  !CDS_PN = "2";
BODY = "Q_CAP","I22": #LOCATION = "C7502" !CDS_LOCATION = "C7502" &SEC = "1" #&CDS_SEC = "1";
"A":   PN = "1"  !CDS_PN = "1";
"B":   PN = "2"  !CDS_PN = "2";
DRAWING = "@t6g_mb_lib.t6g(sch_1):page453";
BODY = "Q_RES","I3": #LOCATION = "R694" !CDS_LOCATION = "R694" &SEC = "1" #&CDS_SEC = "1";
"A":   PN = "1"  !CDS_PN = "1";
"B":   PN = "2"  !CDS_PN = "2";
BODY = "Q_RES","I4": #LOCATION = "R693" !CDS_LOCATION = "R693" &SEC = "1" #&CDS_SEC = "1";
"A":   PN = "1"  !CDS_PN = "1";
"B":   PN = "2"  !CDS_PN = "2";
BODY = "M24M02DRMN6TP","I5": #LOCATION = "U20" !CDS_LOCATION = "U20" &SEC = "1" #&CDS_SEC = "1";
"DU1":   PN = "1"  !CDS_PN = "1";
"DU2":   PN = "2"  !CDS_PN = "2";
"E2":   PN = "3"  !CDS_PN = "3";
"SCL":   PN = "6"  !CDS_PN = "6";
"SDA":   PN = "5"  !CDS_PN = "5";
"VCC":   PN = "8"  !CDS_PN = "8";
"VSS":   PN = "4"  !CDS_PN = "4";
"WC_N":   PN = "7"  !CDS_PN = "7";
BODY = "Q_RES","I19": #LOCATION = "R6790" !CDS_LOCATION = "R6790" &SEC = "1" #&CDS_SEC = "1";
"A":   PN = "1"  !CDS_PN = "1";
"B":   PN = "2"  !CDS_PN = "2";
BODY = "Q_CAP","I23": #LOCATION = "C7503" !CDS_LOCATION = "C7503" &SEC = "1" #&CDS_SEC = "1";
"A":   PN = "1"  !CDS_PN = "1";
"B":   PN = "2"  !CDS_PN = "2";
DRAWING = "@t6g_mb_lib.t6g(sch_1):page464";
BODY = "Q_RES","I4": #LOCATION = "R698" !CDS_LOCATION = "R698" &SEC = "1" #&CDS_SEC = "1";
"A":   PN = "1"  !CDS_PN = "1";
"B":   PN = "2"  !CDS_PN = "2";
BODY = "M24M02DRMN6TP","I5": #LOCATION = "U21" !CDS_LOCATION = "U21" &SEC = "1" #&CDS_SEC = "1";
"DU1":   PN = "1"  !CDS_PN = "1";
"DU2":   PN = "2"  !CDS_PN = "2";
"E2":   PN = "3"  !CDS_PN = "3";
"SCL":   PN = "6"  !CDS_PN = "6";
"SDA":   PN = "5"  !CDS_PN = "5";
"VCC":   PN = "8"  !CDS_PN = "8";
"VSS":   PN = "4"  !CDS_PN = "4";
"WC_N":   PN = "7"  !CDS_PN = "7";
BODY = "Q_CAP","I19": #LOCATION = "C7504" !CDS_LOCATION = "C7504" &SEC = "1" #&CDS_SEC = "1";
"A":   PN = "1"  !CDS_PN = "1";
"B":   PN = "2"  !CDS_PN = "2";
BODY = "Q_RES","I22": #LOCATION = "R6791" !CDS_LOCATION = "R6791" &SEC = "1" #&CDS_SEC = "1";
"A":   PN = "1"  !CDS_PN = "1";
"B":   PN = "2"  !CDS_PN = "2";
BODY = "Q_RES","I25": #LOCATION = "R697" !CDS_LOCATION = "R697" #SEC = "1" !CDS_SEC = "1";
"A":   PN = "1"  !CDS_PN = "1";
"B":   PN = "2"  !CDS_PN = "2";
DRAWING = "@t6g_mb_lib.t6g(sch_1):page398";
BODY = "Q_CAP","I4": #LOCATION = "C114" !CDS_LOCATION = "C114" &SEC = "1" #&CDS_SEC = "1";
"A":   PN = "1"  !CDS_PN = "1";
"B":   PN = "2"  !CDS_PN = "2";
BODY = "Q_CAP","I5": #LOCATION = "C117" !CDS_LOCATION = "C117" &SEC = "1" #&CDS_SEC = "1";
"A":   PN = "1"  !CDS_PN = "1";
"B":   PN = "2"  !CDS_PN = "2";
BODY = "Q_CAP","I7": #LOCATION = "C121" !CDS_LOCATION = "C121" &SEC = "1" #&CDS_SEC = "1";
"A":   PN = "1"  !CDS_PN = "1";
"B":   PN = "2"  !CDS_PN = "2";
BODY = "Q_CAP","I9": #LOCATION = "C126" !CDS_LOCATION = "C126" &SEC = "1" #&CDS_SEC = "1";
"A":   PN = "1"  !CDS_PN = "1";
"B":   PN = "2"  !CDS_PN = "2";
BODY = "Q_CAP","I12": #LOCATION = "C113" !CDS_LOCATION = "C113" &SEC = "1" #&CDS_SEC = "1";
"A":   PN = "1"  !CDS_PN = "1";
"B":   PN = "2"  !CDS_PN = "2";
BODY = "Q_CAP","I14": #LOCATION = "C118" !CDS_LOCATION = "C118" &SEC = "1" #&CDS_SEC = "1";
"A":   PN = "1"  !CDS_PN = "1";
"B":   PN = "2"  !CDS_PN = "2";
BODY = "Q_CAP","I15": #LOCATION = "C122" !CDS_LOCATION = "C122" &SEC = "1" #&CDS_SEC = "1";
"A":   PN = "1"  !CDS_PN = "1";
"B":   PN = "2"  !CDS_PN = "2";
BODY = "Q_CAP","I18": #LOCATION = "C123" !CDS_LOCATION = "C123" &SEC = "1" #&CDS_SEC = "1";
"A":   PN = "1"  !CDS_PN = "1";
"B":   PN = "2"  !CDS_PN = "2";
BODY = "Q_CAP","I19": #LOCATION = "C125" !CDS_LOCATION = "C125" &SEC = "1" #&CDS_SEC = "1";
"A":   PN = "1"  !CDS_PN = "1";
"B":   PN = "2"  !CDS_PN = "2";
BODY = "Q_CAP","I20": #LOCATION = "C119" !CDS_LOCATION = "C119" &SEC = "1" #&CDS_SEC = "1";
"A":   PN = "1"  !CDS_PN = "1";
"B":   PN = "2"  !CDS_PN = "2";
BODY = "Q_CAP","I21": #LOCATION = "C115" !CDS_LOCATION = "C115" &SEC = "1" #&CDS_SEC = "1";
"A":   PN = "1"  !CDS_PN = "1";
"B":   PN = "2"  !CDS_PN = "2";
BODY = "Q_INDUCTOR","I22": #LOCATION = "L3" !CDS_LOCATION = "L3" &SEC = "1" #&CDS_SEC = "1";
"1":   PN = "1"  !CDS_PN = "1";
"2":   PN = "2"  !CDS_PN = "2";
BODY = "Q_CAP","I23": #LOCATION = "C129" !CDS_LOCATION = "C129" &SEC = "1" #&CDS_SEC = "1";
"A":   PN = "1"  !CDS_PN = "1";
"B":   PN = "2"  !CDS_PN = "2";
BODY = "Q_CAP","I24": #LOCATION = "C131" !CDS_LOCATION = "C131" &SEC = "1" #&CDS_SEC = "1";
"A":   PN = "1"  !CDS_PN = "1";
"B":   PN = "2"  !CDS_PN = "2";
BODY = "Q_CAP","I25": #LOCATION = "C133" !CDS_LOCATION = "C133" &SEC = "1" #&CDS_SEC = "1";
"A":   PN = "1"  !CDS_PN = "1";
"B":   PN = "2"  !CDS_PN = "2";
BODY = "Q_CAP","I26": #LOCATION = "C134" !CDS_LOCATION = "C134" &SEC = "1" #&CDS_SEC = "1";
"A":   PN = "1"  !CDS_PN = "1";
"B":   PN = "2"  !CDS_PN = "2";
BODY = "Q_CAP","I27": #LOCATION = "C130" !CDS_LOCATION = "C130" &SEC = "1" #&CDS_SEC = "1";
"A":   PN = "1"  !CDS_PN = "1";
"B":   PN = "2"  !CDS_PN = "2";
BODY = "Q_RES","I32": #LOCATION = "R6702" !CDS_LOCATION = "R6702" #SEC = "1" !CDS_SEC = "1";
"A":   PN = "1"  !CDS_PN = "1";
"B":   PN = "2"  !CDS_PN = "2";
BODY = "Q_RES","I33": #LOCATION = "R6703" !CDS_LOCATION = "R6703" #SEC = "1" !CDS_SEC = "1";
"A":   PN = "1"  !CDS_PN = "1";
"B":   PN = "2"  !CDS_PN = "2";
BODY = "Q_CAP","I34": #LOCATION = "C229" !CDS_LOCATION = "C229" &SEC = "1" #&CDS_SEC = "1";
"A":   PN = "1"  !CDS_PN = "1";
"B":   PN = "2"  !CDS_PN = "2";
BODY = "Q_CAP","I35": #LOCATION = "C244" !CDS_LOCATION = "C244" &SEC = "1" #&CDS_SEC = "1";
"A":   PN = "1"  !CDS_PN = "1";
"B":   PN = "2"  !CDS_PN = "2";
BODY = "Q_CAP","I36": #LOCATION = "C261" !CDS_LOCATION = "C261" &SEC = "1" #&CDS_SEC = "1";
"A":   PN = "1"  !CDS_PN = "1";
"B":   PN = "2"  !CDS_PN = "2";
BODY = "Q_CAP","I39": #LOCATION = "C256" !CDS_LOCATION = "C256" &SEC = "1" #&CDS_SEC = "1";
"A":   PN = "1"  !CDS_PN = "1";
"B":   PN = "2"  !CDS_PN = "2";
BODY = "Q_CAP","I40": #LOCATION = "C185" !CDS_LOCATION = "C185" &SEC = "1" #&CDS_SEC = "1";
"A":   PN = "1"  !CDS_PN = "1";
"B":   PN = "2"  !CDS_PN = "2";
BODY = "Q_CAP","I42": #LOCATION = "C222" !CDS_LOCATION = "C222" &SEC = "1" #&CDS_SEC = "1";
"A":   PN = "1"  !CDS_PN = "1";
"B":   PN = "2"  !CDS_PN = "2";
BODY = "Q_CAP","I44": #LOCATION = "C220" !CDS_LOCATION = "C220" &SEC = "1" #&CDS_SEC = "1";
"A":   PN = "1"  !CDS_PN = "1";
"B":   PN = "2"  !CDS_PN = "2";
BODY = "Q_CAP","I46": #LOCATION = "C135" !CDS_LOCATION = "C135" &SEC = "1" #&CDS_SEC = "1";
"A":   PN = "1"  !CDS_PN = "1";
"B":   PN = "2"  !CDS_PN = "2";
BODY = "Q_CAP","I47": #LOCATION = "C243" !CDS_LOCATION = "C243" &SEC = "1" #&CDS_SEC = "1";
"A":   PN = "1"  !CDS_PN = "1";
"B":   PN = "2"  !CDS_PN = "2";
BODY = "Q_CAP","I48": #LOCATION = "C138" !CDS_LOCATION = "C138" &SEC = "1" #&CDS_SEC = "1";
"A":   PN = "1"  !CDS_PN = "1";
"B":   PN = "2"  !CDS_PN = "2";
BODY = "Q_CAP","I49": #LOCATION = "C257" !CDS_LOCATION = "C257" &SEC = "1" #&CDS_SEC = "1";
"A":   PN = "1"  !CDS_PN = "1";
"B":   PN = "2"  !CDS_PN = "2";
BODY = "Q_CAP","I50": #LOCATION = "C221" !CDS_LOCATION = "C221" &SEC = "1" #&CDS_SEC = "1";
"A":   PN = "1"  !CDS_PN = "1";
"B":   PN = "2"  !CDS_PN = "2";
BODY = "Q_CAP","I51": #LOCATION = "C258" !CDS_LOCATION = "C258" &SEC = "1" #&CDS_SEC = "1";
"A":   PN = "1"  !CDS_PN = "1";
"B":   PN = "2"  !CDS_PN = "2";
BODY = "Q_CAP","I52": #LOCATION = "C225" !CDS_LOCATION = "C225" &SEC = "1" #&CDS_SEC = "1";
"A":   PN = "1"  !CDS_PN = "1";
"B":   PN = "2"  !CDS_PN = "2";
BODY = "Q_CAP","I53": #LOCATION = "C240" !CDS_LOCATION = "C240" &SEC = "1" #&CDS_SEC = "1";
"A":   PN = "1"  !CDS_PN = "1";
"B":   PN = "2"  !CDS_PN = "2";
BODY = "Q_CAP","I54": #LOCATION = "C284" !CDS_LOCATION = "C284" &SEC = "1" #&CDS_SEC = "1";
"A":   PN = "1"  !CDS_PN = "1";
"B":   PN = "2"  !CDS_PN = "2";
BODY = "Q_CAP","I55": #LOCATION = "C188" !CDS_LOCATION = "C188" &SEC = "1" #&CDS_SEC = "1";
"A":   PN = "1"  !CDS_PN = "1";
"B":   PN = "2"  !CDS_PN = "2";
BODY = "Q_CAP","I56": #LOCATION = "C265" !CDS_LOCATION = "C265" &SEC = "1" #&CDS_SEC = "1";
"A":   PN = "1"  !CDS_PN = "1";
"B":   PN = "2"  !CDS_PN = "2";
BODY = "Q_CAP","I57": #LOCATION = "C227" !CDS_LOCATION = "C227" &SEC = "1" #&CDS_SEC = "1";
"A":   PN = "1"  !CDS_PN = "1";
"B":   PN = "2"  !CDS_PN = "2";
BODY = "Q_CAP","I58": #LOCATION = "C186" !CDS_LOCATION = "C186" &SEC = "1" #&CDS_SEC = "1";
"A":   PN = "1"  !CDS_PN = "1";
"B":   PN = "2"  !CDS_PN = "2";
BODY = "Q_CAP","I59": #LOCATION = "C280" !CDS_LOCATION = "C280" &SEC = "1" #&CDS_SEC = "1";
"A":   PN = "1"  !CDS_PN = "1";
"B":   PN = "2"  !CDS_PN = "2";
BODY = "Q_CAP","I62": #LOCATION = "C190" !CDS_LOCATION = "C190" &SEC = "1" #&CDS_SEC = "1";
"A":   PN = "1"  !CDS_PN = "1";
"B":   PN = "2"  !CDS_PN = "2";
BODY = "Q_CAP","I63": #LOCATION = "C285" !CDS_LOCATION = "C285" &SEC = "1" #&CDS_SEC = "1";
"A":   PN = "1"  !CDS_PN = "1";
"B":   PN = "2"  !CDS_PN = "2";
BODY = "Q_CAP","I64": #LOCATION = "C255" !CDS_LOCATION = "C255" &SEC = "1" #&CDS_SEC = "1";
"A":   PN = "1"  !CDS_PN = "1";
"B":   PN = "2"  !CDS_PN = "2";
BODY = "Q_CAP","I65": #LOCATION = "C262" !CDS_LOCATION = "C262" &SEC = "1" #&CDS_SEC = "1";
"A":   PN = "1"  !CDS_PN = "1";
"B":   PN = "2"  !CDS_PN = "2";
BODY = "Q_CAP","I66": #LOCATION = "C259" !CDS_LOCATION = "C259" &SEC = "1" #&CDS_SEC = "1";
"A":   PN = "1"  !CDS_PN = "1";
"B":   PN = "2"  !CDS_PN = "2";
BODY = "Q_CAP","I67": #LOCATION = "C254" !CDS_LOCATION = "C254" &SEC = "1" #&CDS_SEC = "1";
"A":   PN = "1"  !CDS_PN = "1";
"B":   PN = "2"  !CDS_PN = "2";
BODY = "Q_CAP","I68": #LOCATION = "C286" !CDS_LOCATION = "C286" &SEC = "1" #&CDS_SEC = "1";
"A":   PN = "1"  !CDS_PN = "1";
"B":   PN = "2"  !CDS_PN = "2";
BODY = "Q_CAP","I70": #LOCATION = "C250" !CDS_LOCATION = "C250" &SEC = "1" #&CDS_SEC = "1";
"A":   PN = "1"  !CDS_PN = "1";
"B":   PN = "2"  !CDS_PN = "2";
BODY = "Q_CAP","I71": #LOCATION = "C269" !CDS_LOCATION = "C269" &SEC = "1" #&CDS_SEC = "1";
"A":   PN = "1"  !CDS_PN = "1";
"B":   PN = "2"  !CDS_PN = "2";
BODY = "Q_CAP","I72": #LOCATION = "C241" !CDS_LOCATION = "C241" &SEC = "1" #&CDS_SEC = "1";
"A":   PN = "1"  !CDS_PN = "1";
"B":   PN = "2"  !CDS_PN = "2";
BODY = "Q_CAP","I73": #LOCATION = "C247" !CDS_LOCATION = "C247" &SEC = "1" #&CDS_SEC = "1";
"A":   PN = "1"  !CDS_PN = "1";
"B":   PN = "2"  !CDS_PN = "2";
BODY = "Q_INDUCTOR","I74": #LOCATION = "L4" !CDS_LOCATION = "L4" &SEC = "1" #&CDS_SEC = "1";
"1":   PN = "1"  !CDS_PN = "1";
"2":   PN = "2"  !CDS_PN = "2";
BODY = "Q_CAP","I75": #LOCATION = "C189" !CDS_LOCATION = "C189" &SEC = "1" #&CDS_SEC = "1";
"A":   PN = "1"  !CDS_PN = "1";
"B":   PN = "2"  !CDS_PN = "2";
BODY = "Q_CAP","I76": #LOCATION = "C266" !CDS_LOCATION = "C266" &SEC = "1" #&CDS_SEC = "1";
"A":   PN = "1"  !CDS_PN = "1";
"B":   PN = "2"  !CDS_PN = "2";
BODY = "Q_CAP","I77": #LOCATION = "C139" !CDS_LOCATION = "C139" &SEC = "1" #&CDS_SEC = "1";
"A":   PN = "1"  !CDS_PN = "1";
"B":   PN = "2"  !CDS_PN = "2";
BODY = "Q_CAP","I78": #LOCATION = "C137" !CDS_LOCATION = "C137" &SEC = "1" #&CDS_SEC = "1";
"A":   PN = "1"  !CDS_PN = "1";
"B":   PN = "2"  !CDS_PN = "2";
BODY = "Q_CAP","I80": #LOCATION = "C282" !CDS_LOCATION = "C282" &SEC = "1" #&CDS_SEC = "1";
"A":   PN = "1"  !CDS_PN = "1";
"B":   PN = "2"  !CDS_PN = "2";
BODY = "Q_CAP","I81": #LOCATION = "C264" !CDS_LOCATION = "C264" &SEC = "1" #&CDS_SEC = "1";
"A":   PN = "1"  !CDS_PN = "1";
"B":   PN = "2"  !CDS_PN = "2";
BODY = "Q_CAP","I82": #LOCATION = "C141" !CDS_LOCATION = "C141" &SEC = "1" #&CDS_SEC = "1";
"A":   PN = "1"  !CDS_PN = "1";
"B":   PN = "2"  !CDS_PN = "2";
BODY = "Q_CAP","I83": #LOCATION = "C192" !CDS_LOCATION = "C192" &SEC = "1" #&CDS_SEC = "1";
"A":   PN = "1"  !CDS_PN = "1";
"B":   PN = "2"  !CDS_PN = "2";
BODY = "Q_CAP","I84": #LOCATION = "C260" !CDS_LOCATION = "C260" &SEC = "1" #&CDS_SEC = "1";
"A":   PN = "1"  !CDS_PN = "1";
"B":   PN = "2"  !CDS_PN = "2";
BODY = "Q_CAP","I85": #LOCATION = "C184" !CDS_LOCATION = "C184" &SEC = "1" #&CDS_SEC = "1";
"A":   PN = "1"  !CDS_PN = "1";
"B":   PN = "2"  !CDS_PN = "2";
BODY = "Q_CAP","I86": #LOCATION = "C253" !CDS_LOCATION = "C253" &SEC = "1" #&CDS_SEC = "1";
"A":   PN = "1"  !CDS_PN = "1";
"B":   PN = "2"  !CDS_PN = "2";
BODY = "Q_CAP","I87": #LOCATION = "C228" !CDS_LOCATION = "C228" &SEC = "1" #&CDS_SEC = "1";
"A":   PN = "1"  !CDS_PN = "1";
"B":   PN = "2"  !CDS_PN = "2";
BODY = "Q_CAP","I92": #LOCATION = "C198" !CDS_LOCATION = "C198" &SEC = "1" #&CDS_SEC = "1";
"A":   PN = "1"  !CDS_PN = "1";
"B":   PN = "2"  !CDS_PN = "2";
BODY = "Q_CAP","I93": #LOCATION = "C191" !CDS_LOCATION = "C191" &SEC = "1" #&CDS_SEC = "1";
"A":   PN = "1"  !CDS_PN = "1";
"B":   PN = "2"  !CDS_PN = "2";
BODY = "Q_RES","I95": #LOCATION = "R6705" !CDS_LOCATION = "R6705" &SEC = "1" #&CDS_SEC = "1";
"A":   PN = "1"  !CDS_PN = "1";
"B":   PN = "2"  !CDS_PN = "2";
BODY = "Q_RES","I96": #LOCATION = "R6704" !CDS_LOCATION = "R6704" &SEC = "1" #&CDS_SEC = "1";
"A":   PN = "1"  !CDS_PN = "1";
"B":   PN = "2"  !CDS_PN = "2";
BODY = "Q_INDUCTOR","I97": #LOCATION = "L27" !CDS_LOCATION = "L27" &SEC = "1" #&CDS_SEC = "1";
"1":   PN = "1"  !CDS_PN = "1";
"2":   PN = "2"  !CDS_PN = "2";
BODY = "Q_RES","I98": #LOCATION = "R6701" !CDS_LOCATION = "R6701" &SEC = "1" #&CDS_SEC = "1";
"A":   PN = "1"  !CDS_PN = "1";
"B":   PN = "2"  !CDS_PN = "2";
BODY = "Q_CAP","I99": #LOCATION = "C187" !CDS_LOCATION = "C187" &SEC = "1" #&CDS_SEC = "1";
"A":   PN = "1"  !CDS_PN = "1";
"B":   PN = "2"  !CDS_PN = "2";
BODY = "Q_CAP","I100": #LOCATION = "C201" !CDS_LOCATION = "C201" &SEC = "1" #&CDS_SEC = "1";
"A":   PN = "1"  !CDS_PN = "1";
"B":   PN = "2"  !CDS_PN = "2";
BODY = "Q_CAP","I101": #LOCATION = "C281" !CDS_LOCATION = "C281" &SEC = "1" #&CDS_SEC = "1";
"A":   PN = "1"  !CDS_PN = "1";
"B":   PN = "2"  !CDS_PN = "2";
BODY = "Q_CAP","I102": #LOCATION = "C283" !CDS_LOCATION = "C283" &SEC = "1" #&CDS_SEC = "1";
"A":   PN = "1"  !CDS_PN = "1";
"B":   PN = "2"  !CDS_PN = "2";
BODY = "Q_CAPP","I103": #LOCATION = "C7020" !CDS_LOCATION = "C7020" &SEC = "1" #&CDS_SEC = "1";
"A":   PN = "1"  !CDS_PN = "1";
"B":   PN = "2"  !CDS_PN = "2";
BODY = "Q_CAPP","I104": #LOCATION = "C7021" !CDS_LOCATION = "C7021" &SEC = "1" #&CDS_SEC = "1";
"A":   PN = "1"  !CDS_PN = "1";
"B":   PN = "2"  !CDS_PN = "2";
BODY = "Q_CAP","I105": #LOCATION = "C7022" !CDS_LOCATION = "C7022" &SEC = "1" #&CDS_SEC = "1";
"A":   PN = "1"  !CDS_PN = "1";
"B":   PN = "2"  !CDS_PN = "2";
DRAWING = "@t6g_mb_lib.t6g(sch_1):page469";
BODY = "Q_CAP","I4": #LOCATION = "PC6500" !CDS_LOCATION = "PC6500" &SEC = "1" #&CDS_SEC = "1";
"A":   PN = "1"  !CDS_PN = "1";
"B":   PN = "2"  !CDS_PN = "2";
BODY = "Q_CAP","I5": #LOCATION = "C6757" !CDS_LOCATION = "C6757" &SEC = "1" #&CDS_SEC = "1";
"A":   PN = "1"  !CDS_PN = "1";
"B":   PN = "2"  !CDS_PN = "2";
BODY = "Q_CAPP","I6": #LOCATION = "PC6800" !CDS_LOCATION = "PC6800" &SEC = "1" #&CDS_SEC = "1";
"A":   PN = "1"  !CDS_PN = "1";
"B":   PN = "2"  !CDS_PN = "2";
BODY = "Q_CAP","I7": #LOCATION = "PC6802" !CDS_LOCATION = "PC6802" &SEC = "1" #&CDS_SEC = "1";
"A":   PN = "1"  !CDS_PN = "1";
"B":   PN = "2"  !CDS_PN = "2";
BODY = "Q_INDUCTOR","I9": #LOCATION = "PL6500" !CDS_LOCATION = "PL6500" &SEC = "1" #&CDS_SEC = "1";
"1":   PN = "1"  !CDS_PN = "1";
"2":   PN = "2"  !CDS_PN = "2";
BODY = "Q_CAP","I12": #LOCATION = "PC6506" !CDS_LOCATION = "PC6506" #SEC = "1" !CDS_SEC = "1";
"A":   PN = "1"  !CDS_PN = "1";
"B":   PN = "2"  !CDS_PN = "2";
BODY = "Q_RES","I13": #LOCATION = "PR6501" !CDS_LOCATION = "PR6501" &SEC = "1" #&CDS_SEC = "1";
"A":   PN = "1"  !CDS_PN = "1";
"B":   PN = "2"  !CDS_PN = "2";
BODY = "Q_CAP","I16": #LOCATION = "PC6501" !CDS_LOCATION = "PC6501" &SEC = "1" #&CDS_SEC = "1";
"A":   PN = "1"  !CDS_PN = "1";
"B":   PN = "2"  !CDS_PN = "2";
BODY = "Q_CAP","I17": #LOCATION = "PC6502" !CDS_LOCATION = "PC6502" &SEC = "1" #&CDS_SEC = "1";
"A":   PN = "1"  !CDS_PN = "1";
"B":   PN = "2"  !CDS_PN = "2";
BODY = "Q_CAP","I18": #LOCATION = "PC6503" !CDS_LOCATION = "PC6503" &SEC = "1" #&CDS_SEC = "1";
"A":   PN = "1"  !CDS_PN = "1";
"B":   PN = "2"  !CDS_PN = "2";
BODY = "Q_RES","I20": #LOCATION = "PR6502" !CDS_LOCATION = "PR6502" #SEC = "1" !CDS_SEC = "1";
"A":   PN = "1"  !CDS_PN = "1";
"B":   PN = "2"  !CDS_PN = "2";
BODY = "Q_RES","I21": #LOCATION = "PR6500" !CDS_LOCATION = "PR6500" &SEC = "1" #&CDS_SEC = "1";
"A":   PN = "1"  !CDS_PN = "1";
"B":   PN = "2"  !CDS_PN = "2";
BODY = "Q_CAP","I22": #LOCATION = "PC6504" !CDS_LOCATION = "PC6504" &SEC = "1" #&CDS_SEC = "1";
"A":   PN = "1"  !CDS_PN = "1";
"B":   PN = "2"  !CDS_PN = "2";
BODY = "Q_CAP","I23": #LOCATION = "PC6505" !CDS_LOCATION = "PC6505" &SEC = "1" #&CDS_SEC = "1";
"A":   PN = "1"  !CDS_PN = "1";
"B":   PN = "2"  !CDS_PN = "2";
BODY = "Q_CAP","I26": #LOCATION = "PC6518" !CDS_LOCATION = "PC6518" &SEC = "1" #&CDS_SEC = "1";
"A":   PN = "1"  !CDS_PN = "1";
"B":   PN = "2"  !CDS_PN = "2";
BODY = "Q_RES","I28": #LOCATION = "R6505" !CDS_LOCATION = "R6505" #SEC = "1" !CDS_SEC = "1";
"A":   PN = "1"  !CDS_PN = "1";
"B":   PN = "2"  !CDS_PN = "2";
BODY = "Q_RES","I29": #LOCATION = "PR6800" !CDS_LOCATION = "PR6800" &SEC = "1" #&CDS_SEC = "1";
"A":   PN = "1"  !CDS_PN = "1";
"B":   PN = "2"  !CDS_PN = "2";
BODY = "Q_CAP","I32": #LOCATION = "PC6507" !CDS_LOCATION = "PC6507" #SEC = "1" !CDS_SEC = "1";
"A":   PN = "1"  !CDS_PN = "1";
"B":   PN = "2"  !CDS_PN = "2";
BODY = "Q_RES","I33": #LOCATION = "PR6507" !CDS_LOCATION = "PR6507" &SEC = "1" #&CDS_SEC = "1";
"A":   PN = "1"  !CDS_PN = "1";
"B":   PN = "2"  !CDS_PN = "2";
BODY = "Q_CAP","I34": #LOCATION = "PC6515" !CDS_LOCATION = "PC6515" &SEC = "1" #&CDS_SEC = "1";
"A":   PN = "1"  !CDS_PN = "1";
"B":   PN = "2"  !CDS_PN = "2";
BODY = "Q_RES","I35": #LOCATION = "PR6505" !CDS_LOCATION = "PR6505" &SEC = "1" #&CDS_SEC = "1";
"A":   PN = "1"  !CDS_PN = "1";
"B":   PN = "2"  !CDS_PN = "2";
BODY = "Q_INDUCTOR","I36": #LOCATION = "PL6501" !CDS_LOCATION = "PL6501" &SEC = "1" #&CDS_SEC = "1";
"1":   PN = "1"  !CDS_PN = "1";
"2":   PN = "2"  !CDS_PN = "2";
BODY = "Q_RES","I37": #LOCATION = "R6506" !CDS_LOCATION = "R6506" &SEC = "1" #&CDS_SEC = "1";
"A":   PN = "1"  !CDS_PN = "1";
"B":   PN = "2"  !CDS_PN = "2";
BODY = "Q_CAP","I38": #LOCATION = "PC6508" !CDS_LOCATION = "PC6508" &SEC = "1" #&CDS_SEC = "1";
"A":   PN = "1"  !CDS_PN = "1";
"B":   PN = "2"  !CDS_PN = "2";
BODY = "Q_CAP","I39": #LOCATION = "PC6509" !CDS_LOCATION = "PC6509" &SEC = "1" #&CDS_SEC = "1";
"A":   PN = "1"  !CDS_PN = "1";
"B":   PN = "2"  !CDS_PN = "2";
BODY = "Q_CAP","I40": #LOCATION = "PC6510" !CDS_LOCATION = "PC6510" &SEC = "1" #&CDS_SEC = "1";
"A":   PN = "1"  !CDS_PN = "1";
"B":   PN = "2"  !CDS_PN = "2";
BODY = "Q_CAP","I42": #LOCATION = "C6758" !CDS_LOCATION = "C6758" &SEC = "1" #&CDS_SEC = "1";
"A":   PN = "1"  !CDS_PN = "1";
"B":   PN = "2"  !CDS_PN = "2";
BODY = "Q_CAP","I44": #LOCATION = "PC6511" !CDS_LOCATION = "PC6511" &SEC = "1" #&CDS_SEC = "1";
"A":   PN = "1"  !CDS_PN = "1";
"B":   PN = "2"  !CDS_PN = "2";
BODY = "Q_CAPP","I46": #LOCATION = "PC6513" !CDS_LOCATION = "PC6513" &SEC = "1" #&CDS_SEC = "1";
"A":   PN = "1"  !CDS_PN = "1";
"B":   PN = "2"  !CDS_PN = "2";
BODY = "Q_CAPP","I48": #LOCATION = "PC6805" !CDS_LOCATION = "PC6805" &SEC = "1" #&CDS_SEC = "1";
"A":   PN = "1"  !CDS_PN = "1";
"B":   PN = "2"  !CDS_PN = "2";
BODY = "Q_CAP","I49": #LOCATION = "PC6514" !CDS_LOCATION = "PC6514" #SEC = "1" !CDS_SEC = "1";
"A":   PN = "1"  !CDS_PN = "1";
"B":   PN = "2"  !CDS_PN = "2";
BODY = "MPQ8633BGLEC838Z","I51": #LOCATION = "PU6500" !CDS_LOCATION = "PU6500" &SEC = "1" #&CDS_SEC = "1";
"AGND":   PN = "2"  !CDS_PN = "2";
"BST":   PN = "1"  !CDS_PN = "1";
"CS":   PN = "3"  !CDS_PN = "3";
"EN":   PN = "8"  !CDS_PN = "8";
"FB":   PN = "7"  !CDS_PN = "7";
"MODE":   PN = "4"  !CDS_PN = "4";
"PGND":   PN = "11_18"  !CDS_PN = "11_18";
"PGOOD":   PN = "9"  !CDS_PN = "9";
"RGND":   PN = "6"  !CDS_PN = "6";
"SW":   PN = "20"  !CDS_PN = "20";
"TRK_REF":   PN = "5"  !CDS_PN = "5";
"VCC":   PN = "19"  !CDS_PN = "19";
"VIN1":   PN = "10"  !CDS_PN = "10";
"VIN2":   PN = "21"  !CDS_PN = "21";
BODY = "Q_CAP","I52": #LOCATION = "PC6512" !CDS_LOCATION = "PC6512" &SEC = "1" #&CDS_SEC = "1";
"A":   PN = "1"  !CDS_PN = "1";
"B":   PN = "2"  !CDS_PN = "2";
BODY = "Q_CAP","I56": #LOCATION = "PC6902" !CDS_LOCATION = "PC6902" &SEC = "1" #&CDS_SEC = "1";
"A":   PN = "1"  !CDS_PN = "1";
"B":   PN = "2"  !CDS_PN = "2";
BODY = "Q_CAP","I57": #LOCATION = "PC6901" !CDS_LOCATION = "PC6901" &SEC = "1" #&CDS_SEC = "1";
"A":   PN = "1"  !CDS_PN = "1";
"B":   PN = "2"  !CDS_PN = "2";
BODY = "Q_CAP","I58": #LOCATION = "PC6900" !CDS_LOCATION = "PC6900" &SEC = "1" #&CDS_SEC = "1";
"A":   PN = "1"  !CDS_PN = "1";
"B":   PN = "2"  !CDS_PN = "2";
DRAWING = "@t6g_mb_lib.t6g(sch_1):page470";
BODY = "Q_CAP","I3": #LOCATION = "PC6519" !CDS_LOCATION = "PC6519" &SEC = "1" #&CDS_SEC = "1";
"A":   PN = "1"  !CDS_PN = "1";
"B":   PN = "2"  !CDS_PN = "2";
BODY = "Q_CAP","I5": #LOCATION = "C105" !CDS_LOCATION = "C105" &SEC = "1" #&CDS_SEC = "1";
"A":   PN = "1"  !CDS_PN = "1";
"B":   PN = "2"  !CDS_PN = "2";
BODY = "Q_CAPP","I6": #LOCATION = "PC6801" !CDS_LOCATION = "PC6801" &SEC = "1" #&CDS_SEC = "1";
"A":   PN = "1"  !CDS_PN = "1";
"B":   PN = "2"  !CDS_PN = "2";
BODY = "Q_CAP","I7": #LOCATION = "PC6803" !CDS_LOCATION = "PC6803" &SEC = "1" #&CDS_SEC = "1";
"A":   PN = "1"  !CDS_PN = "1";
"B":   PN = "2"  !CDS_PN = "2";
BODY = "Q_INDUCTOR","I9": #LOCATION = "PL6503" !CDS_LOCATION = "PL6503" &SEC = "1" #&CDS_SEC = "1";
"1":   PN = "1"  !CDS_PN = "1";
"2":   PN = "2"  !CDS_PN = "2";
BODY = "Q_CAP","I12": #LOCATION = "PC6525" !CDS_LOCATION = "PC6525" #SEC = "1" !CDS_SEC = "1";
"A":   PN = "1"  !CDS_PN = "1";
"B":   PN = "2"  !CDS_PN = "2";
BODY = "Q_RES","I13": #LOCATION = "PR6521" !CDS_LOCATION = "PR6521" &SEC = "1" #&CDS_SEC = "1";
"A":   PN = "1"  !CDS_PN = "1";
"B":   PN = "2"  !CDS_PN = "2";
BODY = "Q_CAP","I16": #LOCATION = "PC6520" !CDS_LOCATION = "PC6520" &SEC = "1" #&CDS_SEC = "1";
"A":   PN = "1"  !CDS_PN = "1";
"B":   PN = "2"  !CDS_PN = "2";
BODY = "Q_CAP","I17": #LOCATION = "PC6521" !CDS_LOCATION = "PC6521" &SEC = "1" #&CDS_SEC = "1";
"A":   PN = "1"  !CDS_PN = "1";
"B":   PN = "2"  !CDS_PN = "2";
BODY = "Q_CAP","I18": #LOCATION = "PC6522" !CDS_LOCATION = "PC6522" &SEC = "1" #&CDS_SEC = "1";
"A":   PN = "1"  !CDS_PN = "1";
"B":   PN = "2"  !CDS_PN = "2";
BODY = "Q_RES","I20": #LOCATION = "PR6522" !CDS_LOCATION = "PR6522" #SEC = "1" !CDS_SEC = "1";
"A":   PN = "1"  !CDS_PN = "1";
"B":   PN = "2"  !CDS_PN = "2";
BODY = "Q_RES","I21": #LOCATION = "PR6520" !CDS_LOCATION = "PR6520" &SEC = "1" #&CDS_SEC = "1";
"A":   PN = "1"  !CDS_PN = "1";
"B":   PN = "2"  !CDS_PN = "2";
BODY = "Q_CAP","I22": #LOCATION = "PC6523" !CDS_LOCATION = "PC6523" &SEC = "1" #&CDS_SEC = "1";
"A":   PN = "1"  !CDS_PN = "1";
"B":   PN = "2"  !CDS_PN = "2";
BODY = "Q_CAP","I23": #LOCATION = "PC6524" !CDS_LOCATION = "PC6524" &SEC = "1" #&CDS_SEC = "1";
"A":   PN = "1"  !CDS_PN = "1";
"B":   PN = "2"  !CDS_PN = "2";
BODY = "Q_CAP","I25": #LOCATION = "PC6537" !CDS_LOCATION = "PC6537" &SEC = "1" #&CDS_SEC = "1";
"A":   PN = "1"  !CDS_PN = "1";
"B":   PN = "2"  !CDS_PN = "2";
BODY = "Q_RES","I28": #LOCATION = "PR6801" !CDS_LOCATION = "PR6801" &SEC = "1" #&CDS_SEC = "1";
"A":   PN = "1"  !CDS_PN = "1";
"B":   PN = "2"  !CDS_PN = "2";
BODY = "Q_RES","I29": #LOCATION = "R644" !CDS_LOCATION = "R644" #SEC = "1" !CDS_SEC = "1";
"A":   PN = "1"  !CDS_PN = "1";
"B":   PN = "2"  !CDS_PN = "2";
BODY = "Q_RES","I32": #LOCATION = "PR6526" !CDS_LOCATION = "PR6526" &SEC = "1" #&CDS_SEC = "1";
"A":   PN = "1"  !CDS_PN = "1";
"B":   PN = "2"  !CDS_PN = "2";
BODY = "Q_CAP","I33": #LOCATION = "PC6534" !CDS_LOCATION = "PC6534" &SEC = "1" #&CDS_SEC = "1";
"A":   PN = "1"  !CDS_PN = "1";
"B":   PN = "2"  !CDS_PN = "2";
BODY = "Q_RES","I34": #LOCATION = "PR6524" !CDS_LOCATION = "PR6524" &SEC = "1" #&CDS_SEC = "1";
"A":   PN = "1"  !CDS_PN = "1";
"B":   PN = "2"  !CDS_PN = "2";
BODY = "Q_CAP","I35": #LOCATION = "PC6526" !CDS_LOCATION = "PC6526" #SEC = "1" !CDS_SEC = "1";
"A":   PN = "1"  !CDS_PN = "1";
"B":   PN = "2"  !CDS_PN = "2";
BODY = "Q_RES","I36": #LOCATION = "R645" !CDS_LOCATION = "R645" &SEC = "1" #&CDS_SEC = "1";
"A":   PN = "1"  !CDS_PN = "1";
"B":   PN = "2"  !CDS_PN = "2";
BODY = "Q_INDUCTOR","I37": #LOCATION = "PL6502" !CDS_LOCATION = "PL6502" &SEC = "1" #&CDS_SEC = "1";
"1":   PN = "1"  !CDS_PN = "1";
"2":   PN = "2"  !CDS_PN = "2";
BODY = "Q_CAP","I38": #LOCATION = "PC6527" !CDS_LOCATION = "PC6527" &SEC = "1" #&CDS_SEC = "1";
"A":   PN = "1"  !CDS_PN = "1";
"B":   PN = "2"  !CDS_PN = "2";
BODY = "Q_CAP","I39": #LOCATION = "C109" !CDS_LOCATION = "C109" &SEC = "1" #&CDS_SEC = "1";
"A":   PN = "1"  !CDS_PN = "1";
"B":   PN = "2"  !CDS_PN = "2";
BODY = "Q_CAP","I41": #LOCATION = "PC6528" !CDS_LOCATION = "PC6528" &SEC = "1" #&CDS_SEC = "1";
"A":   PN = "1"  !CDS_PN = "1";
"B":   PN = "2"  !CDS_PN = "2";
BODY = "Q_CAP","I42": #LOCATION = "PC6529" !CDS_LOCATION = "PC6529" &SEC = "1" #&CDS_SEC = "1";
"A":   PN = "1"  !CDS_PN = "1";
"B":   PN = "2"  !CDS_PN = "2";
BODY = "Q_CAP","I44": #LOCATION = "PC6530" !CDS_LOCATION = "PC6530" &SEC = "1" #&CDS_SEC = "1";
"A":   PN = "1"  !CDS_PN = "1";
"B":   PN = "2"  !CDS_PN = "2";
BODY = "Q_CAP","I45": #LOCATION = "PC6531" !CDS_LOCATION = "PC6531" &SEC = "1" #&CDS_SEC = "1";
"A":   PN = "1"  !CDS_PN = "1";
"B":   PN = "2"  !CDS_PN = "2";
BODY = "Q_CAPP","I46": #LOCATION = "PC6532" !CDS_LOCATION = "PC6532" &SEC = "1" #&CDS_SEC = "1";
"A":   PN = "1"  !CDS_PN = "1";
"B":   PN = "2"  !CDS_PN = "2";
BODY = "Q_CAPP","I47": #LOCATION = "PC6804" !CDS_LOCATION = "PC6804" &SEC = "1" #&CDS_SEC = "1";
"A":   PN = "1"  !CDS_PN = "1";
"B":   PN = "2"  !CDS_PN = "2";
BODY = "Q_CAP","I49": #LOCATION = "PC6533" !CDS_LOCATION = "PC6533" #SEC = "1" !CDS_SEC = "1";
"A":   PN = "1"  !CDS_PN = "1";
"B":   PN = "2"  !CDS_PN = "2";
BODY = "MPQ8633BGLEC838Z","I51": #LOCATION = "PU6501" !CDS_LOCATION = "PU6501" &SEC = "1" #&CDS_SEC = "1";
"AGND":   PN = "2"  !CDS_PN = "2";
"BST":   PN = "1"  !CDS_PN = "1";
"CS":   PN = "3"  !CDS_PN = "3";
"EN":   PN = "8"  !CDS_PN = "8";
"FB":   PN = "7"  !CDS_PN = "7";
"MODE":   PN = "4"  !CDS_PN = "4";
"PGND":   PN = "11_18"  !CDS_PN = "11_18";
"PGOOD":   PN = "9"  !CDS_PN = "9";
"RGND":   PN = "6"  !CDS_PN = "6";
"SW":   PN = "20"  !CDS_PN = "20";
"TRK_REF":   PN = "5"  !CDS_PN = "5";
"VCC":   PN = "19"  !CDS_PN = "19";
"VIN1":   PN = "10"  !CDS_PN = "10";
"VIN2":   PN = "21"  !CDS_PN = "21";
BODY = "Q_CAP","I55": #LOCATION = "PC6905" !CDS_LOCATION = "PC6905" &SEC = "1" #&CDS_SEC = "1";
"A":   PN = "1"  !CDS_PN = "1";
"B":   PN = "2"  !CDS_PN = "2";
BODY = "Q_CAP","I56": #LOCATION = "PC6904" !CDS_LOCATION = "PC6904" &SEC = "1" #&CDS_SEC = "1";
"A":   PN = "1"  !CDS_PN = "1";
"B":   PN = "2"  !CDS_PN = "2";
BODY = "Q_CAP","I57": #LOCATION = "PC6903" !CDS_LOCATION = "PC6903" &SEC = "1" #&CDS_SEC = "1";
"A":   PN = "1"  !CDS_PN = "1";
"B":   PN = "2"  !CDS_PN = "2";
DRAWING = "@t6g_mb_lib.t6g(sch_1):page475";
BODY = "Q_RES","I32": #LOCATION = "PR6532" !CDS_LOCATION = "PR6532" &SEC = "1" #&CDS_SEC = "1";
"A":   PN = "1"  !CDS_PN = "1";
"B":   PN = "2"  !CDS_PN = "2";
BODY = "Q_RES","I34": #LOCATION = "PR6530" !CDS_LOCATION = "PR6530" &SEC = "1" #&CDS_SEC = "1";
"A":   PN = "1"  !CDS_PN = "1";
"B":   PN = "2"  !CDS_PN = "2";
BODY = "ISL69260IRAZT","I42": #LOCATION = "PU6502" !CDS_LOCATION = "PU6502" #SEC = "1" !CDS_SEC = "1";
"ADDR_CFG":   PN = "34"  !CDS_PN = "34";
"CFP":   PN = "33"  !CDS_PN = "33";
"CS0":   PN = "30"  !CDS_PN = "30";
"CS1":   PN = "29"  !CDS_PN = "29";
"CS2":   PN = "28"  !CDS_PN = "28";
"CS3":   PN = "27"  !CDS_PN = "27";
"CS4":   PN = "26"  !CDS_PN = "26";
"CS5":   PN = "25"  !CDS_PN = "25";
"CS6":   PN = "24"  !CDS_PN = "24";
"CS7":   PN = "23"  !CDS_PN = "23";
"EN0":   PN = "13"  !CDS_PN = "13";
"EN1":   PN = "20"  !CDS_PN = "20";
"PG0":   PN = "12"  !CDS_PN = "12";
"PG1":   PN = "16"  !CDS_PN = "16";
"PMSCL":   PN = "10"  !CDS_PN = "10";
"PMSDA":   PN = "9"  !CDS_PN = "9";
"PWM0":   PN = "1"  !CDS_PN = "1";
"PWM1":   PN = "2"  !CDS_PN = "2";
"PWM2":   PN = "3"  !CDS_PN = "3";
"PWM3":   PN = "4"  !CDS_PN = "4";
"PWM4":   PN = "5"  !CDS_PN = "5";
"PWM5":   PN = "6"  !CDS_PN = "6";
"PWM6":   PN = "7"  !CDS_PN = "7";
"PWM7":   PN = "8"  !CDS_PN = "8";
"RGND0":   PN = "22"  !CDS_PN = "22";
"RGND1":   PN = "31"  !CDS_PN = "31";
"SVCLK":   PN = "17"  !CDS_PN = "17";
"SVDATA":   PN = "18"  !CDS_PN = "18";
"TEMP0":   PN = "35"  !CDS_PN = "35";
"TEMP1||ISYS":   PN = "36"  !CDS_PN = "36";
"TH_GND":   PN = "TH"  !CDS_PN = "TH";
"VCC":   PN = "39"  !CDS_PN = "39";
"VCCS":   PN = "40"  !CDS_PN = "40";
"VSEN0":   PN = "21"  !CDS_PN = "21";
"VSEN1":   PN = "32"  !CDS_PN = "32";
"NPINALERT#||NPSYSCRIT#":   PN = "15"  !CDS_PN = "15";
"NPMALERT#":   PN = "11"  !CDS_PN = "11";
"NSVALERT#":   PN = "19"  !CDS_PN = "19";
"NVRHOT#":   PN = "14"  !CDS_PN = "14";
"VINSEN||VSYS":   PN = "38"  !CDS_PN = "38";
"VMON||IINSEN||VSYS||ISYS":   PN = "37"  !CDS_PN = "37";
BODY = "Q_RES","I94": #LOCATION = "R646" !CDS_LOCATION = "R646" #SEC = "1" !CDS_SEC = "1";
"A":   PN = "1"  !CDS_PN = "1";
"B":   PN = "2"  !CDS_PN = "2";
BODY = "Q_RES","I95": #LOCATION = "R647" !CDS_LOCATION = "R647" #SEC = "1" !CDS_SEC = "1";
"A":   PN = "1"  !CDS_PN = "1";
"B":   PN = "2"  !CDS_PN = "2";
BODY = "Q_RES","I105": #LOCATION = "PR6531" !CDS_LOCATION = "PR6531" #SEC = "1" !CDS_SEC = "1";
"A":   PN = "1"  !CDS_PN = "1";
"B":   PN = "2"  !CDS_PN = "2";
BODY = "Q_CAP","I118": #LOCATION = "C101" !CDS_LOCATION = "C101" #SEC = "1" !CDS_SEC = "1";
"A":   PN = "1"  !CDS_PN = "1";
"B":   PN = "2"  !CDS_PN = "2";
BODY = "Q_RES","I119": #LOCATION = "R650" !CDS_LOCATION = "R650" #SEC = "1" !CDS_SEC = "1";
"A":   PN = "1"  !CDS_PN = "1";
"B":   PN = "2"  !CDS_PN = "2";
BODY = "Q_RES","I120": #LOCATION = "R651" !CDS_LOCATION = "R651" #SEC = "1" !CDS_SEC = "1";
"A":   PN = "1"  !CDS_PN = "1";
"B":   PN = "2"  !CDS_PN = "2";
BODY = "Q_CAP","I121": #LOCATION = "PC6540" !CDS_LOCATION = "PC6540" #SEC = "1" !CDS_SEC = "1";
"A":   PN = "1"  !CDS_PN = "1";
"B":   PN = "2"  !CDS_PN = "2";
BODY = "Q_CAP","I123": #LOCATION = "PC6602" !CDS_LOCATION = "PC6602" #SEC = "1" !CDS_SEC = "1";
"A":   PN = "1"  !CDS_PN = "1";
"B":   PN = "2"  !CDS_PN = "2";
BODY = "Q_RES","I125": #LOCATION = "PR6607" !CDS_LOCATION = "PR6607" &SEC = "1" #&CDS_SEC = "1";
"A":   PN = "1"  !CDS_PN = "1";
"B":   PN = "2"  !CDS_PN = "2";
BODY = "Q_RES","I127": #LOCATION = "R655" !CDS_LOCATION = "R655" #SEC = "1" !CDS_SEC = "1";
"A":   PN = "1"  !CDS_PN = "1";
"B":   PN = "2"  !CDS_PN = "2";
BODY = "Q_RES","I128": #LOCATION = "R652" !CDS_LOCATION = "R652" #SEC = "1" !CDS_SEC = "1";
"A":   PN = "1"  !CDS_PN = "1";
"B":   PN = "2"  !CDS_PN = "2";
BODY = "Q_RES","I131": #LOCATION = "PR6608" !CDS_LOCATION = "PR6608" #SEC = "1" !CDS_SEC = "1";
"A":   PN = "1"  !CDS_PN = "1";
"B":   PN = "2"  !CDS_PN = "2";
BODY = "Q_CAP","I132": #LOCATION = "PC6604" !CDS_LOCATION = "PC6604" #SEC = "1" !CDS_SEC = "1";
"A":   PN = "1"  !CDS_PN = "1";
"B":   PN = "2"  !CDS_PN = "2";
BODY = "Q_RES","I135": #LOCATION = "PR6615" !CDS_LOCATION = "PR6615" #SEC = "1" !CDS_SEC = "1";
"A":   PN = "1"  !CDS_PN = "1";
"B":   PN = "2"  !CDS_PN = "2";
BODY = "Q_RES","I136": #LOCATION = "PR6616" !CDS_LOCATION = "PR6616" #SEC = "1" !CDS_SEC = "1";
"A":   PN = "1"  !CDS_PN = "1";
"B":   PN = "2"  !CDS_PN = "2";
BODY = "Q_RES","I138": #LOCATION = "PR6814" !CDS_LOCATION = "PR6814" #SEC = "1" !CDS_SEC = "1";
"A":   PN = "1"  !CDS_PN = "1";
"B":   PN = "2"  !CDS_PN = "2";
BODY = "Q_CAP","I144": #LOCATION = "PC6603" !CDS_LOCATION = "PC6603" #SEC = "1" !CDS_SEC = "1";
"A":   PN = "1"  !CDS_PN = "1";
"B":   PN = "2"  !CDS_PN = "2";
BODY = "Q_CAP","I145": #LOCATION = "PC6606" !CDS_LOCATION = "PC6606" #SEC = "1" !CDS_SEC = "1";
"A":   PN = "1"  !CDS_PN = "1";
"B":   PN = "2"  !CDS_PN = "2";
BODY = "Q_CAP","I146": #LOCATION = "PC6605" !CDS_LOCATION = "PC6605" #SEC = "1" !CDS_SEC = "1";
"A":   PN = "1"  !CDS_PN = "1";
"B":   PN = "2"  !CDS_PN = "2";
BODY = "Q_CAP","I148": #LOCATION = "PC6607" !CDS_LOCATION = "PC6607" #SEC = "1" !CDS_SEC = "1";
"A":   PN = "1"  !CDS_PN = "1";
"B":   PN = "2"  !CDS_PN = "2";
BODY = "Q_RES","I150": #LOCATION = "PR6605" !CDS_LOCATION = "PR6605" #SEC = "1" !CDS_SEC = "1";
"A":   PN = "1"  !CDS_PN = "1";
"B":   PN = "2"  !CDS_PN = "2";
BODY = "Q_CAP","I151": #LOCATION = "PC6601" !CDS_LOCATION = "PC6601" #SEC = "1" !CDS_SEC = "1";
"A":   PN = "1"  !CDS_PN = "1";
"B":   PN = "2"  !CDS_PN = "2";
BODY = "Q_RES","I158": #LOCATION = "PR6807" !CDS_LOCATION = "PR6807" #SEC = "1" !CDS_SEC = "1";
"A":   PN = "1"  !CDS_PN = "1";
"B":   PN = "2"  !CDS_PN = "2";
BODY = "Q_RES","I160": #LOCATION = "PR6606" !CDS_LOCATION = "PR6606" #SEC = "1" !CDS_SEC = "1";
"A":   PN = "1"  !CDS_PN = "1";
"B":   PN = "2"  !CDS_PN = "2";
BODY = "Q_RES","I161": #LOCATION = "R6801" !CDS_LOCATION = "R6801" #SEC = "1" !CDS_SEC = "1";
"A":   PN = "1"  !CDS_PN = "1";
"B":   PN = "2"  !CDS_PN = "2";
BODY = "Q_RES","I165": #LOCATION = "PR6810" !CDS_LOCATION = "PR6810" #SEC = "1" !CDS_SEC = "1";
"A":   PN = "1"  !CDS_PN = "1";
"B":   PN = "2"  !CDS_PN = "2";
BODY = "Q_RES","I166": #LOCATION = "PR6805" !CDS_LOCATION = "PR6805" #SEC = "1" !CDS_SEC = "1";
"A":   PN = "1"  !CDS_PN = "1";
"B":   PN = "2"  !CDS_PN = "2";
BODY = "Q_RES","I167": #LOCATION = "PR6803" !CDS_LOCATION = "PR6803" #SEC = "1" !CDS_SEC = "1";
"A":   PN = "1"  !CDS_PN = "1";
"B":   PN = "2"  !CDS_PN = "2";
BODY = "Q_RES","I168": #LOCATION = "PR6819" !CDS_LOCATION = "PR6819" #SEC = "1" !CDS_SEC = "1";
"A":   PN = "1"  !CDS_PN = "1";
"B":   PN = "2"  !CDS_PN = "2";
BODY = "Q_RES","I169": #LOCATION = "PR6817" !CDS_LOCATION = "PR6817" #SEC = "1" !CDS_SEC = "1";
"A":   PN = "1"  !CDS_PN = "1";
"B":   PN = "2"  !CDS_PN = "2";
BODY = "Q_RES","I178": #LOCATION = "PR6604" !CDS_LOCATION = "PR6604" #SEC = "1" !CDS_SEC = "1";
"A":   PN = "1"  !CDS_PN = "1";
"B":   PN = "2"  !CDS_PN = "2";
BODY = "Q_RES","I183": #LOCATION = "PR6603" !CDS_LOCATION = "PR6603" #SEC = "1" !CDS_SEC = "1";
"A":   PN = "1"  !CDS_PN = "1";
"B":   PN = "2"  !CDS_PN = "2";
BODY = "Q_RES","I188": #LOCATION = "PR6609" !CDS_LOCATION = "PR6609" &SEC = "1" #&CDS_SEC = "1";
"A":   PN = "1"  !CDS_PN = "1";
"B":   PN = "2"  !CDS_PN = "2";
BODY = "Q_RES","I190": #LOCATION = "PR6610" !CDS_LOCATION = "PR6610" &SEC = "1" #&CDS_SEC = "1";
"A":   PN = "1"  !CDS_PN = "1";
"B":   PN = "2"  !CDS_PN = "2";
BODY = "Q_RES","I191": #LOCATION = "PR6611" !CDS_LOCATION = "PR6611" &SEC = "1" #&CDS_SEC = "1";
"A":   PN = "1"  !CDS_PN = "1";
"B":   PN = "2"  !CDS_PN = "2";
BODY = "Q_RES","I192": #LOCATION = "PR6612" !CDS_LOCATION = "PR6612" &SEC = "1" #&CDS_SEC = "1";
"A":   PN = "1"  !CDS_PN = "1";
"B":   PN = "2"  !CDS_PN = "2";
BODY = "Q_RES","I193": #LOCATION = "PR6613" !CDS_LOCATION = "PR6613" &SEC = "1" #&CDS_SEC = "1";
"A":   PN = "1"  !CDS_PN = "1";
"B":   PN = "2"  !CDS_PN = "2";
BODY = "Q_RES","I198": #LOCATION = "PR6614" !CDS_LOCATION = "PR6614" &SEC = "1" #&CDS_SEC = "1";
"A":   PN = "1"  !CDS_PN = "1";
"B":   PN = "2"  !CDS_PN = "2";
BODY = "Q_RES","I204": #LOCATION = "PR6618" !CDS_LOCATION = "PR6618" &SEC = "1" #&CDS_SEC = "1";
"A":   PN = "1"  !CDS_PN = "1";
"B":   PN = "2"  !CDS_PN = "2";
BODY = "Q_RES","I207": #LOCATION = "R649" !CDS_LOCATION = "R649" &SEC = "1" #&CDS_SEC = "1";
"A":   PN = "1"  !CDS_PN = "1";
"B":   PN = "2"  !CDS_PN = "2";
BODY = "Q_RES","I208": #LOCATION = "R6786" !CDS_LOCATION = "R6786" &SEC = "1" #&CDS_SEC = "1";
"A":   PN = "1"  !CDS_PN = "1";
"B":   PN = "2"  !CDS_PN = "2";
BODY = "Q_RES","I210": #LOCATION = "PR883" !CDS_LOCATION = "PR883" &SEC = "1" #&CDS_SEC = "1";
"A":   PN = "1"  !CDS_PN = "1";
"B":   PN = "2"  !CDS_PN = "2";
BODY = "Q_RES","I212": #LOCATION = "R643" !CDS_LOCATION = "R643" &SEC = "1" #&CDS_SEC = "1";
"A":   PN = "1"  !CDS_PN = "1";
"B":   PN = "2"  !CDS_PN = "2";
BODY = "Q_RES","I213": #LOCATION = "R6860" !CDS_LOCATION = "R6860" &SEC = "1" #&CDS_SEC = "1";
"A":   PN = "1"  !CDS_PN = "1";
"B":   PN = "2"  !CDS_PN = "2";
BODY = "Q_SHORT","I214": #LOCATION = "PJ09_P0_P" !CDS_LOCATION = "PJ09_P0_P" #SEC = "1" !CDS_SEC = "1";
"1":   PN = "1"  !CDS_PN = "1";
"2":   PN = "2"  !CDS_PN = "2";
BODY = "Q_SHORT","I215": #LOCATION = "PJ09_P0_N" !CDS_LOCATION = "PJ09_P0_N" #SEC = "1" !CDS_SEC = "1";
"1":   PN = "1"  !CDS_PN = "1";
"2":   PN = "2"  !CDS_PN = "2";
DRAWING = "@t6g_mb_lib.t6g(sch_1):page476";
BODY = "Q_CAP","I6": #LOCATION = "PC6555_1" !CDS_LOCATION = "PC6555_1" &SEC = "1" #&CDS_SEC = "1";
"A":   PN = "1"  !CDS_PN = "1";
"B":   PN = "2"  !CDS_PN = "2";
BODY = "Q_CAP","I21": #LOCATION = "PC6558_1" !CDS_LOCATION = "PC6558_1" &SEC = "1" #&CDS_SEC = "1";
"A":   PN = "1"  !CDS_PN = "1";
"B":   PN = "2"  !CDS_PN = "2";
BODY = "Q_CAP","I24": #LOCATION = "PC6557_1" !CDS_LOCATION = "PC6557_1" &SEC = "1" #&CDS_SEC = "1";
"A":   PN = "1"  !CDS_PN = "1";
"B":   PN = "2"  !CDS_PN = "2";
BODY = "Q_CAP","I27": #LOCATION = "PC6556_1" !CDS_LOCATION = "PC6556_1" &SEC = "1" #&CDS_SEC = "1";
"A":   PN = "1"  !CDS_PN = "1";
"B":   PN = "2"  !CDS_PN = "2";
BODY = "Q_CAP","I29": #LOCATION = "PC6554_1" !CDS_LOCATION = "PC6554_1" &SEC = "1" #&CDS_SEC = "1";
"A":   PN = "1"  !CDS_PN = "1";
"B":   PN = "2"  !CDS_PN = "2";
BODY = "Q_CAP","I30": #LOCATION = "PC6563" !CDS_LOCATION = "PC6563" &SEC = "1" #&CDS_SEC = "1";
"A":   PN = "1"  !CDS_PN = "1";
"B":   PN = "2"  !CDS_PN = "2";
BODY = "Q_CAP","I33": #LOCATION = "PC6565" !CDS_LOCATION = "PC6565" &SEC = "1" #&CDS_SEC = "1";
"A":   PN = "1"  !CDS_PN = "1";
"B":   PN = "2"  !CDS_PN = "2";
BODY = "Q_INDUCTOR","I34": #LOCATION = "PL6505" !CDS_LOCATION = "PL6505" #SEC = "1" !CDS_SEC = "1";
"1":   PN = "1"  !CDS_PN = "1";
"2":   PN = "2"  !CDS_PN = "2";
BODY = "Q_RES","I42": #LOCATION = "PR6556" !CDS_LOCATION = "PR6556" &SEC = "1" #&CDS_SEC = "1";
"A":   PN = "1"  !CDS_PN = "1";
"B":   PN = "2"  !CDS_PN = "2";
BODY = "Q_CAP","I47": #LOCATION = "PC6550_09P0_1" !CDS_LOCATION = "PC6550_09P0_1" &SEC = "1" #&CDS_SEC = "1";
"A":   PN = "1"  !CDS_PN = "1";
"B":   PN = "2"  !CDS_PN = "2";
BODY = "Q_CAP","I48": #LOCATION = "PC6552" !CDS_LOCATION = "PC6552" &SEC = "1" #&CDS_SEC = "1";
"A":   PN = "1"  !CDS_PN = "1";
"B":   PN = "2"  !CDS_PN = "2";
BODY = "ISL99390FRZTR5935","I53": #LOCATION = "PU6503" !CDS_LOCATION = "PU6503" #SEC = "1" !CDS_SEC = "1";
"AGND":   PN = "2"  !CDS_PN = "2";
"BOOT":   PN = "33"  !CDS_PN = "33";
"DNC":   PN = "31"  !CDS_PN = "31";
"EN":   PN = "35"  !CDS_PN = "35";
"GL1":   PN = "6"  !CDS_PN = "6";
"GL2":   PN = "41"  !CDS_PN = "41";
"IOUT":   PN = "38"  !CDS_PN = "38";
"LSET":   PN = "37"  !CDS_PN = "37";
"PGND1":   PN = "5"  !CDS_PN = "5";
"PGND2":   PN = "7_9-20_24"  !CDS_PN = "7_9-20_24";
"PGND3":   PN = "40"  !CDS_PN = "40";
"PHASE":   PN = "32"  !CDS_PN = "32";
"PVCC":   PN = "4"  !CDS_PN = "4";
"PWM":   PN = "34"  !CDS_PN = "34";
"REFIN":   PN = "39"  !CDS_PN = "39";
"SW":   PN = "10_19"  !CDS_PN = "10_19";
"TOUT_FLT":   PN = "36"  !CDS_PN = "36";
"VCC":   PN = "3"  !CDS_PN = "3";
"VIN1":   PN = "25_29"  !CDS_PN = "25_29";
"VIN2":   PN = "30"  !CDS_PN = "30";
"VOS":   PN = "1"  !CDS_PN = "1";
BODY = "Q_RES","I58": #LOCATION = "PR6552" !CDS_LOCATION = "PR6552" &SEC = "1" #&CDS_SEC = "1";
"A":   PN = "1"  !CDS_PN = "1";
"B":   PN = "2"  !CDS_PN = "2";
BODY = "Q_CAP","I68": #LOCATION = "PC6553_1" !CDS_LOCATION = "PC6553_1" &SEC = "1" #&CDS_SEC = "1";
"A":   PN = "1"  !CDS_PN = "1";
"B":   PN = "2"  !CDS_PN = "2";
BODY = "Q_INDUCTOR","I182": #LOCATION = "PL6504" !CDS_LOCATION = "PL6504" #SEC = "1" !CDS_SEC = "1";
"1":   PN = "1"  !CDS_PN = "1";
"2":   PN = "2"  !CDS_PN = "2";
BODY = "Q_RES","I183": #LOCATION = "PR6550" !CDS_LOCATION = "PR6550" #SEC = "1" !CDS_SEC = "1";
"A":   PN = "1"  !CDS_PN = "1";
"B":   PN = "2"  !CDS_PN = "2";
BODY = "Q_RES","I185": #LOCATION = "PR6551" !CDS_LOCATION = "PR6551" #SEC = "1" !CDS_SEC = "1";
"A":   PN = "1"  !CDS_PN = "1";
"B":   PN = "2"  !CDS_PN = "2";
BODY = "Q_RES","I187": #LOCATION = "PR6557" !CDS_LOCATION = "PR6557" #SEC = "1" !CDS_SEC = "1";
"A":   PN = "1"  !CDS_PN = "1";
"B":   PN = "2"  !CDS_PN = "2";
BODY = "Q_CAP","I202": #LOCATION = "PC6566_1" !CDS_LOCATION = "PC6566_1" &SEC = "1" #&CDS_SEC = "1";
"A":   PN = "1"  !CDS_PN = "1";
"B":   PN = "2"  !CDS_PN = "2";
BODY = "Q_CAPP","I209": #LOCATION = "PC6561" !CDS_LOCATION = "PC6561" &SEC = "1" #&CDS_SEC = "1";
"A":   PN = "1"  !CDS_PN = "1";
"B":   PN = "2"  !CDS_PN = "2";
BODY = "Q_CAP","I210": #LOCATION = "PC6559_1" !CDS_LOCATION = "PC6559_1" #SEC = "1" !CDS_SEC = "1";
"A":   PN = "1"  !CDS_PN = "1";
"B":   PN = "2"  !CDS_PN = "2";
BODY = "Q_CAP","I216": #LOCATION = "PC6816" !CDS_LOCATION = "PC6816" #SEC = "1" !CDS_SEC = "1";
"A":   PN = "1"  !CDS_PN = "1";
"B":   PN = "2"  !CDS_PN = "2";
BODY = "Q_CAP","I217": #LOCATION = "PC6560" !CDS_LOCATION = "PC6560" #SEC = "1" !CDS_SEC = "1";
"A":   PN = "1"  !CDS_PN = "1";
"B":   PN = "2"  !CDS_PN = "2";
BODY = "Q_RES","I220": #LOCATION = "PR6553" !CDS_LOCATION = "PR6553" #SEC = "1" !CDS_SEC = "1";
"A":   PN = "1"  !CDS_PN = "1";
"B":   PN = "2"  !CDS_PN = "2";
BODY = "Q_RES","I221": #LOCATION = "PR6554" !CDS_LOCATION = "PR6554" #SEC = "1" !CDS_SEC = "1";
"A":   PN = "1"  !CDS_PN = "1";
"B":   PN = "2"  !CDS_PN = "2";
BODY = "Q_CAPP","I222": #LOCATION = "PC6572" !CDS_LOCATION = "PC6572" &SEC = "1" #&CDS_SEC = "1";
"A":   PN = "1"  !CDS_PN = "1";
"B":   PN = "2"  !CDS_PN = "2";
BODY = "Q_CAP","I223": #LOCATION = "PC6567_1" !CDS_LOCATION = "PC6567_1" &SEC = "1" #&CDS_SEC = "1";
"A":   PN = "1"  !CDS_PN = "1";
"B":   PN = "2"  !CDS_PN = "2";
BODY = "Q_CAPP","I224": #LOCATION = "PC6568" !CDS_LOCATION = "PC6568" &SEC = "1" #&CDS_SEC = "1";
"A":   PN = "1"  !CDS_PN = "1";
"B":   PN = "2"  !CDS_PN = "2";
BODY = "Q_CAPP","I225": #LOCATION = "PC6569" !CDS_LOCATION = "PC6569" &SEC = "1" #&CDS_SEC = "1";
"A":   PN = "1"  !CDS_PN = "1";
"B":   PN = "2"  !CDS_PN = "2";
BODY = "Q_CAPP","I226": #LOCATION = "PC6570" !CDS_LOCATION = "PC6570" &SEC = "1" #&CDS_SEC = "1";
"A":   PN = "1"  !CDS_PN = "1";
"B":   PN = "2"  !CDS_PN = "2";
BODY = "Q_CAPP","I227": #LOCATION = "PC6571" !CDS_LOCATION = "PC6571" &SEC = "1" #&CDS_SEC = "1";
"A":   PN = "1"  !CDS_PN = "1";
"B":   PN = "2"  !CDS_PN = "2";
BODY = "Q_CAPP","I231": #LOCATION = "PC6810" !CDS_LOCATION = "PC6810" &SEC = "1" #&CDS_SEC = "1";
"A":   PN = "1"  !CDS_PN = "1";
"B":   PN = "2"  !CDS_PN = "2";
BODY = "Q_CAP","I232": #LOCATION = "PC6817" !CDS_LOCATION = "PC6817" &SEC = "1" #&CDS_SEC = "1";
"A":   PN = "1"  !CDS_PN = "1";
"B":   PN = "2"  !CDS_PN = "2";
BODY = "Q_CAPP","I236": #LOCATION = "PC6574" !CDS_LOCATION = "PC6574" &SEC = "1" #&CDS_SEC = "1";
"A":   PN = "1"  !CDS_PN = "1";
"B":   PN = "2"  !CDS_PN = "2";
BODY = "Q_CAPP","I238": #LOCATION = "PC6573" !CDS_LOCATION = "PC6573" &SEC = "1" #&CDS_SEC = "1";
"A":   PN = "1"  !CDS_PN = "1";
"B":   PN = "2"  !CDS_PN = "2";
BODY = "Q_CAPP","I239": #LOCATION = "PC534" !CDS_LOCATION = "PC534" &SEC = "1" #&CDS_SEC = "1";
"A":   PN = "1"  !CDS_PN = "1";
"B":   PN = "2"  !CDS_PN = "2";
BODY = "Q_CAP","I241": #LOCATION = "PC6583" !CDS_LOCATION = "PC6583" &SEC = "1" #&CDS_SEC = "1";
"A":   PN = "1"  !CDS_PN = "1";
"B":   PN = "2"  !CDS_PN = "2";
BODY = "Q_CAP","I242": #LOCATION = "PC6582_2" !CDS_LOCATION = "PC6582_2" &SEC = "1" #&CDS_SEC = "1";
"A":   PN = "1"  !CDS_PN = "1";
"B":   PN = "2"  !CDS_PN = "2";
BODY = "Q_CAP","I243": #LOCATION = "PC6581_2" !CDS_LOCATION = "PC6581_2" &SEC = "1" #&CDS_SEC = "1";
"A":   PN = "1"  !CDS_PN = "1";
"B":   PN = "2"  !CDS_PN = "2";
BODY = "Q_CAP","I244": #LOCATION = "PC6580_2" !CDS_LOCATION = "PC6580_2" &SEC = "1" #&CDS_SEC = "1";
"A":   PN = "1"  !CDS_PN = "1";
"B":   PN = "2"  !CDS_PN = "2";
BODY = "Q_CAP","I245": #LOCATION = "PC6579_2" !CDS_LOCATION = "PC6579_2" &SEC = "1" #&CDS_SEC = "1";
"A":   PN = "1"  !CDS_PN = "1";
"B":   PN = "2"  !CDS_PN = "2";
BODY = "Q_CAPP","I247": #LOCATION = "PC6811" !CDS_LOCATION = "PC6811" &SEC = "1" #&CDS_SEC = "1";
"A":   PN = "1"  !CDS_PN = "1";
"B":   PN = "2"  !CDS_PN = "2";
BODY = "Q_CAPP","I248": #LOCATION = "PC6812" !CDS_LOCATION = "PC6812" &SEC = "1" #&CDS_SEC = "1";
"A":   PN = "1"  !CDS_PN = "1";
"B":   PN = "2"  !CDS_PN = "2";
BODY = "Q_CAP","I250": #LOCATION = "PC6587_2" !CDS_LOCATION = "PC6587_2" &SEC = "1" #&CDS_SEC = "1";
"A":   PN = "1"  !CDS_PN = "1";
"B":   PN = "2"  !CDS_PN = "2";
BODY = "Q_CAP","I251": #LOCATION = "PC6586_2" !CDS_LOCATION = "PC6586_2" &SEC = "1" #&CDS_SEC = "1";
"A":   PN = "1"  !CDS_PN = "1";
"B":   PN = "2"  !CDS_PN = "2";
BODY = "Q_CAP","I253": #LOCATION = "PC6584" !CDS_LOCATION = "PC6584" &SEC = "1" #&CDS_SEC = "1";
"A":   PN = "1"  !CDS_PN = "1";
"B":   PN = "2"  !CDS_PN = "2";
BODY = "Q_CAP","I255": #LOCATION = "PC6806" !CDS_LOCATION = "PC6806" &SEC = "1" #&CDS_SEC = "1";
"A":   PN = "1"  !CDS_PN = "1";
"B":   PN = "2"  !CDS_PN = "2";
BODY = "Q_INDUCTOR","I257": #LOCATION = "PL6506" !CDS_LOCATION = "PL6506" &SEC = "1" #&CDS_SEC = "1";
"1":   PN = "1"  !CDS_PN = "1";
"2":   PN = "2"  !CDS_PN = "2";
BODY = "Q_CAP","I258": #LOCATION = "PC6577_2" !CDS_LOCATION = "PC6577_2" &SEC = "1" #&CDS_SEC = "1";
"A":   PN = "1"  !CDS_PN = "1";
"B":   PN = "2"  !CDS_PN = "2";
BODY = "Q_CAP","I259": #LOCATION = "PC6578_2" !CDS_LOCATION = "PC6578_2" &SEC = "1" #&CDS_SEC = "1";
"A":   PN = "1"  !CDS_PN = "1";
"B":   PN = "2"  !CDS_PN = "2";
BODY = "Q_RES","I262": #LOCATION = "PR6562" !CDS_LOCATION = "PR6562" &SEC = "1" #&CDS_SEC = "1";
"A":   PN = "1"  !CDS_PN = "1";
"B":   PN = "2"  !CDS_PN = "2";
BODY = "Q_RES","I263": #LOCATION = "PR6564" !CDS_LOCATION = "PR6564" &SEC = "1" #&CDS_SEC = "1";
"A":   PN = "1"  !CDS_PN = "1";
"B":   PN = "2"  !CDS_PN = "2";
BODY = "Q_CAP","I267": #LOCATION = "PC6551_09P0_2" !CDS_LOCATION = "PC6551_09P0_2" &SEC = "1" #&CDS_SEC = "1";
"A":   PN = "1"  !CDS_PN = "1";
"B":   PN = "2"  !CDS_PN = "2";
BODY = "Q_RES","I269": #LOCATION = "PR6560" !CDS_LOCATION = "PR6560" &SEC = "1" #&CDS_SEC = "1";
"A":   PN = "1"  !CDS_PN = "1";
"B":   PN = "2"  !CDS_PN = "2";
BODY = "ISL99390FRZTR5935","I270": #LOCATION = "PU6504" !CDS_LOCATION = "PU6504" #SEC = "1" !CDS_SEC = "1";
"AGND":   PN = "2"  !CDS_PN = "2";
"BOOT":   PN = "33"  !CDS_PN = "33";
"DNC":   PN = "31"  !CDS_PN = "31";
"EN":   PN = "35"  !CDS_PN = "35";
"GL1":   PN = "6"  !CDS_PN = "6";
"GL2":   PN = "41"  !CDS_PN = "41";
"IOUT":   PN = "38"  !CDS_PN = "38";
"LSET":   PN = "37"  !CDS_PN = "37";
"PGND1":   PN = "5"  !CDS_PN = "5";
"PGND2":   PN = "7_9-20_24"  !CDS_PN = "7_9-20_24";
"PGND3":   PN = "40"  !CDS_PN = "40";
"PHASE":   PN = "32"  !CDS_PN = "32";
"PVCC":   PN = "4"  !CDS_PN = "4";
"PWM":   PN = "34"  !CDS_PN = "34";
"REFIN":   PN = "39"  !CDS_PN = "39";
"SW":   PN = "10_19"  !CDS_PN = "10_19";
"TOUT_FLT":   PN = "36"  !CDS_PN = "36";
"VCC":   PN = "3"  !CDS_PN = "3";
"VIN1":   PN = "25_29"  !CDS_PN = "25_29";
"VIN2":   PN = "30"  !CDS_PN = "30";
"VOS":   PN = "1"  !CDS_PN = "1";
BODY = "Q_CAP","I271": #LOCATION = "PC6575" !CDS_LOCATION = "PC6575" &SEC = "1" #&CDS_SEC = "1";
"A":   PN = "1"  !CDS_PN = "1";
"B":   PN = "2"  !CDS_PN = "2";
BODY = "Q_RES","I276": #LOCATION = "PR6561" !CDS_LOCATION = "PR6561" &SEC = "1" #&CDS_SEC = "1";
"A":   PN = "1"  !CDS_PN = "1";
"B":   PN = "2"  !CDS_PN = "2";
BODY = "Q_CAP","I281": #LOCATION = "PC6576" !CDS_LOCATION = "PC6576" &SEC = "1" #&CDS_SEC = "1";
"A":   PN = "1"  !CDS_PN = "1";
"B":   PN = "2"  !CDS_PN = "2";
BODY = "Q_RES","I283": #LOCATION = "PR6555" !CDS_LOCATION = "PR6555" &SEC = "1" #&CDS_SEC = "1";
"A":   PN = "1"  !CDS_PN = "1";
"B":   PN = "2"  !CDS_PN = "2";
BODY = "Q_CAP","I285": #LOCATION = "PC6564" !CDS_LOCATION = "PC6564" &SEC = "1" #&CDS_SEC = "1";
"A":   PN = "1"  !CDS_PN = "1";
"B":   PN = "2"  !CDS_PN = "2";
BODY = "Q_RES","I286": #LOCATION = "PR6563" !CDS_LOCATION = "PR6563" &SEC = "1" #&CDS_SEC = "1";
"A":   PN = "1"  !CDS_PN = "1";
"B":   PN = "2"  !CDS_PN = "2";
BODY = "Q_CAP","I288": #LOCATION = "PC6585" !CDS_LOCATION = "PC6585" &SEC = "1" #&CDS_SEC = "1";
"A":   PN = "1"  !CDS_PN = "1";
"B":   PN = "2"  !CDS_PN = "2";
BODY = "Q_CAP","I291": #LOCATION = "PC6562" !CDS_LOCATION = "PC6562" &SEC = "1" #&CDS_SEC = "1";
"A":   PN = "1"  !CDS_PN = "1";
"B":   PN = "2"  !CDS_PN = "2";
DRAWING = "@t6g_mb_lib.t6g(sch_1):page477";
BODY = "Q_RES","I2": #LOCATION = "R6800" !CDS_LOCATION = "R6800" &SEC = "1" #&CDS_SEC = "1";
"A":   PN = "1"  !CDS_PN = "1";
"B":   PN = "2"  !CDS_PN = "2";
BODY = "Q_RES","I3": #LOCATION = "PR6821" !CDS_LOCATION = "PR6821" &SEC = "1" #&CDS_SEC = "1";
"A":   PN = "1"  !CDS_PN = "1";
"B":   PN = "2"  !CDS_PN = "2";
BODY = "Q_CAP","I5": #LOCATION = "PC514" !CDS_LOCATION = "PC514" &SEC = "1" #&CDS_SEC = "1";
"A":   PN = "1"  !CDS_PN = "1";
"B":   PN = "2"  !CDS_PN = "2";
BODY = "Q_RES","I7": #LOCATION = "PR885" !CDS_LOCATION = "PR885" &SEC = "1" #&CDS_SEC = "1";
"A":   PN = "1"  !CDS_PN = "1";
"B":   PN = "2"  !CDS_PN = "2";
BODY = "Q_RES","I10": #LOCATION = "PR6809" !CDS_LOCATION = "PR6809" &SEC = "1" #&CDS_SEC = "1";
"A":   PN = "1"  !CDS_PN = "1";
"B":   PN = "2"  !CDS_PN = "2";
BODY = "Q_RES","I11": #LOCATION = "PR6808" !CDS_LOCATION = "PR6808" &SEC = "1" #&CDS_SEC = "1";
"A":   PN = "1"  !CDS_PN = "1";
"B":   PN = "2"  !CDS_PN = "2";
BODY = "Q_RES","I13": #LOCATION = "PR6533" !CDS_LOCATION = "PR6533" &SEC = "1" #&CDS_SEC = "1";
"A":   PN = "1"  !CDS_PN = "1";
"B":   PN = "2"  !CDS_PN = "2";
BODY = "Q_RES","I14": #LOCATION = "R665" !CDS_LOCATION = "R665" &SEC = "1" #&CDS_SEC = "1";
"A":   PN = "1"  !CDS_PN = "1";
"B":   PN = "2"  !CDS_PN = "2";
BODY = "Q_RES","I15": #LOCATION = "R663" !CDS_LOCATION = "R663" &SEC = "1" #&CDS_SEC = "1";
"A":   PN = "1"  !CDS_PN = "1";
"B":   PN = "2"  !CDS_PN = "2";
BODY = "Q_RES","I22": #LOCATION = "PR6602" !CDS_LOCATION = "PR6602" &SEC = "1" #&CDS_SEC = "1";
"A":   PN = "1"  !CDS_PN = "1";
"B":   PN = "2"  !CDS_PN = "2";
BODY = "Q_RES","I23": #LOCATION = "PR6600" !CDS_LOCATION = "PR6600" &SEC = "1" #&CDS_SEC = "1";
"A":   PN = "1"  !CDS_PN = "1";
"B":   PN = "2"  !CDS_PN = "2";
BODY = "Q_RES","I27": #LOCATION = "PR6601" !CDS_LOCATION = "PR6601" &SEC = "1" #&CDS_SEC = "1";
"A":   PN = "1"  !CDS_PN = "1";
"B":   PN = "2"  !CDS_PN = "2";
BODY = "Q_CAP","I28": #LOCATION = "PC6600" !CDS_LOCATION = "PC6600" &SEC = "1" #&CDS_SEC = "1";
"A":   PN = "1"  !CDS_PN = "1";
"B":   PN = "2"  !CDS_PN = "2";
BODY = "Q_RES","I31": #LOCATION = "R658" !CDS_LOCATION = "R658" &SEC = "1" #&CDS_SEC = "1";
"A":   PN = "1"  !CDS_PN = "1";
"B":   PN = "2"  !CDS_PN = "2";
BODY = "Q_RES","I32": #LOCATION = "PR6818" !CDS_LOCATION = "PR6818" &SEC = "1" #&CDS_SEC = "1";
"A":   PN = "1"  !CDS_PN = "1";
"B":   PN = "2"  !CDS_PN = "2";
BODY = "Q_RES","I33": #LOCATION = "R657" !CDS_LOCATION = "R657" &SEC = "1" #&CDS_SEC = "1";
"A":   PN = "1"  !CDS_PN = "1";
"B":   PN = "2"  !CDS_PN = "2";
BODY = "Q_RES","I36": #LOCATION = "PR6804" !CDS_LOCATION = "PR6804" &SEC = "1" #&CDS_SEC = "1";
"A":   PN = "1"  !CDS_PN = "1";
"B":   PN = "2"  !CDS_PN = "2";
BODY = "Q_RES","I37": #LOCATION = "PR6806" !CDS_LOCATION = "PR6806" &SEC = "1" #&CDS_SEC = "1";
"A":   PN = "1"  !CDS_PN = "1";
"B":   PN = "2"  !CDS_PN = "2";
BODY = "Q_RES","I38": #LOCATION = "R662" !CDS_LOCATION = "R662" &SEC = "1" #&CDS_SEC = "1";
"A":   PN = "1"  !CDS_PN = "1";
"B":   PN = "2"  !CDS_PN = "2";
BODY = "Q_RES","I39": #LOCATION = "R661" !CDS_LOCATION = "R661" &SEC = "1" #&CDS_SEC = "1";
"A":   PN = "1"  !CDS_PN = "1";
"B":   PN = "2"  !CDS_PN = "2";
BODY = "Q_RES","I42": #LOCATION = "PR6811" !CDS_LOCATION = "PR6811" &SEC = "1" #&CDS_SEC = "1";
"A":   PN = "1"  !CDS_PN = "1";
"B":   PN = "2"  !CDS_PN = "2";
BODY = "Q_RES","I43": #LOCATION = "PR6820" !CDS_LOCATION = "PR6820" &SEC = "1" #&CDS_SEC = "1";
"A":   PN = "1"  !CDS_PN = "1";
"B":   PN = "2"  !CDS_PN = "2";
BODY = "Q_RES","I44": #LOCATION = "PR6802" !CDS_LOCATION = "PR6802" &SEC = "1" #&CDS_SEC = "1";
"A":   PN = "1"  !CDS_PN = "1";
"B":   PN = "2"  !CDS_PN = "2";
BODY = "Q_CAP","I45": #LOCATION = "C107" !CDS_LOCATION = "C107" &SEC = "1" #&CDS_SEC = "1";
"A":   PN = "1"  !CDS_PN = "1";
"B":   PN = "2"  !CDS_PN = "2";
BODY = "Q_RES","I46": #LOCATION = "PR6813" !CDS_LOCATION = "PR6813" &SEC = "1" #&CDS_SEC = "1";
"A":   PN = "1"  !CDS_PN = "1";
"B":   PN = "2"  !CDS_PN = "2";
BODY = "Q_CAP","I48": #LOCATION = "PC819" !CDS_LOCATION = "PC819" &SEC = "1" #&CDS_SEC = "1";
"A":   PN = "1"  !CDS_PN = "1";
"B":   PN = "2"  !CDS_PN = "2";
BODY = "Q_CAP","I51": #LOCATION = "PC523" !CDS_LOCATION = "PC523" &SEC = "1" #&CDS_SEC = "1";
"A":   PN = "1"  !CDS_PN = "1";
"B":   PN = "2"  !CDS_PN = "2";
BODY = "Q_RES","I52": #LOCATION = "PR6548" !CDS_LOCATION = "PR6548" &SEC = "1" #&CDS_SEC = "1";
"A":   PN = "1"  !CDS_PN = "1";
"B":   PN = "2"  !CDS_PN = "2";
BODY = "Q_RES","I54": #LOCATION = "PR6815" !CDS_LOCATION = "PR6815" &SEC = "1" #&CDS_SEC = "1";
"A":   PN = "1"  !CDS_PN = "1";
"B":   PN = "2"  !CDS_PN = "2";
BODY = "Q_RES","I56": #LOCATION = "PR6816" !CDS_LOCATION = "PR6816" &SEC = "1" #&CDS_SEC = "1";
"A":   PN = "1"  !CDS_PN = "1";
"B":   PN = "2"  !CDS_PN = "2";
BODY = "Q_RES","I57": #LOCATION = "PR6544" !CDS_LOCATION = "PR6544" &SEC = "1" #&CDS_SEC = "1";
"A":   PN = "1"  !CDS_PN = "1";
"B":   PN = "2"  !CDS_PN = "2";
BODY = "Q_RES","I58": #LOCATION = "PR6543" !CDS_LOCATION = "PR6543" &SEC = "1" #&CDS_SEC = "1";
"A":   PN = "1"  !CDS_PN = "1";
"B":   PN = "2"  !CDS_PN = "2";
BODY = "Q_RES","I64": #LOCATION = "PR6542" !CDS_LOCATION = "PR6542" &SEC = "1" #&CDS_SEC = "1";
"A":   PN = "1"  !CDS_PN = "1";
"B":   PN = "2"  !CDS_PN = "2";
BODY = "Q_RES","I65": #LOCATION = "PR6541" !CDS_LOCATION = "PR6541" &SEC = "1" #&CDS_SEC = "1";
"A":   PN = "1"  !CDS_PN = "1";
"B":   PN = "2"  !CDS_PN = "2";
BODY = "Q_RES","I68": #LOCATION = "PR6540" !CDS_LOCATION = "PR6540" &SEC = "1" #&CDS_SEC = "1";
"A":   PN = "1"  !CDS_PN = "1";
"B":   PN = "2"  !CDS_PN = "2";
BODY = "Q_RES","I69": #LOCATION = "PR6539" !CDS_LOCATION = "PR6539" &SEC = "1" #&CDS_SEC = "1";
"A":   PN = "1"  !CDS_PN = "1";
"B":   PN = "2"  !CDS_PN = "2";
BODY = "Q_CAP","I72": #LOCATION = "PC6546" !CDS_LOCATION = "PC6546" &SEC = "1" #&CDS_SEC = "1";
"A":   PN = "1"  !CDS_PN = "1";
"B":   PN = "2"  !CDS_PN = "2";
BODY = "Q_CAP","I73": #LOCATION = "PC6545" !CDS_LOCATION = "PC6545" &SEC = "1" #&CDS_SEC = "1";
"A":   PN = "1"  !CDS_PN = "1";
"B":   PN = "2"  !CDS_PN = "2";
BODY = "Q_CAP","I74": #LOCATION = "PC6543" !CDS_LOCATION = "PC6543" &SEC = "1" #&CDS_SEC = "1";
"A":   PN = "1"  !CDS_PN = "1";
"B":   PN = "2"  !CDS_PN = "2";
BODY = "Q_CAP","I75": #LOCATION = "PC6544" !CDS_LOCATION = "PC6544" &SEC = "1" #&CDS_SEC = "1";
"A":   PN = "1"  !CDS_PN = "1";
"B":   PN = "2"  !CDS_PN = "2";
BODY = "Q_RES","I83": #LOCATION = "PR6538" !CDS_LOCATION = "PR6538" &SEC = "1" #&CDS_SEC = "1";
"A":   PN = "1"  !CDS_PN = "1";
"B":   PN = "2"  !CDS_PN = "2";
BODY = "Q_RES","I86": #LOCATION = "PR6812" !CDS_LOCATION = "PR6812" &SEC = "1" #&CDS_SEC = "1";
"A":   PN = "1"  !CDS_PN = "1";
"B":   PN = "2"  !CDS_PN = "2";
BODY = "ISL69260IRAZT","I88": #LOCATION = "PU6510" !CDS_LOCATION = "PU6510" #SEC = "1" !CDS_SEC = "1";
"ADDR_CFG":   PN = "34"  !CDS_PN = "34";
"CFP":   PN = "33"  !CDS_PN = "33";
"CS0":   PN = "30"  !CDS_PN = "30";
"CS1":   PN = "29"  !CDS_PN = "29";
"CS2":   PN = "28"  !CDS_PN = "28";
"CS3":   PN = "27"  !CDS_PN = "27";
"CS4":   PN = "26"  !CDS_PN = "26";
"CS5":   PN = "25"  !CDS_PN = "25";
"CS6":   PN = "24"  !CDS_PN = "24";
"CS7":   PN = "23"  !CDS_PN = "23";
"EN0":   PN = "13"  !CDS_PN = "13";
"EN1":   PN = "20"  !CDS_PN = "20";
"PG0":   PN = "12"  !CDS_PN = "12";
"PG1":   PN = "16"  !CDS_PN = "16";
"PMSCL":   PN = "10"  !CDS_PN = "10";
"PMSDA":   PN = "9"  !CDS_PN = "9";
"PWM0":   PN = "1"  !CDS_PN = "1";
"PWM1":   PN = "2"  !CDS_PN = "2";
"PWM2":   PN = "3"  !CDS_PN = "3";
"PWM3":   PN = "4"  !CDS_PN = "4";
"PWM4":   PN = "5"  !CDS_PN = "5";
"PWM5":   PN = "6"  !CDS_PN = "6";
"PWM6":   PN = "7"  !CDS_PN = "7";
"PWM7":   PN = "8"  !CDS_PN = "8";
"RGND0":   PN = "22"  !CDS_PN = "22";
"RGND1":   PN = "31"  !CDS_PN = "31";
"SVCLK":   PN = "17"  !CDS_PN = "17";
"SVDATA":   PN = "18"  !CDS_PN = "18";
"TEMP0":   PN = "35"  !CDS_PN = "35";
"TEMP1||ISYS":   PN = "36"  !CDS_PN = "36";
"TH_GND":   PN = "TH"  !CDS_PN = "TH";
"VCC":   PN = "39"  !CDS_PN = "39";
"VCCS":   PN = "40"  !CDS_PN = "40";
"VSEN0":   PN = "21"  !CDS_PN = "21";
"VSEN1":   PN = "32"  !CDS_PN = "32";
"NPINALERT#||NPSYSCRIT#":   PN = "15"  !CDS_PN = "15";
"NPMALERT#":   PN = "11"  !CDS_PN = "11";
"NSVALERT#":   PN = "19"  !CDS_PN = "19";
"NVRHOT#":   PN = "14"  !CDS_PN = "14";
"VINSEN||VSYS":   PN = "38"  !CDS_PN = "38";
"VMON||IINSEN||VSYS||ISYS":   PN = "37"  !CDS_PN = "37";
BODY = "Q_RES","I89": #LOCATION = "R660" !CDS_LOCATION = "R660" &SEC = "1" #&CDS_SEC = "1";
"A":   PN = "1"  !CDS_PN = "1";
"B":   PN = "2"  !CDS_PN = "2";
BODY = "Q_RES","I90": #LOCATION = "R6787" !CDS_LOCATION = "R6787" &SEC = "1" #&CDS_SEC = "1";
"A":   PN = "1"  !CDS_PN = "1";
"B":   PN = "2"  !CDS_PN = "2";
BODY = "Q_RES","I92": #LOCATION = "R656" !CDS_LOCATION = "R656" &SEC = "1" #&CDS_SEC = "1";
"A":   PN = "1"  !CDS_PN = "1";
"B":   PN = "2"  !CDS_PN = "2";
BODY = "Q_RES","I93": #LOCATION = "R6861" !CDS_LOCATION = "R6861" &SEC = "1" #&CDS_SEC = "1";
"A":   PN = "1"  !CDS_PN = "1";
"B":   PN = "2"  !CDS_PN = "2";
BODY = "Q_SHORT","I95": #LOCATION = "PJ09_P1_P" !CDS_LOCATION = "PJ09_P1_P" &SEC = "1" #&CDS_SEC = "1";
"1":   PN = "1"  !CDS_PN = "1";
"2":   PN = "2"  !CDS_PN = "2";
BODY = "Q_SHORT","I96": #LOCATION = "PJ09_P1_N" !CDS_LOCATION = "PJ09_P1_N" &SEC = "1" #&CDS_SEC = "1";
"1":   PN = "1"  !CDS_PN = "1";
"2":   PN = "2"  !CDS_PN = "2";
DRAWING = "@t6g_mb_lib.t6g(sch_1):page478";
BODY = "Q_CAP","I2": #LOCATION = "PC6646" !CDS_LOCATION = "PC6646" &SEC = "1" #&CDS_SEC = "1";
"A":   PN = "1"  !CDS_PN = "1";
"B":   PN = "2"  !CDS_PN = "2";
BODY = "Q_RES","I5": #LOCATION = "PR6628" !CDS_LOCATION = "PR6628" &SEC = "1" #&CDS_SEC = "1";
"A":   PN = "1"  !CDS_PN = "1";
"B":   PN = "2"  !CDS_PN = "2";
BODY = "Q_CAP","I10": #LOCATION = "PC6645" !CDS_LOCATION = "PC6645" &SEC = "1" #&CDS_SEC = "1";
"A":   PN = "1"  !CDS_PN = "1";
"B":   PN = "2"  !CDS_PN = "2";
BODY = "Q_RES","I11": #LOCATION = "PR6627" !CDS_LOCATION = "PR6627" &SEC = "1" #&CDS_SEC = "1";
"A":   PN = "1"  !CDS_PN = "1";
"B":   PN = "2"  !CDS_PN = "2";
BODY = "ISL99390FRZTR5935","I12": #LOCATION = "PU6512" !CDS_LOCATION = "PU6512" #SEC = "1" !CDS_SEC = "1";
"AGND":   PN = "2"  !CDS_PN = "2";
"BOOT":   PN = "33"  !CDS_PN = "33";
"DNC":   PN = "31"  !CDS_PN = "31";
"EN":   PN = "35"  !CDS_PN = "35";
"GL1":   PN = "6"  !CDS_PN = "6";
"GL2":   PN = "41"  !CDS_PN = "41";
"IOUT":   PN = "38"  !CDS_PN = "38";
"LSET":   PN = "37"  !CDS_PN = "37";
"PGND1":   PN = "5"  !CDS_PN = "5";
"PGND2":   PN = "7_9-20_24"  !CDS_PN = "7_9-20_24";
"PGND3":   PN = "40"  !CDS_PN = "40";
"PHASE":   PN = "32"  !CDS_PN = "32";
"PVCC":   PN = "4"  !CDS_PN = "4";
"PWM":   PN = "34"  !CDS_PN = "34";
"REFIN":   PN = "39"  !CDS_PN = "39";
"SW":   PN = "10_19"  !CDS_PN = "10_19";
"TOUT_FLT":   PN = "36"  !CDS_PN = "36";
"VCC":   PN = "3"  !CDS_PN = "3";
"VIN1":   PN = "25_29"  !CDS_PN = "25_29";
"VIN2":   PN = "30"  !CDS_PN = "30";
"VOS":   PN = "1"  !CDS_PN = "1";
BODY = "Q_CAP","I14": #LOCATION = "PC6644_09P1_2" !CDS_LOCATION = "PC6644_09P1_2" &SEC = "1" #&CDS_SEC = "1";
"A":   PN = "1"  !CDS_PN = "1";
"B":   PN = "2"  !CDS_PN = "2";
BODY = "Q_RES","I16": #LOCATION = "PR6631" !CDS_LOCATION = "PR6631" &SEC = "1" #&CDS_SEC = "1";
"A":   PN = "1"  !CDS_PN = "1";
"B":   PN = "2"  !CDS_PN = "2";
BODY = "Q_CAP","I18": #LOCATION = "PC6634_2" !CDS_LOCATION = "PC6634_2" &SEC = "1" #&CDS_SEC = "1";
"A":   PN = "1"  !CDS_PN = "1";
"B":   PN = "2"  !CDS_PN = "2";
BODY = "Q_RES","I19": #LOCATION = "PR6629" !CDS_LOCATION = "PR6629" &SEC = "1" #&CDS_SEC = "1";
"A":   PN = "1"  !CDS_PN = "1";
"B":   PN = "2"  !CDS_PN = "2";
BODY = "Q_CAP","I21": #LOCATION = "PC6633_2" !CDS_LOCATION = "PC6633_2" &SEC = "1" #&CDS_SEC = "1";
"A":   PN = "1"  !CDS_PN = "1";
"B":   PN = "2"  !CDS_PN = "2";
BODY = "Q_INDUCTOR","I22": #LOCATION = "PL6512" !CDS_LOCATION = "PL6512" &SEC = "1" #&CDS_SEC = "1";
"1":   PN = "1"  !CDS_PN = "1";
"2":   PN = "2"  !CDS_PN = "2";
BODY = "Q_CAP","I23": #LOCATION = "PC6807" !CDS_LOCATION = "PC6807" &SEC = "1" #&CDS_SEC = "1";
"A":   PN = "1"  !CDS_PN = "1";
"B":   PN = "2"  !CDS_PN = "2";
BODY = "Q_CAP","I25": #LOCATION = "PC6635_2" !CDS_LOCATION = "PC6635_2" &SEC = "1" #&CDS_SEC = "1";
"A":   PN = "1"  !CDS_PN = "1";
"B":   PN = "2"  !CDS_PN = "2";
BODY = "Q_CAP","I26": #LOCATION = "PC6640" !CDS_LOCATION = "PC6640" &SEC = "1" #&CDS_SEC = "1";
"A":   PN = "1"  !CDS_PN = "1";
"B":   PN = "2"  !CDS_PN = "2";
BODY = "Q_CAP","I28": #LOCATION = "PC6636_2" !CDS_LOCATION = "PC6636_2" &SEC = "1" #&CDS_SEC = "1";
"A":   PN = "1"  !CDS_PN = "1";
"B":   PN = "2"  !CDS_PN = "2";
BODY = "Q_CAP","I29": #LOCATION = "PC6642_2" !CDS_LOCATION = "PC6642_2" &SEC = "1" #&CDS_SEC = "1";
"A":   PN = "1"  !CDS_PN = "1";
"B":   PN = "2"  !CDS_PN = "2";
BODY = "Q_CAP","I30": #LOCATION = "PC6643_2" !CDS_LOCATION = "PC6643_2" &SEC = "1" #&CDS_SEC = "1";
"A":   PN = "1"  !CDS_PN = "1";
"B":   PN = "2"  !CDS_PN = "2";
BODY = "Q_CAPP","I31": #LOCATION = "PC6813" !CDS_LOCATION = "PC6813" &SEC = "1" #&CDS_SEC = "1";
"A":   PN = "1"  !CDS_PN = "1";
"B":   PN = "2"  !CDS_PN = "2";
BODY = "Q_CAPP","I32": #LOCATION = "PC6814" !CDS_LOCATION = "PC6814" &SEC = "1" #&CDS_SEC = "1";
"A":   PN = "1"  !CDS_PN = "1";
"B":   PN = "2"  !CDS_PN = "2";
BODY = "Q_CAP","I35": #LOCATION = "PC6637_2" !CDS_LOCATION = "PC6637_2" &SEC = "1" #&CDS_SEC = "1";
"A":   PN = "1"  !CDS_PN = "1";
"B":   PN = "2"  !CDS_PN = "2";
BODY = "Q_CAP","I36": #LOCATION = "PC6638_2" !CDS_LOCATION = "PC6638_2" &SEC = "1" #&CDS_SEC = "1";
"A":   PN = "1"  !CDS_PN = "1";
"B":   PN = "2"  !CDS_PN = "2";
BODY = "Q_CAP","I38": #LOCATION = "PC6639" !CDS_LOCATION = "PC6639" &SEC = "1" #&CDS_SEC = "1";
"A":   PN = "1"  !CDS_PN = "1";
"B":   PN = "2"  !CDS_PN = "2";
BODY = "Q_CAP","I39": #LOCATION = "PC6611_1" !CDS_LOCATION = "PC6611_1" &SEC = "1" #&CDS_SEC = "1";
"A":   PN = "1"  !CDS_PN = "1";
"B":   PN = "2"  !CDS_PN = "2";
BODY = "Q_RES","I42": #LOCATION = "PR6619" !CDS_LOCATION = "PR6619" &SEC = "1" #&CDS_SEC = "1";
"A":   PN = "1"  !CDS_PN = "1";
"B":   PN = "2"  !CDS_PN = "2";
BODY = "Q_RES","I46": #LOCATION = "PR6622" !CDS_LOCATION = "PR6622" &SEC = "1" #&CDS_SEC = "1";
"A":   PN = "1"  !CDS_PN = "1";
"B":   PN = "2"  !CDS_PN = "2";
BODY = "ISL99390FRZTR5935","I51": #LOCATION = "PU6511" !CDS_LOCATION = "PU6511" #SEC = "1" !CDS_SEC = "1";
"AGND":   PN = "2"  !CDS_PN = "2";
"BOOT":   PN = "33"  !CDS_PN = "33";
"DNC":   PN = "31"  !CDS_PN = "31";
"EN":   PN = "35"  !CDS_PN = "35";
"GL1":   PN = "6"  !CDS_PN = "6";
"GL2":   PN = "41"  !CDS_PN = "41";
"IOUT":   PN = "38"  !CDS_PN = "38";
"LSET":   PN = "37"  !CDS_PN = "37";
"PGND1":   PN = "5"  !CDS_PN = "5";
"PGND2":   PN = "7_9-20_24"  !CDS_PN = "7_9-20_24";
"PGND3":   PN = "40"  !CDS_PN = "40";
"PHASE":   PN = "32"  !CDS_PN = "32";
"PVCC":   PN = "4"  !CDS_PN = "4";
"PWM":   PN = "34"  !CDS_PN = "34";
"REFIN":   PN = "39"  !CDS_PN = "39";
"SW":   PN = "10_19"  !CDS_PN = "10_19";
"TOUT_FLT":   PN = "36"  !CDS_PN = "36";
"VCC":   PN = "3"  !CDS_PN = "3";
"VIN1":   PN = "25_29"  !CDS_PN = "25_29";
"VIN2":   PN = "30"  !CDS_PN = "30";
"VOS":   PN = "1"  !CDS_PN = "1";
BODY = "Q_CAP","I52": #LOCATION = "PC6610" !CDS_LOCATION = "PC6610" &SEC = "1" #&CDS_SEC = "1";
"A":   PN = "1"  !CDS_PN = "1";
"B":   PN = "2"  !CDS_PN = "2";
BODY = "Q_RES","I53": #LOCATION = "PR6621" !CDS_LOCATION = "PR6621" &SEC = "1" #&CDS_SEC = "1";
"A":   PN = "1"  !CDS_PN = "1";
"B":   PN = "2"  !CDS_PN = "2";
BODY = "Q_CAP","I55": #LOCATION = "PC6609_09P1_1" !CDS_LOCATION = "PC6609_09P1_1" &SEC = "1" #&CDS_SEC = "1";
"A":   PN = "1"  !CDS_PN = "1";
"B":   PN = "2"  !CDS_PN = "2";
BODY = "Q_RES","I56": #LOCATION = "PR6620" !CDS_LOCATION = "PR6620" &SEC = "1" #&CDS_SEC = "1";
"A":   PN = "1"  !CDS_PN = "1";
"B":   PN = "2"  !CDS_PN = "2";
BODY = "Q_RES","I59": #LOCATION = "PR6626" !CDS_LOCATION = "PR6626" &SEC = "1" #&CDS_SEC = "1";
"A":   PN = "1"  !CDS_PN = "1";
"B":   PN = "2"  !CDS_PN = "2";
BODY = "Q_CAP","I61": #LOCATION = "PC6613_1" !CDS_LOCATION = "PC6613_1" &SEC = "1" #&CDS_SEC = "1";
"A":   PN = "1"  !CDS_PN = "1";
"B":   PN = "2"  !CDS_PN = "2";
BODY = "Q_RES","I62": #LOCATION = "PR6623" !CDS_LOCATION = "PR6623" &SEC = "1" #&CDS_SEC = "1";
"A":   PN = "1"  !CDS_PN = "1";
"B":   PN = "2"  !CDS_PN = "2";
BODY = "Q_CAP","I64": #LOCATION = "PC6612_1" !CDS_LOCATION = "PC6612_1" &SEC = "1" #&CDS_SEC = "1";
"A":   PN = "1"  !CDS_PN = "1";
"B":   PN = "2"  !CDS_PN = "2";
BODY = "Q_INDUCTOR","I65": #LOCATION = "PL6511" !CDS_LOCATION = "PL6511" &SEC = "1" #&CDS_SEC = "1";
"1":   PN = "1"  !CDS_PN = "1";
"2":   PN = "2"  !CDS_PN = "2";
BODY = "Q_CAP","I66": #LOCATION = "PC6623" !CDS_LOCATION = "PC6623" &SEC = "1" #&CDS_SEC = "1";
"A":   PN = "1"  !CDS_PN = "1";
"B":   PN = "2"  !CDS_PN = "2";
BODY = "Q_CAP","I67": #LOCATION = "PC6624_1" !CDS_LOCATION = "PC6624_1" &SEC = "1" #&CDS_SEC = "1";
"A":   PN = "1"  !CDS_PN = "1";
"B":   PN = "2"  !CDS_PN = "2";
BODY = "Q_CAP","I68": #LOCATION = "PC6625_1" !CDS_LOCATION = "PC6625_1" &SEC = "1" #&CDS_SEC = "1";
"A":   PN = "1"  !CDS_PN = "1";
"B":   PN = "2"  !CDS_PN = "2";
BODY = "Q_CAPP","I69": #LOCATION = "PC6626" !CDS_LOCATION = "PC6626" &SEC = "1" #&CDS_SEC = "1";
"A":   PN = "1"  !CDS_PN = "1";
"B":   PN = "2"  !CDS_PN = "2";
BODY = "Q_CAPP","I70": #LOCATION = "PC6627" !CDS_LOCATION = "PC6627" &SEC = "1" #&CDS_SEC = "1";
"A":   PN = "1"  !CDS_PN = "1";
"B":   PN = "2"  !CDS_PN = "2";
BODY = "Q_CAP","I72": #LOCATION = "PC6614_1" !CDS_LOCATION = "PC6614_1" &SEC = "1" #&CDS_SEC = "1";
"A":   PN = "1"  !CDS_PN = "1";
"B":   PN = "2"  !CDS_PN = "2";
BODY = "Q_CAP","I74": #LOCATION = "PC6615_1" !CDS_LOCATION = "PC6615_1" &SEC = "1" #&CDS_SEC = "1";
"A":   PN = "1"  !CDS_PN = "1";
"B":   PN = "2"  !CDS_PN = "2";
BODY = "Q_CAP","I76": #LOCATION = "PC6621" !CDS_LOCATION = "PC6621" &SEC = "1" #&CDS_SEC = "1";
"A":   PN = "1"  !CDS_PN = "1";
"B":   PN = "2"  !CDS_PN = "2";
BODY = "Q_CAP","I77": #LOCATION = "PC6616_1" !CDS_LOCATION = "PC6616_1" &SEC = "1" #&CDS_SEC = "1";
"A":   PN = "1"  !CDS_PN = "1";
"B":   PN = "2"  !CDS_PN = "2";
BODY = "Q_CAP","I79": #LOCATION = "PC6617_1" !CDS_LOCATION = "PC6617_1" &SEC = "1" #&CDS_SEC = "1";
"A":   PN = "1"  !CDS_PN = "1";
"B":   PN = "2"  !CDS_PN = "2";
BODY = "Q_CAP","I80": #LOCATION = "PC6618" !CDS_LOCATION = "PC6618" &SEC = "1" #&CDS_SEC = "1";
"A":   PN = "1"  !CDS_PN = "1";
"B":   PN = "2"  !CDS_PN = "2";
BODY = "Q_CAPP","I82": #LOCATION = "PC6815" !CDS_LOCATION = "PC6815" &SEC = "1" #&CDS_SEC = "1";
"A":   PN = "1"  !CDS_PN = "1";
"B":   PN = "2"  !CDS_PN = "2";
BODY = "Q_CAPP","I83": #LOCATION = "PC6631" !CDS_LOCATION = "PC6631" &SEC = "1" #&CDS_SEC = "1";
"A":   PN = "1"  !CDS_PN = "1";
"B":   PN = "2"  !CDS_PN = "2";
BODY = "Q_CAPP","I84": #LOCATION = "PC6632" !CDS_LOCATION = "PC6632" &SEC = "1" #&CDS_SEC = "1";
"A":   PN = "1"  !CDS_PN = "1";
"B":   PN = "2"  !CDS_PN = "2";
BODY = "Q_CAP","I86": #LOCATION = "PC6818" !CDS_LOCATION = "PC6818" &SEC = "1" #&CDS_SEC = "1";
"A":   PN = "1"  !CDS_PN = "1";
"B":   PN = "2"  !CDS_PN = "2";
BODY = "Q_CAPP","I88": #LOCATION = "PC473" !CDS_LOCATION = "PC473" &SEC = "1" #&CDS_SEC = "1";
"A":   PN = "1"  !CDS_PN = "1";
"B":   PN = "2"  !CDS_PN = "2";
BODY = "Q_CAPP","I93": #LOCATION = "PC6628" !CDS_LOCATION = "PC6628" &SEC = "1" #&CDS_SEC = "1";
"A":   PN = "1"  !CDS_PN = "1";
"B":   PN = "2"  !CDS_PN = "2";
BODY = "Q_CAPP","I94": #LOCATION = "PC6629" !CDS_LOCATION = "PC6629" &SEC = "1" #&CDS_SEC = "1";
"A":   PN = "1"  !CDS_PN = "1";
"B":   PN = "2"  !CDS_PN = "2";
BODY = "Q_CAPP","I95": #LOCATION = "PC6630" !CDS_LOCATION = "PC6630" &SEC = "1" #&CDS_SEC = "1";
"A":   PN = "1"  !CDS_PN = "1";
"B":   PN = "2"  !CDS_PN = "2";
BODY = "Q_RES","I97": #LOCATION = "PR6625" !CDS_LOCATION = "PR6625" &SEC = "1" #&CDS_SEC = "1";
"A":   PN = "1"  !CDS_PN = "1";
"B":   PN = "2"  !CDS_PN = "2";
BODY = "Q_CAP","I100": #LOCATION = "PC6819" !CDS_LOCATION = "PC6819" &SEC = "1" #&CDS_SEC = "1";
"A":   PN = "1"  !CDS_PN = "1";
"B":   PN = "2"  !CDS_PN = "2";
BODY = "Q_CAPP","I102": #LOCATION = "PC6619" !CDS_LOCATION = "PC6619" &SEC = "1" #&CDS_SEC = "1";
"A":   PN = "1"  !CDS_PN = "1";
"B":   PN = "2"  !CDS_PN = "2";
BODY = "Q_INDUCTOR","I104": #LOCATION = "PL6510" !CDS_LOCATION = "PL6510" &SEC = "1" #&CDS_SEC = "1";
"1":   PN = "1"  !CDS_PN = "1";
"2":   PN = "2"  !CDS_PN = "2";
BODY = "Q_RES","I106": #LOCATION = "PR6624" !CDS_LOCATION = "PR6624" &SEC = "1" #&CDS_SEC = "1";
"A":   PN = "1"  !CDS_PN = "1";
"B":   PN = "2"  !CDS_PN = "2";
BODY = "Q_CAP","I108": #LOCATION = "PC6622" !CDS_LOCATION = "PC6622" &SEC = "1" #&CDS_SEC = "1";
"A":   PN = "1"  !CDS_PN = "1";
"B":   PN = "2"  !CDS_PN = "2";
BODY = "Q_CAP","I109": #LOCATION = "PC6641" !CDS_LOCATION = "PC6641" &SEC = "1" #&CDS_SEC = "1";
"A":   PN = "1"  !CDS_PN = "1";
"B":   PN = "2"  !CDS_PN = "2";
BODY = "Q_RES","I110": #LOCATION = "PR6630" !CDS_LOCATION = "PR6630" &SEC = "1" #&CDS_SEC = "1";
"A":   PN = "1"  !CDS_PN = "1";
"B":   PN = "2"  !CDS_PN = "2";
BODY = "Q_CAP","I114": #LOCATION = "PC6620" !CDS_LOCATION = "PC6620" &SEC = "1" #&CDS_SEC = "1";
"A":   PN = "1"  !CDS_PN = "1";
"B":   PN = "2"  !CDS_PN = "2";
DRAWING = "@t6g_mb_lib.t6g(sch_1):page378";
BODY = "TCA9548APWR","I1": #LOCATION = "U6020" !CDS_LOCATION = "U6020" &SEC = "1" #&CDS_SEC = "1";
"A0":   PN = "1"  !CDS_PN = "1";
"A1":   PN = "2"  !CDS_PN = "2";
"A2":   PN = "21"  !CDS_PN = "21";
"GND":   PN = "12"  !CDS_PN = "12";
"RESET#":   PN = "3"  !CDS_PN = "3";
"SC0":   PN = "5"  !CDS_PN = "5";
"SC1":   PN = "7"  !CDS_PN = "7";
"SC2":   PN = "9"  !CDS_PN = "9";
"SC3":   PN = "11"  !CDS_PN = "11";
"SC4":   PN = "14"  !CDS_PN = "14";
"SC5":   PN = "16"  !CDS_PN = "16";
"SC6":   PN = "18"  !CDS_PN = "18";
"SC7":   PN = "20"  !CDS_PN = "20";
"SCL":   PN = "22"  !CDS_PN = "22";
"SD0":   PN = "4"  !CDS_PN = "4";
"SD1":   PN = "6"  !CDS_PN = "6";
"SD2":   PN = "8"  !CDS_PN = "8";
"SD3":   PN = "10"  !CDS_PN = "10";
"SD4":   PN = "13"  !CDS_PN = "13";
"SD5":   PN = "15"  !CDS_PN = "15";
"SD6":   PN = "17"  !CDS_PN = "17";
"SD7":   PN = "19"  !CDS_PN = "19";
"SDA":   PN = "23"  !CDS_PN = "23";
"VCC":   PN = "24"  !CDS_PN = "24";
BODY = "Q_RES","I6": #LOCATION = "R6810" !CDS_LOCATION = "R6810" #SEC = "1" !CDS_SEC = "1";
"A":   PN = "1"  !CDS_PN = "1";
"B":   PN = "2"  !CDS_PN = "2";
BODY = "Q_RES","I7": #LOCATION = "R6811" !CDS_LOCATION = "R6811" #SEC = "1" !CDS_SEC = "1";
"A":   PN = "1"  !CDS_PN = "1";
"B":   PN = "2"  !CDS_PN = "2";
BODY = "Q_RES","I9": #LOCATION = "R6718" !CDS_LOCATION = "R6718" &SEC = "1" #&CDS_SEC = "1";
"A":   PN = "1"  !CDS_PN = "1";
"B":   PN = "2"  !CDS_PN = "2";
BODY = "Q_RES","I11": #LOCATION = "R6719" !CDS_LOCATION = "R6719" &SEC = "1" #&CDS_SEC = "1";
"A":   PN = "1"  !CDS_PN = "1";
"B":   PN = "2"  !CDS_PN = "2";
BODY = "Q_RES","I13": #LOCATION = "R6736" !CDS_LOCATION = "R6736" &SEC = "1" #&CDS_SEC = "1";
"A":   PN = "1"  !CDS_PN = "1";
"B":   PN = "2"  !CDS_PN = "2";
BODY = "Q_RES","I14": #LOCATION = "R6737" !CDS_LOCATION = "R6737" &SEC = "1" #&CDS_SEC = "1";
"A":   PN = "1"  !CDS_PN = "1";
"B":   PN = "2"  !CDS_PN = "2";
BODY = "Q_RES","I17": #LOCATION = "R6738" !CDS_LOCATION = "R6738" &SEC = "1" #&CDS_SEC = "1";
"A":   PN = "1"  !CDS_PN = "1";
"B":   PN = "2"  !CDS_PN = "2";
BODY = "Q_RES","I18": #LOCATION = "R6739" !CDS_LOCATION = "R6739" &SEC = "1" #&CDS_SEC = "1";
"A":   PN = "1"  !CDS_PN = "1";
"B":   PN = "2"  !CDS_PN = "2";
BODY = "Q_RES","I21": #LOCATION = "R6747" !CDS_LOCATION = "R6747" &SEC = "1" #&CDS_SEC = "1";
"A":   PN = "1"  !CDS_PN = "1";
"B":   PN = "2"  !CDS_PN = "2";
BODY = "Q_RES","I22": #LOCATION = "R6746" !CDS_LOCATION = "R6746" &SEC = "1" #&CDS_SEC = "1";
"A":   PN = "1"  !CDS_PN = "1";
"B":   PN = "2"  !CDS_PN = "2";
BODY = "Q_RES","I25": #LOCATION = "R6749" !CDS_LOCATION = "R6749" &SEC = "1" #&CDS_SEC = "1";
"A":   PN = "1"  !CDS_PN = "1";
"B":   PN = "2"  !CDS_PN = "2";
BODY = "Q_RES","I26": #LOCATION = "R6748" !CDS_LOCATION = "R6748" &SEC = "1" #&CDS_SEC = "1";
"A":   PN = "1"  !CDS_PN = "1";
"B":   PN = "2"  !CDS_PN = "2";
BODY = "Q_RES","I31": #LOCATION = "R6750" !CDS_LOCATION = "R6750" &SEC = "1" #&CDS_SEC = "1";
"A":   PN = "1"  !CDS_PN = "1";
"B":   PN = "2"  !CDS_PN = "2";
BODY = "Q_RES","I32": #LOCATION = "R6751" !CDS_LOCATION = "R6751" &SEC = "1" #&CDS_SEC = "1";
"A":   PN = "1"  !CDS_PN = "1";
"B":   PN = "2"  !CDS_PN = "2";
BODY = "Q_RES","I35": #LOCATION = "R6752" !CDS_LOCATION = "R6752" &SEC = "1" #&CDS_SEC = "1";
"A":   PN = "1"  !CDS_PN = "1";
"B":   PN = "2"  !CDS_PN = "2";
BODY = "Q_RES","I36": #LOCATION = "R6753" !CDS_LOCATION = "R6753" &SEC = "1" #&CDS_SEC = "1";
"A":   PN = "1"  !CDS_PN = "1";
"B":   PN = "2"  !CDS_PN = "2";
BODY = "Q_RES","I53": #LOCATION = "R6754" !CDS_LOCATION = "R6754" #SEC = "1" !CDS_SEC = "1";
"A":   PN = "1"  !CDS_PN = "1";
"B":   PN = "2"  !CDS_PN = "2";
BODY = "Q_RES","I54": #LOCATION = "R6755" !CDS_LOCATION = "R6755" #SEC = "1" !CDS_SEC = "1";
"A":   PN = "1"  !CDS_PN = "1";
"B":   PN = "2"  !CDS_PN = "2";
BODY = "Q_RES","I55": #LOCATION = "R6758" !CDS_LOCATION = "R6758" &SEC = "1" #&CDS_SEC = "1";
"A":   PN = "1"  !CDS_PN = "1";
"B":   PN = "2"  !CDS_PN = "2";
BODY = "Q_RES","I56": #LOCATION = "R6756" !CDS_LOCATION = "R6756" &SEC = "1" #&CDS_SEC = "1";
"A":   PN = "1"  !CDS_PN = "1";
"B":   PN = "2"  !CDS_PN = "2";
BODY = "Q_RES","I57": #LOCATION = "R6757" !CDS_LOCATION = "R6757" &SEC = "1" #&CDS_SEC = "1";
"A":   PN = "1"  !CDS_PN = "1";
"B":   PN = "2"  !CDS_PN = "2";
BODY = "Q_RES","I58": #LOCATION = "R6760" !CDS_LOCATION = "R6760" &SEC = "1" #&CDS_SEC = "1";
"A":   PN = "1"  !CDS_PN = "1";
"B":   PN = "2"  !CDS_PN = "2";
BODY = "Q_RES","I59": #LOCATION = "R6759" !CDS_LOCATION = "R6759" &SEC = "1" #&CDS_SEC = "1";
"A":   PN = "1"  !CDS_PN = "1";
"B":   PN = "2"  !CDS_PN = "2";
BODY = "Q_RES","I60": #LOCATION = "R6761" !CDS_LOCATION = "R6761" &SEC = "1" #&CDS_SEC = "1";
"A":   PN = "1"  !CDS_PN = "1";
"B":   PN = "2"  !CDS_PN = "2";
BODY = "Q_RES","I77": #LOCATION = "R6762" !CDS_LOCATION = "R6762" &SEC = "1" #&CDS_SEC = "1";
"A":   PN = "1"  !CDS_PN = "1";
"B":   PN = "2"  !CDS_PN = "2";
BODY = "Q_RES","I78": #LOCATION = "R6763" !CDS_LOCATION = "R6763" &SEC = "1" #&CDS_SEC = "1";
"A":   PN = "1"  !CDS_PN = "1";
"B":   PN = "2"  !CDS_PN = "2";
BODY = "Q_RES","I79": #LOCATION = "R6764" !CDS_LOCATION = "R6764" &SEC = "1" #&CDS_SEC = "1";
"A":   PN = "1"  !CDS_PN = "1";
"B":   PN = "2"  !CDS_PN = "2";
BODY = "Q_RES","I80": #LOCATION = "R6765" !CDS_LOCATION = "R6765" &SEC = "1" #&CDS_SEC = "1";
"A":   PN = "1"  !CDS_PN = "1";
"B":   PN = "2"  !CDS_PN = "2";
BODY = "Q_RES","I82": #LOCATION = "R6767" !CDS_LOCATION = "R6767" &SEC = "1" #&CDS_SEC = "1";
"A":   PN = "1"  !CDS_PN = "1";
"B":   PN = "2"  !CDS_PN = "2";
BODY = "Q_RES","I83": #LOCATION = "R6766" !CDS_LOCATION = "R6766" &SEC = "1" #&CDS_SEC = "1";
"A":   PN = "1"  !CDS_PN = "1";
"B":   PN = "2"  !CDS_PN = "2";
BODY = "Q_RES","I84": #LOCATION = "R6768" !CDS_LOCATION = "R6768" &SEC = "1" #&CDS_SEC = "1";
"A":   PN = "1"  !CDS_PN = "1";
"B":   PN = "2"  !CDS_PN = "2";
BODY = "Q_RES","I85": #LOCATION = "R6769" !CDS_LOCATION = "R6769" &SEC = "1" #&CDS_SEC = "1";
"A":   PN = "1"  !CDS_PN = "1";
"B":   PN = "2"  !CDS_PN = "2";
BODY = "Q_CAP","I88": #LOCATION = "C7500" !CDS_LOCATION = "C7500" &SEC = "1" #&CDS_SEC = "1";
"A":   PN = "1"  !CDS_PN = "1";
"B":   PN = "2"  !CDS_PN = "2";
BODY = "Q_RES","I94": #LOCATION = "R6773" !CDS_LOCATION = "R6773" &SEC = "1" #&CDS_SEC = "1";
"A":   PN = "1"  !CDS_PN = "1";
"B":   PN = "2"  !CDS_PN = "2";
BODY = "Q_RES","I95": #LOCATION = "R6774" !CDS_LOCATION = "R6774" &SEC = "1" #&CDS_SEC = "1";
"A":   PN = "1"  !CDS_PN = "1";
"B":   PN = "2"  !CDS_PN = "2";
BODY = "Q_RES","I96": #LOCATION = "R6770" !CDS_LOCATION = "R6770" &SEC = "1" #&CDS_SEC = "1";
"A":   PN = "1"  !CDS_PN = "1";
"B":   PN = "2"  !CDS_PN = "2";
BODY = "Q_RES","I97": #LOCATION = "R6775" !CDS_LOCATION = "R6775" &SEC = "1" #&CDS_SEC = "1";
"A":   PN = "1"  !CDS_PN = "1";
"B":   PN = "2"  !CDS_PN = "2";
BODY = "Q_RES","I98": #LOCATION = "R6772" !CDS_LOCATION = "R6772" &SEC = "1" #&CDS_SEC = "1";
"A":   PN = "1"  !CDS_PN = "1";
"B":   PN = "2"  !CDS_PN = "2";
BODY = "Q_RES","I100": #LOCATION = "R6771" !CDS_LOCATION = "R6771" &SEC = "1" #&CDS_SEC = "1";
"A":   PN = "1"  !CDS_PN = "1";
"B":   PN = "2"  !CDS_PN = "2";
BODY = "Q_RES","I104": #LOCATION = "R6776" !CDS_LOCATION = "R6776" &SEC = "1" #&CDS_SEC = "1";
"A":   PN = "1"  !CDS_PN = "1";
"B":   PN = "2"  !CDS_PN = "2";
BODY = "Q_RES","I107": #LOCATION = "R6778" !CDS_LOCATION = "R6778" &SEC = "1" #&CDS_SEC = "1";
"A":   PN = "1"  !CDS_PN = "1";
"B":   PN = "2"  !CDS_PN = "2";
BODY = "CONN3_210HP1030BR1","I116": #LOCATION = "JP6500" !CDS_LOCATION = "JP6500" &SEC = "1" #&CDS_SEC = "1";
"1":   PN = "1"  !CDS_PN = "1";
"2":   PN = "2"  !CDS_PN = "2";
"3":   PN = "3"  !CDS_PN = "3";
BODY = "Q_RES","I117": #LOCATION = "R1515" !CDS_LOCATION = "R1515" &SEC = "1" #&CDS_SEC = "1";
"A":   PN = "1"  !CDS_PN = "1";
"B":   PN = "2"  !CDS_PN = "2";
BODY = "Q_RES","I118": #LOCATION = "R1514" !CDS_LOCATION = "R1514" &SEC = "1" #&CDS_SEC = "1";
"A":   PN = "1"  !CDS_PN = "1";
"B":   PN = "2"  !CDS_PN = "2";
BODY = "Q_RES","I119": #LOCATION = "R6779" !CDS_LOCATION = "R6779" #SEC = "1" !CDS_SEC = "1";
"A":   PN = "1"  !CDS_PN = "1";
"B":   PN = "2"  !CDS_PN = "2";
BODY = "Q_RES","I120": #LOCATION = "R6780" !CDS_LOCATION = "R6780" #SEC = "1" !CDS_SEC = "1";
"A":   PN = "1"  !CDS_PN = "1";
"B":   PN = "2"  !CDS_PN = "2";
DRAWING = "@t6g_mb_lib.t6g(sch_1):page408";
BODY = "Q_RES","I15": #LOCATION = "R612" !CDS_LOCATION = "R612" #SEC = "1" !CDS_SEC = "1";
"A":   PN = "1"  !CDS_PN = "1";
"B":   PN = "2"  !CDS_PN = "2";
BODY = "Q_RES","I18": #LOCATION = "R629" !CDS_LOCATION = "R629" &SEC = "1" #&CDS_SEC = "1";
"A":   PN = "1"  !CDS_PN = "1";
"B":   PN = "2"  !CDS_PN = "2";
BODY = "Q_RES","I19": #LOCATION = "R630" !CDS_LOCATION = "R630" &SEC = "1" #&CDS_SEC = "1";
"A":   PN = "1"  !CDS_PN = "1";
"B":   PN = "2"  !CDS_PN = "2";
BODY = "Q_RES","I20": #LOCATION = "R611" !CDS_LOCATION = "R611" #SEC = "1" !CDS_SEC = "1";
"A":   PN = "1"  !CDS_PN = "1";
"B":   PN = "2"  !CDS_PN = "2";
BODY = "Q_RES","I5": #LOCATION = "R1021" !CDS_LOCATION = "R1021" &SEC = "1" #&CDS_SEC = "1";
"A":   PN = "1"  !CDS_PN = "1";
"B":   PN = "2"  !CDS_PN = "2";
BODY = "Q_RES","I7": #LOCATION = "R1028" !CDS_LOCATION = "R1028" &SEC = "1" #&CDS_SEC = "1";
"A":   PN = "1"  !CDS_PN = "1";
"B":   PN = "2"  !CDS_PN = "2";
BODY = "Q_RES","I8": #LOCATION = "R1029" !CDS_LOCATION = "R1029" &SEC = "1" #&CDS_SEC = "1";
"A":   PN = "1"  !CDS_PN = "1";
"B":   PN = "2"  !CDS_PN = "2";
BODY = "Q_RES","I9": #LOCATION = "R1031" !CDS_LOCATION = "R1031" &SEC = "1" #&CDS_SEC = "1";
"A":   PN = "1"  !CDS_PN = "1";
"B":   PN = "2"  !CDS_PN = "2";
BODY = "Q_RES","I10": #LOCATION = "R1027" !CDS_LOCATION = "R1027" &SEC = "1" #&CDS_SEC = "1";
"A":   PN = "1"  !CDS_PN = "1";
"B":   PN = "2"  !CDS_PN = "2";
BODY = "Q_RES","I11": #LOCATION = "R1030" !CDS_LOCATION = "R1030" &SEC = "1" #&CDS_SEC = "1";
"A":   PN = "1"  !CDS_PN = "1";
"B":   PN = "2"  !CDS_PN = "2";
BODY = "Q_RES","I21": #LOCATION = "R677" !CDS_LOCATION = "R677" &SEC = "1" #&CDS_SEC = "1";
"A":   PN = "1"  !CDS_PN = "1";
"B":   PN = "2"  !CDS_PN = "2";
BODY = "Q_RES","I22": #LOCATION = "R676" !CDS_LOCATION = "R676" &SEC = "1" #&CDS_SEC = "1";
"A":   PN = "1"  !CDS_PN = "1";
"B":   PN = "2"  !CDS_PN = "2";
BODY = "Q_RES","I29": #LOCATION = "R1026" !CDS_LOCATION = "R1026" &SEC = "1" #&CDS_SEC = "1";
"A":   PN = "1"  !CDS_PN = "1";
"B":   PN = "2"  !CDS_PN = "2";
BODY = "Q_RES","I30": #LOCATION = "R1025" !CDS_LOCATION = "R1025" &SEC = "1" #&CDS_SEC = "1";
"A":   PN = "1"  !CDS_PN = "1";
"B":   PN = "2"  !CDS_PN = "2";
BODY = "Q_RES","I36": #LOCATION = "R1033" !CDS_LOCATION = "R1033" &SEC = "1" #&CDS_SEC = "1";
"A":   PN = "1"  !CDS_PN = "1";
"B":   PN = "2"  !CDS_PN = "2";
BODY = "Q_RES","I37": #LOCATION = "R1035" !CDS_LOCATION = "R1035" &SEC = "1" #&CDS_SEC = "1";
"A":   PN = "1"  !CDS_PN = "1";
"B":   PN = "2"  !CDS_PN = "2";
BODY = "Q_RES","I39": #LOCATION = "R1037" !CDS_LOCATION = "R1037" &SEC = "1" #&CDS_SEC = "1";
"A":   PN = "1"  !CDS_PN = "1";
"B":   PN = "2"  !CDS_PN = "2";
BODY = "Q_RES","I40": #LOCATION = "R1032" !CDS_LOCATION = "R1032" &SEC = "1" #&CDS_SEC = "1";
"A":   PN = "1"  !CDS_PN = "1";
"B":   PN = "2"  !CDS_PN = "2";
BODY = "Q_RES","I41": #LOCATION = "R1034" !CDS_LOCATION = "R1034" &SEC = "1" #&CDS_SEC = "1";
"A":   PN = "1"  !CDS_PN = "1";
"B":   PN = "2"  !CDS_PN = "2";
BODY = "Q_RES","I42": #LOCATION = "R1024" !CDS_LOCATION = "R1024" &SEC = "1" #&CDS_SEC = "1";
"A":   PN = "1"  !CDS_PN = "1";
"B":   PN = "2"  !CDS_PN = "2";
BODY = "Q_RES","I50": #LOCATION = "R1006" !CDS_LOCATION = "R1006" &SEC = "1" #&CDS_SEC = "1";
"A":   PN = "1"  !CDS_PN = "1";
"B":   PN = "2"  !CDS_PN = "2";
BODY = "Q_RES","I51": #LOCATION = "R1039" !CDS_LOCATION = "R1039" &SEC = "1" #&CDS_SEC = "1";
"A":   PN = "1"  !CDS_PN = "1";
"B":   PN = "2"  !CDS_PN = "2";
BODY = "Q_RES","I55": #LOCATION = "R1012" !CDS_LOCATION = "R1012" &SEC = "1" #&CDS_SEC = "1";
"A":   PN = "1"  !CDS_PN = "1";
"B":   PN = "2"  !CDS_PN = "2";
BODY = "Q_RES","I56": #LOCATION = "R1004" !CDS_LOCATION = "R1004" #SEC = "1" !CDS_SEC = "1";
"A":   PN = "1"  !CDS_PN = "1";
"B":   PN = "2"  !CDS_PN = "2";
BODY = "Q_RES","I64": #LOCATION = "R1014" !CDS_LOCATION = "R1014" &SEC = "1" #&CDS_SEC = "1";
"A":   PN = "1"  !CDS_PN = "1";
"B":   PN = "2"  !CDS_PN = "2";
BODY = "Q_RES","I65": #LOCATION = "R1016" !CDS_LOCATION = "R1016" &SEC = "1" #&CDS_SEC = "1";
"A":   PN = "1"  !CDS_PN = "1";
"B":   PN = "2"  !CDS_PN = "2";
BODY = "Q_RES","I66": #LOCATION = "R1013" !CDS_LOCATION = "R1013" &SEC = "1" #&CDS_SEC = "1";
"A":   PN = "1"  !CDS_PN = "1";
"B":   PN = "2"  !CDS_PN = "2";
BODY = "Q_RES","I67": #LOCATION = "R1015" !CDS_LOCATION = "R1015" &SEC = "1" #&CDS_SEC = "1";
"A":   PN = "1"  !CDS_PN = "1";
"B":   PN = "2"  !CDS_PN = "2";
BODY = "Q_RES","I68": #LOCATION = "R1018" !CDS_LOCATION = "R1018" &SEC = "1" #&CDS_SEC = "1";
"A":   PN = "1"  !CDS_PN = "1";
"B":   PN = "2"  !CDS_PN = "2";
BODY = "Q_RES","I69": #LOCATION = "R1017" !CDS_LOCATION = "R1017" &SEC = "1" #&CDS_SEC = "1";
"A":   PN = "1"  !CDS_PN = "1";
"B":   PN = "2"  !CDS_PN = "2";
BODY = "Q_RES","I73": #LOCATION = "R1019" !CDS_LOCATION = "R1019" &SEC = "1" #&CDS_SEC = "1";
"A":   PN = "1"  !CDS_PN = "1";
"B":   PN = "2"  !CDS_PN = "2";
BODY = "Q_RES","I74": #LOCATION = "R1020" !CDS_LOCATION = "R1020" &SEC = "1" #&CDS_SEC = "1";
"A":   PN = "1"  !CDS_PN = "1";
"B":   PN = "2"  !CDS_PN = "2";
BODY = "Q_RES","I78": #LOCATION = "R1023" !CDS_LOCATION = "R1023" &SEC = "1" #&CDS_SEC = "1";
"A":   PN = "1"  !CDS_PN = "1";
"B":   PN = "2"  !CDS_PN = "2";
BODY = "PT5161LRS","I83": #LOCATION = "U6011" !CDS_LOCATION = "U6011" &SEC = "3" #&CDS_SEC = "3";
"CLKREQ_N":   PN = "G35"  !CDS_PN = "G35";
"EE_CLK":   PN = "FF5"  !CDS_PN = "FF5";
"EE_DAT":   PN = "FJ3"  !CDS_PN = "FJ3";
"GPIO0":   PN = "FJ6"  !CDS_PN = "FJ6";
"GPIO1":   PN = "FJ23"  !CDS_PN = "FJ23";
"GPIO2":   PN = "FJ25"  !CDS_PN = "FJ25";
"GPIO3":   PN = "FJ28"  !CDS_PN = "FJ28";
"INT_N":   PN = "FJ31"  !CDS_PN = "FJ31";
"JTAG_TCK":   PN = "B3"  !CDS_PN = "B3";
"JTAG_TDI":   PN = "B6"  !CDS_PN = "B6";
"JTAG_TDO":   PN = "B9"  !CDS_PN = "B9";
"JTAG_TEST_MODE":   PN = "FF8"  !CDS_PN = "FF8";
"JTAG_TMS":   PN = "B12"  !CDS_PN = "B12";
"JTAG_TRST_N":   PN = "E8"  !CDS_PN = "E8";
"MODE":   PN = "FJ9"  !CDS_PN = "FJ9";
"PERST_N":   PN = "F2"  !CDS_PN = "F2";
"REFCLK_OUTN":   PN = "E18"  !CDS_PN = "E18";
"REFCLK_OUTP":   PN = "B16"  !CDS_PN = "B16";
"REFCLKN":   PN = "FF18"  !CDS_PN = "FF18";
"REFCLKP":   PN = "FJ16"  !CDS_PN = "FJ16";
"RESET_N":   PN = "FF11"  !CDS_PN = "FF11";
"RXDET_BYP":   PN = "E11"  !CDS_PN = "E11";
"SCAN_MODE":   PN = "FF33"  !CDS_PN = "FF33";
"SMB_ADDR1":   PN = "F34"  !CDS_PN = "F34";
"SMB_ADDR2":   PN = "B23"  !CDS_PN = "B23";
"SMB_ADDR3":   PN = "B25"  !CDS_PN = "B25";
"SMBCLK":   PN = "B31"  !CDS_PN = "B31";
"SMBDAT":   PN = "B28"  !CDS_PN = "B28";
"T_SENSE":   PN = "E30"  !CDS_PN = "E30";
"TEST0":   PN = "FF24"  !CDS_PN = "FF24";
"TEST1":   PN = "FF27"  !CDS_PN = "FF27";
"TEST2":   PN = "FF30"  !CDS_PN = "FF30";
BODY = "Q_RES","I84": #LOCATION = "R1391" !CDS_LOCATION = "R1391" &SEC = "1" #&CDS_SEC = "1";
"A":   PN = "1"  !CDS_PN = "1";
"B":   PN = "2"  !CDS_PN = "2";
BODY = "Q_RES","I94": #LOCATION = "R1395" !CDS_LOCATION = "R1395" &SEC = "1" #&CDS_SEC = "1";
"A":   PN = "1"  !CDS_PN = "1";
"B":   PN = "2"  !CDS_PN = "2";
BODY = "Q_RES","I98": #LOCATION = "R1398" !CDS_LOCATION = "R1398" &SEC = "1" #&CDS_SEC = "1";
"A":   PN = "1"  !CDS_PN = "1";
"B":   PN = "2"  !CDS_PN = "2";
BODY = "Q_RES","I99": #LOCATION = "R1397" !CDS_LOCATION = "R1397" &SEC = "1" #&CDS_SEC = "1";
"A":   PN = "1"  !CDS_PN = "1";
"B":   PN = "2"  !CDS_PN = "2";
BODY = "Q_RES","I102": #LOCATION = "R1022" !CDS_LOCATION = "R1022" &SEC = "1" #&CDS_SEC = "1";
"A":   PN = "1"  !CDS_PN = "1";
"B":   PN = "2"  !CDS_PN = "2";
BODY = "Q_RES","I115": #LOCATION = "R1470" !CDS_LOCATION = "R1470" &SEC = "1" #&CDS_SEC = "1";
"A":   PN = "1"  !CDS_PN = "1";
"B":   PN = "2"  !CDS_PN = "2";
BODY = "Q_RES","I116": #LOCATION = "R1471" !CDS_LOCATION = "R1471" &SEC = "1" #&CDS_SEC = "1";
"A":   PN = "1"  !CDS_PN = "1";
"B":   PN = "2"  !CDS_PN = "2";
BODY = "Q_RES","I119": #LOCATION = "R1392" !CDS_LOCATION = "R1392" &SEC = "1" #&CDS_SEC = "1";
"A":   PN = "1"  !CDS_PN = "1";
"B":   PN = "2"  !CDS_PN = "2";
BODY = "Q_RES","I121": #LOCATION = "R1472" !CDS_LOCATION = "R1472" &SEC = "1" #&CDS_SEC = "1";
"A":   PN = "1"  !CDS_PN = "1";
"B":   PN = "2"  !CDS_PN = "2";
BODY = "Q_RES","I122": #LOCATION = "R1473" !CDS_LOCATION = "R1473" &SEC = "1" #&CDS_SEC = "1";
"A":   PN = "1"  !CDS_PN = "1";
"B":   PN = "2"  !CDS_PN = "2";
DRAWING = "@t6g_mb_lib.t6g(sch_1):page156";
BODY = "CONN2_AAABAT029Y19","I86": #LOCATION = "BT2" !CDS_LOCATION = "BT2" &SEC = "1" #&CDS_SEC = "1";
"1":   PN = "1"  !CDS_PN = "1";
"2":   PN = "2"  !CDS_PN = "2";
BODY = "TPS71715DCKR","I91": #LOCATION = "U9" !CDS_LOCATION = "U9" #SEC = "1" !CDS_SEC = "1";
"EN":   PN = "3"  !CDS_PN = "3";
"GND":   PN = "2"  !CDS_PN = "2";
"IN":   PN = "1"  !CDS_PN = "1";
"NR||FB":   PN = "4"  !CDS_PN = "4";
"OUT":   PN = "5"  !CDS_PN = "5";
BODY = "Q_RES","I94": #LOCATION = "R1776" !CDS_LOCATION = "R1776" &SEC = "1" #&CDS_SEC = "1";
"A":   PN = "1"  !CDS_PN = "1";
"B":   PN = "2"  !CDS_PN = "2";
BODY = "Q_CAP","I95": #LOCATION = "C1563" !CDS_LOCATION = "C1563" &SEC = "1" #&CDS_SEC = "1";
"A":   PN = "1"  !CDS_PN = "1";
"B":   PN = "2"  !CDS_PN = "2";
BODY = "Q_RES","I97": #LOCATION = "R5101" !CDS_LOCATION = "R5101" &SEC = "1" #&CDS_SEC = "1";
"A":   PN = "1"  !CDS_PN = "1";
"B":   PN = "2"  !CDS_PN = "2";
BODY = "SCHOTTKY_DUAL_12A_3C","I99": #LOCATION = "U166" !CDS_LOCATION = "U166" &SEC = "1" #&CDS_SEC = "1";
"A":   PN = "2"  !CDS_PN = "2";
"B":   PN = "1"  !CDS_PN = "1";
"C":   PN = "3"  !CDS_PN = "3";
BODY = "Q_RES","I100": #LOCATION = "R5052" !CDS_LOCATION = "R5052" &SEC = "1" #&CDS_SEC = "1";
"A":   PN = "1"  !CDS_PN = "1";
"B":   PN = "2"  !CDS_PN = "2";
BODY = "Q_RES","I101": #LOCATION = "R5051" !CDS_LOCATION = "R5051" &SEC = "1" #&CDS_SEC = "1";
"A":   PN = "1"  !CDS_PN = "1";
"B":   PN = "2"  !CDS_PN = "2";
BODY = "MOSFET_DUAL_6P","I104": #LOCATION = "Q8" !CDS_LOCATION = "Q8" &SEC = "1" #&CDS_SEC = "1";
"D1":   PN = "6"  !CDS_PN = "6";
"D2":   PN = "3"  !CDS_PN = "3";
"G1":   PN = "2"  !CDS_PN = "2";
"G2":   PN = "5"  !CDS_PN = "5";
"S1":   PN = "1"  !CDS_PN = "1";
"S2":   PN = "4"  !CDS_PN = "4";
BODY = "Q_CAP","I107": #LOCATION = "C45" !CDS_LOCATION = "C45" &SEC = "1" #&CDS_SEC = "1";
"A":   PN = "1"  !CDS_PN = "1";
"B":   PN = "2"  !CDS_PN = "2";
BODY = "Q_CAP","I108": #LOCATION = "C193" !CDS_LOCATION = "C193" &SEC = "1" #&CDS_SEC = "1";
"A":   PN = "1"  !CDS_PN = "1";
"B":   PN = "2"  !CDS_PN = "2";
BODY = "Q_CAP","I113": #LOCATION = "C22" !CDS_LOCATION = "C22" &SEC = "1" #&CDS_SEC = "1";
"A":   PN = "1"  !CDS_PN = "1";
"B":   PN = "2"  !CDS_PN = "2";
BODY = "Q_RES","I116": #LOCATION = "R1779" !CDS_LOCATION = "R1779" &SEC = "1" #&CDS_SEC = "1";
"A":   PN = "1"  !CDS_PN = "1";
"B":   PN = "2"  !CDS_PN = "2";
BODY = "Q_CAP","I118": #LOCATION = "C1564" !CDS_LOCATION = "C1564" &SEC = "1" #&CDS_SEC = "1";
"A":   PN = "1"  !CDS_PN = "1";
"B":   PN = "2"  !CDS_PN = "2";
BODY = "Q_RES","I120": #LOCATION = "R5053" !CDS_LOCATION = "R5053" &SEC = "1" #&CDS_SEC = "1";
"A":   PN = "1"  !CDS_PN = "1";
"B":   PN = "2"  !CDS_PN = "2";
BODY = "Q_RES","I122": #LOCATION = "R5054" !CDS_LOCATION = "R5054" &SEC = "1" #&CDS_SEC = "1";
"A":   PN = "1"  !CDS_PN = "1";
"B":   PN = "2"  !CDS_PN = "2";
BODY = "Q_CAP","I125": #LOCATION = "C1567" !CDS_LOCATION = "C1567" &SEC = "1" #&CDS_SEC = "1";
"A":   PN = "1"  !CDS_PN = "1";
"B":   PN = "2"  !CDS_PN = "2";
BODY = "Q_CAP","I126": #LOCATION = "C5032" !CDS_LOCATION = "C5032" &SEC = "1" #&CDS_SEC = "1";
"A":   PN = "1"  !CDS_PN = "1";
"B":   PN = "2"  !CDS_PN = "2";
BODY = "CONN3_210HP1030BR1","I128": #LOCATION = "JP12" !CDS_LOCATION = "JP12" &SEC = "1" #&CDS_SEC = "1";
"1":   PN = "1"  !CDS_PN = "1";
"2":   PN = "2"  !CDS_PN = "2";
"3":   PN = "3"  !CDS_PN = "3";
BODY = "Q_RES","I129": #LOCATION = "R1777" !CDS_LOCATION = "R1777" &SEC = "1" #&CDS_SEC = "1";
"A":   PN = "1"  !CDS_PN = "1";
"B":   PN = "2"  !CDS_PN = "2";
BODY = "NCP698SQ15T1G","I130": #LOCATION = "U167" !CDS_LOCATION = "U167" &SEC = "1" #&CDS_SEC = "1";
"EN":   PN = "4"  !CDS_PN = "4";
"GND":   PN = "1"  !CDS_PN = "1";
"VIN":   PN = "2"  !CDS_PN = "2";
"VOUT":   PN = "3"  !CDS_PN = "3";
BODY = "Q_RES","I131": #LOCATION = "R1775" !CDS_LOCATION = "R1775" &SEC = "1" #&CDS_SEC = "1";
"A":   PN = "1"  !CDS_PN = "1";
"B":   PN = "2"  !CDS_PN = "2";
DRAWING = "@t6g_mb_lib.t6g(sch_1):page391";
BODY = "PT5161LRS","I5": #LOCATION = "U6015" !CDS_LOCATION = "U6015" &SEC = "4" #&CDS_SEC = "4";
"PWR_1A_1":   PN = "BV20"  !CDS_PN = "BV20";
"PWR_1A_2":   PN = "CE17"  !CDS_PN = "CE17";
"PWR_1A_3":   PN = "CE20"  !CDS_PN = "CE20";
"PWR_1A_4":   PN = "CM17"  !CDS_PN = "CM17";
"PWR_1A_5":   PN = "CM20"  !CDS_PN = "CM20";
"PWR_1D":   PN = "BV17"  !CDS_PN = "BV17";
"PWR_2A_1":   PN = "AC17"  !CDS_PN = "AC17";
"PWR_2A_2":   PN = "AC20"  !CDS_PN = "AC20";
"PWR_2A_3":   PN = "AK17"  !CDS_PN = "AK17";
"PWR_2A_4":   PN = "AK20"  !CDS_PN = "AK20";
"PWR_2A_5":   PN = "AU17"  !CDS_PN = "AU17";
"PWR_2A_6":   PN = "AU20"  !CDS_PN = "AU20";
"PWR_2A_7":   PN = "BD17"  !CDS_PN = "BD17";
"PWR_2A_8":   PN = "BD20"  !CDS_PN = "BD20";
"PWR_2A_9":   PN = "DF17"  !CDS_PN = "DF17";
"PWR_2A_10":   PN = "DF20"  !CDS_PN = "DF20";
"PWR_2A_11":   PN = "DN17"  !CDS_PN = "DN17";
"PWR_2A_12":   PN = "DN20"  !CDS_PN = "DN20";
"PWR_2A_13":   PN = "DY17"  !CDS_PN = "DY17";
"PWR_2A_14":   PN = "DY20"  !CDS_PN = "DY20";
"PWR_2A_15":   PN = "EG17"  !CDS_PN = "EG17";
"PWR_2A_16":   PN = "EG20"  !CDS_PN = "EG20";
"PWR_2A_17":   PN = "EP17"  !CDS_PN = "EP17";
"PWR_2A_18":   PN = "EP20"  !CDS_PN = "EP20";
"PWR_2A_19":   PN = "T17"  !CDS_PN = "T17";
"PWR_2A_20":   PN = "T20"  !CDS_PN = "T20";
"PWR_2D_1":   PN = "BL17"  !CDS_PN = "BL17";
"PWR_2D_2":   PN = "BL20"  !CDS_PN = "BL20";
"PWR_2D_3":   PN = "CW17"  !CDS_PN = "CW17";
"PWR_2D_4":   PN = "CW20"  !CDS_PN = "CW20";
"VQPS":   PN = "G1"  !CDS_PN = "G1";
BODY = "Q_RES","I15": #LOCATION = "R6733" !CDS_LOCATION = "R6733" &SEC = "1" #&CDS_SEC = "1";
"A":   PN = "1"  !CDS_PN = "1";
"B":   PN = "2"  !CDS_PN = "2";
BODY = "Q_RES","I16": #LOCATION = "R6732" !CDS_LOCATION = "R6732" &SEC = "1" #&CDS_SEC = "1";
"A":   PN = "1"  !CDS_PN = "1";
"B":   PN = "2"  !CDS_PN = "2";
BODY = "PT5161LRS","I19": #LOCATION = "U6015" !CDS_LOCATION = "U6015" &SEC = "5" #&CDS_SEC = "5";
"GND1":   PN = "AC13"  !CDS_PN = "AC13";
"GND2":   PN = "AC22"  !CDS_PN = "AC22";
"GND3":   PN = "AC32"  !CDS_PN = "AC32";
"GND4":   PN = "AC4"  !CDS_PN = "AC4";
"GND5":   PN = "AD2"  !CDS_PN = "AD2";
"GND6":   PN = "AD34"  !CDS_PN = "AD34";
"GND7":   PN = "AE1"  !CDS_PN = "AE1";
"GND8":   PN = "AE35"  !CDS_PN = "AE35";
"GND9":   PN = "AK13"  !CDS_PN = "AK13";
"GND10":   PN = "AK22"  !CDS_PN = "AK22";
"GND11":   PN = "AK32"  !CDS_PN = "AK32";
"GND12":   PN = "AK4"  !CDS_PN = "AK4";
"GND13":   PN = "AL2"  !CDS_PN = "AL2";
"GND14":   PN = "AL34"  !CDS_PN = "AL34";
"GND15":   PN = "AM1"  !CDS_PN = "AM1";
"GND16":   PN = "AM35"  !CDS_PN = "AM35";
"GND17":   PN = "AU13"  !CDS_PN = "AU13";
"GND18":   PN = "AU22"  !CDS_PN = "AU22";
"GND19":   PN = "AU32"  !CDS_PN = "AU32";
"GND20":   PN = "AU4"  !CDS_PN = "AU4";
"GND21":   PN = "AV2"  !CDS_PN = "AV2";
"GND22":   PN = "AV34"  !CDS_PN = "AV34";
"GND23":   PN = "AW1"  !CDS_PN = "AW1";
"GND24":   PN = "AW35"  !CDS_PN = "AW35";
"GND25":   PN = "B19"  !CDS_PN = "B19";
"GND26":   PN = "BD13"  !CDS_PN = "BD13";
"GND27":   PN = "BD22"  !CDS_PN = "BD22";
"GND28":   PN = "BD32"  !CDS_PN = "BD32";
"GND29":   PN = "BD4"  !CDS_PN = "BD4";
"GND30":   PN = "BE2"  !CDS_PN = "BE2";
"GND31":   PN = "BE34"  !CDS_PN = "BE34";
"GND32":   PN = "BF1"  !CDS_PN = "BF1";
"GND33":   PN = "BF35"  !CDS_PN = "BF35";
"GND34":   PN = "BL13"  !CDS_PN = "BL13";
"GND35":   PN = "BL22"  !CDS_PN = "BL22";
"GND36":   PN = "BL32"  !CDS_PN = "BL32";
"GND37":   PN = "BL4"  !CDS_PN = "BL4";
"GND38":   PN = "BM2"  !CDS_PN = "BM2";
"GND39":   PN = "BM34"  !CDS_PN = "BM34";
"GND40":   PN = "BN1"  !CDS_PN = "BN1";
"GND41":   PN = "BN35"  !CDS_PN = "BN35";
"GND42":   PN = "BV13"  !CDS_PN = "BV13";
"GND43":   PN = "BV22"  !CDS_PN = "BV22";
"GND44":   PN = "BV32"  !CDS_PN = "BV32";
"GND45":   PN = "BV4"  !CDS_PN = "BV4";
"GND46":   PN = "BW2"  !CDS_PN = "BW2";
"GND47":   PN = "BW34"  !CDS_PN = "BW34";
"GND48":   PN = "BY1"  !CDS_PN = "BY1";
"GND49":   PN = "BY35"  !CDS_PN = "BY35";
"GND50":   PN = "CE13"  !CDS_PN = "CE13";
"GND51":   PN = "CE22"  !CDS_PN = "CE22";
"GND52":   PN = "CE32"  !CDS_PN = "CE32";
"GND53":   PN = "CE4"  !CDS_PN = "CE4";
"GND54":   PN = "CF2"  !CDS_PN = "CF2";
"GND55":   PN = "CF34"  !CDS_PN = "CF34";
"GND56":   PN = "CG1"  !CDS_PN = "CG1";
"GND57":   PN = "CG35"  !CDS_PN = "CG35";
"GND58":   PN = "CM13"  !CDS_PN = "CM13";
"GND59":   PN = "CM22"  !CDS_PN = "CM22";
"GND60":   PN = "CM32"  !CDS_PN = "CM32";
"GND61":   PN = "CM4"  !CDS_PN = "CM4";
"GND62":   PN = "CN2"  !CDS_PN = "CN2";
"GND63":   PN = "CN34"  !CDS_PN = "CN34";
"GND64":   PN = "CP1"  !CDS_PN = "CP1";
"GND65":   PN = "CP35"  !CDS_PN = "CP35";
"GND66":   PN = "CW13"  !CDS_PN = "CW13";
"GND67":   PN = "CW22"  !CDS_PN = "CW22";
"GND68":   PN = "CW32"  !CDS_PN = "CW32";
"GND69":   PN = "CW4"  !CDS_PN = "CW4";
"GND70":   PN = "CY2"  !CDS_PN = "CY2";
"GND71":   PN = "CY34"  !CDS_PN = "CY34";
"GND72":   PN = "DA1"  !CDS_PN = "DA1";
"GND73":   PN = "DA35"  !CDS_PN = "DA35";
"GND74":   PN = "DF13"  !CDS_PN = "DF13";
"GND75":   PN = "DF22"  !CDS_PN = "DF22";
"GND76":   PN = "DF32"  !CDS_PN = "DF32";
"GND77":   PN = "DF4"  !CDS_PN = "DF4";
"GND78":   PN = "DG2"  !CDS_PN = "DG2";
"GND79":   PN = "DG34"  !CDS_PN = "DG34";
"GND80":   PN = "DH1"  !CDS_PN = "DH1";
"GND81":   PN = "DH35"  !CDS_PN = "DH35";
"GND82":   PN = "DN13"  !CDS_PN = "DN13";
"GND83":   PN = "DN22"  !CDS_PN = "DN22";
"GND84":   PN = "DN32"  !CDS_PN = "DN32";
"GND85":   PN = "DN4"  !CDS_PN = "DN4";
"GND86":   PN = "DP2"  !CDS_PN = "DP2";
"GND87":   PN = "DP34"  !CDS_PN = "DP34";
"GND88":   PN = "DR1"  !CDS_PN = "DR1";
"GND89":   PN = "DR35"  !CDS_PN = "DR35";
"GND90":   PN = "DY13"  !CDS_PN = "DY13";
"GND91":   PN = "DY22"  !CDS_PN = "DY22";
"GND92":   PN = "DY32"  !CDS_PN = "DY32";
"GND93":   PN = "DY4"  !CDS_PN = "DY4";
"GND94":   PN = "E14"  !CDS_PN = "E14";
"GND95":   PN = "E27"  !CDS_PN = "E27";
"GND96":   PN = "E33"  !CDS_PN = "E33";
"GND97":   PN = "EA2"  !CDS_PN = "EA2";
"GND98":   PN = "EA34"  !CDS_PN = "EA34";
"GND99":   PN = "EB1"  !CDS_PN = "EB1";
"GND100":   PN = "EB35"  !CDS_PN = "EB35";
"GND101":   PN = "EG13"  !CDS_PN = "EG13";
"GND102":   PN = "EG22"  !CDS_PN = "EG22";
"GND103":   PN = "EG32"  !CDS_PN = "EG32";
"GND104":   PN = "EG4"  !CDS_PN = "EG4";
"GND105":   PN = "EH2"  !CDS_PN = "EH2";
"GND106":   PN = "EH34"  !CDS_PN = "EH34";
"GND107":   PN = "EJ1"  !CDS_PN = "EJ1";
"GND108":   PN = "EJ35"  !CDS_PN = "EJ35";
"GND109":   PN = "EP13"  !CDS_PN = "EP13";
"GND110":   PN = "EP22"  !CDS_PN = "EP22";
"GND111":   PN = "EP32"  !CDS_PN = "EP32";
"GND112":   PN = "EP4"  !CDS_PN = "EP4";
"GND113":   PN = "ER2"  !CDS_PN = "ER2";
"GND114":   PN = "ER34"  !CDS_PN = "ER34";
"GND115":   PN = "ET1"  !CDS_PN = "ET1";
"GND116":   PN = "ET35"  !CDS_PN = "ET35";
"GND117":   PN = "FA15"  !CDS_PN = "FA15";
"GND118":   PN = "FA32"  !CDS_PN = "FA32";
"GND119":   PN = "FB2"  !CDS_PN = "FB2";
"GND120":   PN = "FB34"  !CDS_PN = "FB34";
"GND121":   PN = "FC19"  !CDS_PN = "FC19";
"GND122":   PN = "FC23"  !CDS_PN = "FC23";
"GND123":   PN = "FC25"  !CDS_PN = "FC25";
"GND124":   PN = "FC28"  !CDS_PN = "FC28";
"GND125":   PN = "FC3"  !CDS_PN = "FC3";
"GND126":   PN = "FC6"  !CDS_PN = "FC6";
"GND127":   PN = "FC9"  !CDS_PN = "FC9";
"GND128":   PN = "FD1"  !CDS_PN = "FD1";
"GND129":   PN = "FD35"  !CDS_PN = "FD35";
"GND130":   PN = "FF14"  !CDS_PN = "FF14";
"GND131":   PN = "FF21"  !CDS_PN = "FF21";
"GND132":   PN = "FJ12"  !CDS_PN = "FJ12";
"GND133":   PN = "FJ19"  !CDS_PN = "FJ19";
"GND134":   PN = "H12"  !CDS_PN = "H12";
"GND135":   PN = "H16"  !CDS_PN = "H16";
"GND136":   PN = "H19"  !CDS_PN = "H19";
"GND137":   PN = "H31"  !CDS_PN = "H31";
"GND138":   PN = "J22"  !CDS_PN = "J22";
"GND139":   PN = "J4"  !CDS_PN = "J4";
"GND140":   PN = "K2"  !CDS_PN = "K2";
"GND141":   PN = "K34"  !CDS_PN = "K34";
"GND142":   PN = "L1"  !CDS_PN = "L1";
"GND143":   PN = "L35"  !CDS_PN = "L35";
"GND144":   PN = "T13"  !CDS_PN = "T13";
"GND145":   PN = "T22"  !CDS_PN = "T22";
"GND146":   PN = "T32"  !CDS_PN = "T32";
"GND147":   PN = "T4"  !CDS_PN = "T4";
"GND148":   PN = "U2"  !CDS_PN = "U2";
"GND149":   PN = "U34"  !CDS_PN = "U34";
"GND150":   PN = "V1"  !CDS_PN = "V1";
"GND151":   PN = "V35"  !CDS_PN = "V35";
"NCF_GND1":   PN = "A1"  !CDS_PN = "A1";
"NCF_GND2":   PN = "A35"  !CDS_PN = "A35";
"NCF_GND3":   PN = "C2"  !CDS_PN = "C2";
"NCF_GND4":   PN = "C34"  !CDS_PN = "C34";
"NCF_GND5":   PN = "D1"  !CDS_PN = "D1";
"NCF_GND6":   PN = "D35"  !CDS_PN = "D35";
"NCF_GND7":   PN = "FE2"  !CDS_PN = "FE2";
"NCF_GND8":   PN = "FE34"  !CDS_PN = "FE34";
"NCF_GND9":   PN = "FG1"  !CDS_PN = "FG1";
"NCF_GND10":   PN = "FG35"  !CDS_PN = "FG35";
"NCF_GND11":   PN = "FH2"  !CDS_PN = "FH2";
"NCF_GND12":   PN = "FH34"  !CDS_PN = "FH34";
BODY = "Q_RES","I20": #LOCATION = "R6731" !CDS_LOCATION = "R6731" &SEC = "1" #&CDS_SEC = "1";
"A":   PN = "1"  !CDS_PN = "1";
"B":   PN = "2"  !CDS_PN = "2";
BODY = "Q_RES","I21": #LOCATION = "R6730" !CDS_LOCATION = "R6730" &SEC = "1" #&CDS_SEC = "1";
"A":   PN = "1"  !CDS_PN = "1";
"B":   PN = "2"  !CDS_PN = "2";
DRAWING = "@t6g_mb_lib.t6g(sch_1):page443";
BODY = "Q_RES","I4": #LOCATION = "R664" !CDS_LOCATION = "R664" #SEC = "1" !CDS_SEC = "1";
"A":   PN = "1"  !CDS_PN = "1";
"B":   PN = "2"  !CDS_PN = "2";
BODY = "Q_RES","I5": #LOCATION = "R653" !CDS_LOCATION = "R653" #SEC = "1" !CDS_SEC = "1";
"A":   PN = "1"  !CDS_PN = "1";
"B":   PN = "2"  !CDS_PN = "2";
BODY = "Q_CAP","I8": #LOCATION = "C203" !CDS_LOCATION = "C203" &SEC = "1" #&CDS_SEC = "1";
"A":   PN = "1"  !CDS_PN = "1";
"B":   PN = "2"  !CDS_PN = "2";
BODY = "Q_CAP","I9": #LOCATION = "C206" !CDS_LOCATION = "C206" &SEC = "1" #&CDS_SEC = "1";
"A":   PN = "1"  !CDS_PN = "1";
"B":   PN = "2"  !CDS_PN = "2";
BODY = "Q_RES","I10": #LOCATION = "R705" !CDS_LOCATION = "R705" &SEC = "1" #&CDS_SEC = "1";
"A":   PN = "1"  !CDS_PN = "1";
"B":   PN = "2"  !CDS_PN = "2";
BODY = "Q_RES","I11": #LOCATION = "R712" !CDS_LOCATION = "R712" &SEC = "1" #&CDS_SEC = "1";
"A":   PN = "1"  !CDS_PN = "1";
"B":   PN = "2"  !CDS_PN = "2";
BODY = "Q_INDUCTOR","I12": #LOCATION = "L5" !CDS_LOCATION = "L5" &SEC = "1" #&CDS_SEC = "1";
"1":   PN = "1"  !CDS_PN = "1";
"2":   PN = "2"  !CDS_PN = "2";
BODY = "Q_CAP","I13": #LOCATION = "C103" !CDS_LOCATION = "C103" &SEC = "1" #&CDS_SEC = "1";
"A":   PN = "1"  !CDS_PN = "1";
"B":   PN = "2"  !CDS_PN = "2";
BODY = "Q_CAP","I14": #LOCATION = "C111" !CDS_LOCATION = "C111" &SEC = "1" #&CDS_SEC = "1";
"A":   PN = "1"  !CDS_PN = "1";
"B":   PN = "2"  !CDS_PN = "2";
BODY = "Q_CAP","I16": #LOCATION = "C102" !CDS_LOCATION = "C102" &SEC = "1" #&CDS_SEC = "1";
"A":   PN = "1"  !CDS_PN = "1";
"B":   PN = "2"  !CDS_PN = "2";
BODY = "Q_CAP","I17": #LOCATION = "C199" !CDS_LOCATION = "C199" &SEC = "1" #&CDS_SEC = "1";
"A":   PN = "1"  !CDS_PN = "1";
"B":   PN = "2"  !CDS_PN = "2";
BODY = "Q_CAP","I18": #LOCATION = "C195" !CDS_LOCATION = "C195" &SEC = "1" #&CDS_SEC = "1";
"A":   PN = "1"  !CDS_PN = "1";
"B":   PN = "2"  !CDS_PN = "2";
BODY = "Q_CAP","I20": #LOCATION = "C202" !CDS_LOCATION = "C202" &SEC = "1" #&CDS_SEC = "1";
"A":   PN = "1"  !CDS_PN = "1";
"B":   PN = "2"  !CDS_PN = "2";
BODY = "Q_CAP","I22": #LOCATION = "C204" !CDS_LOCATION = "C204" &SEC = "1" #&CDS_SEC = "1";
"A":   PN = "1"  !CDS_PN = "1";
"B":   PN = "2"  !CDS_PN = "2";
BODY = "Q_CAP","I23": #LOCATION = "C205" !CDS_LOCATION = "C205" &SEC = "1" #&CDS_SEC = "1";
"A":   PN = "1"  !CDS_PN = "1";
"B":   PN = "2"  !CDS_PN = "2";
BODY = "Q_CAP","I24": #LOCATION = "C110" !CDS_LOCATION = "C110" &SEC = "1" #&CDS_SEC = "1";
"A":   PN = "1"  !CDS_PN = "1";
"B":   PN = "2"  !CDS_PN = "2";
BODY = "Q_CAP","I25": #LOCATION = "C127" !CDS_LOCATION = "C127" &SEC = "1" #&CDS_SEC = "1";
"A":   PN = "1"  !CDS_PN = "1";
"B":   PN = "2"  !CDS_PN = "2";
BODY = "Q_CAP","I26": #LOCATION = "C200" !CDS_LOCATION = "C200" &SEC = "1" #&CDS_SEC = "1";
"A":   PN = "1"  !CDS_PN = "1";
"B":   PN = "2"  !CDS_PN = "2";
BODY = "Q_CAP","I27": #LOCATION = "C217" !CDS_LOCATION = "C217" &SEC = "1" #&CDS_SEC = "1";
"A":   PN = "1"  !CDS_PN = "1";
"B":   PN = "2"  !CDS_PN = "2";
BODY = "Q_CAP","I28": #LOCATION = "C287" !CDS_LOCATION = "C287" &SEC = "1" #&CDS_SEC = "1";
"A":   PN = "1"  !CDS_PN = "1";
"B":   PN = "2"  !CDS_PN = "2";
BODY = "Q_CAP","I29": #LOCATION = "C288" !CDS_LOCATION = "C288" &SEC = "1" #&CDS_SEC = "1";
"A":   PN = "1"  !CDS_PN = "1";
"B":   PN = "2"  !CDS_PN = "2";
BODY = "Q_INDUCTOR","I30": #LOCATION = "L6" !CDS_LOCATION = "L6" &SEC = "1" #&CDS_SEC = "1";
"1":   PN = "1"  !CDS_PN = "1";
"2":   PN = "2"  !CDS_PN = "2";
BODY = "Q_CAP","I34": #LOCATION = "C313" !CDS_LOCATION = "C313" &SEC = "1" #&CDS_SEC = "1";
"A":   PN = "1"  !CDS_PN = "1";
"B":   PN = "2"  !CDS_PN = "2";
BODY = "Q_CAP","I37": #LOCATION = "C316" !CDS_LOCATION = "C316" &SEC = "1" #&CDS_SEC = "1";
"A":   PN = "1"  !CDS_PN = "1";
"B":   PN = "2"  !CDS_PN = "2";
BODY = "Q_CAP","I38": #LOCATION = "C340" !CDS_LOCATION = "C340" &SEC = "1" #&CDS_SEC = "1";
"A":   PN = "1"  !CDS_PN = "1";
"B":   PN = "2"  !CDS_PN = "2";
BODY = "Q_CAP","I39": #LOCATION = "C344" !CDS_LOCATION = "C344" &SEC = "1" #&CDS_SEC = "1";
"A":   PN = "1"  !CDS_PN = "1";
"B":   PN = "2"  !CDS_PN = "2";
BODY = "Q_CAP","I40": #LOCATION = "C294" !CDS_LOCATION = "C294" &SEC = "1" #&CDS_SEC = "1";
"A":   PN = "1"  !CDS_PN = "1";
"B":   PN = "2"  !CDS_PN = "2";
BODY = "Q_CAP","I41": #LOCATION = "C332" !CDS_LOCATION = "C332" &SEC = "1" #&CDS_SEC = "1";
"A":   PN = "1"  !CDS_PN = "1";
"B":   PN = "2"  !CDS_PN = "2";
BODY = "Q_CAP","I42": #LOCATION = "C307" !CDS_LOCATION = "C307" &SEC = "1" #&CDS_SEC = "1";
"A":   PN = "1"  !CDS_PN = "1";
"B":   PN = "2"  !CDS_PN = "2";
BODY = "Q_CAP","I43": #LOCATION = "C326" !CDS_LOCATION = "C326" &SEC = "1" #&CDS_SEC = "1";
"A":   PN = "1"  !CDS_PN = "1";
"B":   PN = "2"  !CDS_PN = "2";
BODY = "Q_CAP","I44": #LOCATION = "C321" !CDS_LOCATION = "C321" &SEC = "1" #&CDS_SEC = "1";
"A":   PN = "1"  !CDS_PN = "1";
"B":   PN = "2"  !CDS_PN = "2";
BODY = "Q_CAP","I45": #LOCATION = "C325" !CDS_LOCATION = "C325" &SEC = "1" #&CDS_SEC = "1";
"A":   PN = "1"  !CDS_PN = "1";
"B":   PN = "2"  !CDS_PN = "2";
BODY = "Q_CAP","I46": #LOCATION = "C331" !CDS_LOCATION = "C331" &SEC = "1" #&CDS_SEC = "1";
"A":   PN = "1"  !CDS_PN = "1";
"B":   PN = "2"  !CDS_PN = "2";
BODY = "Q_CAP","I47": #LOCATION = "C330" !CDS_LOCATION = "C330" &SEC = "1" #&CDS_SEC = "1";
"A":   PN = "1"  !CDS_PN = "1";
"B":   PN = "2"  !CDS_PN = "2";
BODY = "Q_CAP","I48": #LOCATION = "C312" !CDS_LOCATION = "C312" &SEC = "1" #&CDS_SEC = "1";
"A":   PN = "1"  !CDS_PN = "1";
"B":   PN = "2"  !CDS_PN = "2";
BODY = "Q_CAP","I49": #LOCATION = "C349" !CDS_LOCATION = "C349" &SEC = "1" #&CDS_SEC = "1";
"A":   PN = "1"  !CDS_PN = "1";
"B":   PN = "2"  !CDS_PN = "2";
BODY = "Q_CAP","I50": #LOCATION = "C291" !CDS_LOCATION = "C291" &SEC = "1" #&CDS_SEC = "1";
"A":   PN = "1"  !CDS_PN = "1";
"B":   PN = "2"  !CDS_PN = "2";
BODY = "Q_CAP","I51": #LOCATION = "C319" !CDS_LOCATION = "C319" &SEC = "1" #&CDS_SEC = "1";
"A":   PN = "1"  !CDS_PN = "1";
"B":   PN = "2"  !CDS_PN = "2";
BODY = "Q_CAP","I52": #LOCATION = "C314" !CDS_LOCATION = "C314" &SEC = "1" #&CDS_SEC = "1";
"A":   PN = "1"  !CDS_PN = "1";
"B":   PN = "2"  !CDS_PN = "2";
BODY = "Q_CAP","I53": #LOCATION = "C337" !CDS_LOCATION = "C337" &SEC = "1" #&CDS_SEC = "1";
"A":   PN = "1"  !CDS_PN = "1";
"B":   PN = "2"  !CDS_PN = "2";
BODY = "Q_CAP","I54": #LOCATION = "C343" !CDS_LOCATION = "C343" &SEC = "1" #&CDS_SEC = "1";
"A":   PN = "1"  !CDS_PN = "1";
"B":   PN = "2"  !CDS_PN = "2";
BODY = "Q_CAP","I55": #LOCATION = "C336" !CDS_LOCATION = "C336" &SEC = "1" #&CDS_SEC = "1";
"A":   PN = "1"  !CDS_PN = "1";
"B":   PN = "2"  !CDS_PN = "2";
BODY = "Q_CAP","I57": #LOCATION = "C346" !CDS_LOCATION = "C346" &SEC = "1" #&CDS_SEC = "1";
"A":   PN = "1"  !CDS_PN = "1";
"B":   PN = "2"  !CDS_PN = "2";
BODY = "Q_CAP","I58": #LOCATION = "C293" !CDS_LOCATION = "C293" &SEC = "1" #&CDS_SEC = "1";
"A":   PN = "1"  !CDS_PN = "1";
"B":   PN = "2"  !CDS_PN = "2";
BODY = "Q_CAP","I59": #LOCATION = "C301" !CDS_LOCATION = "C301" &SEC = "1" #&CDS_SEC = "1";
"A":   PN = "1"  !CDS_PN = "1";
"B":   PN = "2"  !CDS_PN = "2";
BODY = "Q_CAP","I60": #LOCATION = "C322" !CDS_LOCATION = "C322" &SEC = "1" #&CDS_SEC = "1";
"A":   PN = "1"  !CDS_PN = "1";
"B":   PN = "2"  !CDS_PN = "2";
BODY = "Q_CAP","I62": #LOCATION = "C334" !CDS_LOCATION = "C334" &SEC = "1" #&CDS_SEC = "1";
"A":   PN = "1"  !CDS_PN = "1";
"B":   PN = "2"  !CDS_PN = "2";
BODY = "Q_CAP","I65": #LOCATION = "C289" !CDS_LOCATION = "C289" &SEC = "1" #&CDS_SEC = "1";
"A":   PN = "1"  !CDS_PN = "1";
"B":   PN = "2"  !CDS_PN = "2";
BODY = "Q_CAP","I66": #LOCATION = "C353" !CDS_LOCATION = "C353" &SEC = "1" #&CDS_SEC = "1";
"A":   PN = "1"  !CDS_PN = "1";
"B":   PN = "2"  !CDS_PN = "2";
BODY = "Q_CAP","I67": #LOCATION = "C317" !CDS_LOCATION = "C317" &SEC = "1" #&CDS_SEC = "1";
"A":   PN = "1"  !CDS_PN = "1";
"B":   PN = "2"  !CDS_PN = "2";
BODY = "Q_CAP","I69": #LOCATION = "C320" !CDS_LOCATION = "C320" &SEC = "1" #&CDS_SEC = "1";
"A":   PN = "1"  !CDS_PN = "1";
"B":   PN = "2"  !CDS_PN = "2";
BODY = "Q_CAP","I70": #LOCATION = "C324" !CDS_LOCATION = "C324" &SEC = "1" #&CDS_SEC = "1";
"A":   PN = "1"  !CDS_PN = "1";
"B":   PN = "2"  !CDS_PN = "2";
BODY = "Q_CAP","I71": #LOCATION = "C328" !CDS_LOCATION = "C328" &SEC = "1" #&CDS_SEC = "1";
"A":   PN = "1"  !CDS_PN = "1";
"B":   PN = "2"  !CDS_PN = "2";
BODY = "Q_CAP","I72": #LOCATION = "C323" !CDS_LOCATION = "C323" &SEC = "1" #&CDS_SEC = "1";
"A":   PN = "1"  !CDS_PN = "1";
"B":   PN = "2"  !CDS_PN = "2";
BODY = "Q_CAP","I73": #LOCATION = "C327" !CDS_LOCATION = "C327" &SEC = "1" #&CDS_SEC = "1";
"A":   PN = "1"  !CDS_PN = "1";
"B":   PN = "2"  !CDS_PN = "2";
BODY = "Q_CAP","I74": #LOCATION = "C329" !CDS_LOCATION = "C329" &SEC = "1" #&CDS_SEC = "1";
"A":   PN = "1"  !CDS_PN = "1";
"B":   PN = "2"  !CDS_PN = "2";
BODY = "Q_CAP","I75": #LOCATION = "C335" !CDS_LOCATION = "C335" &SEC = "1" #&CDS_SEC = "1";
"A":   PN = "1"  !CDS_PN = "1";
"B":   PN = "2"  !CDS_PN = "2";
BODY = "Q_CAP","I76": #LOCATION = "C351" !CDS_LOCATION = "C351" &SEC = "1" #&CDS_SEC = "1";
"A":   PN = "1"  !CDS_PN = "1";
"B":   PN = "2"  !CDS_PN = "2";
BODY = "Q_CAP","I77": #LOCATION = "C318" !CDS_LOCATION = "C318" &SEC = "1" #&CDS_SEC = "1";
"A":   PN = "1"  !CDS_PN = "1";
"B":   PN = "2"  !CDS_PN = "2";
BODY = "Q_CAP","I78": #LOCATION = "C338" !CDS_LOCATION = "C338" &SEC = "1" #&CDS_SEC = "1";
"A":   PN = "1"  !CDS_PN = "1";
"B":   PN = "2"  !CDS_PN = "2";
BODY = "Q_CAP","I79": #LOCATION = "C342" !CDS_LOCATION = "C342" &SEC = "1" #&CDS_SEC = "1";
"A":   PN = "1"  !CDS_PN = "1";
"B":   PN = "2"  !CDS_PN = "2";
BODY = "Q_CAP","I80": #LOCATION = "C339" !CDS_LOCATION = "C339" &SEC = "1" #&CDS_SEC = "1";
"A":   PN = "1"  !CDS_PN = "1";
"B":   PN = "2"  !CDS_PN = "2";
BODY = "Q_CAP","I81": #LOCATION = "C354" !CDS_LOCATION = "C354" &SEC = "1" #&CDS_SEC = "1";
"A":   PN = "1"  !CDS_PN = "1";
"B":   PN = "2"  !CDS_PN = "2";
BODY = "Q_CAP","I82": #LOCATION = "C300" !CDS_LOCATION = "C300" &SEC = "1" #&CDS_SEC = "1";
"A":   PN = "1"  !CDS_PN = "1";
"B":   PN = "2"  !CDS_PN = "2";
BODY = "Q_CAP","I84": #LOCATION = "C311" !CDS_LOCATION = "C311" &SEC = "1" #&CDS_SEC = "1";
"A":   PN = "1"  !CDS_PN = "1";
"B":   PN = "2"  !CDS_PN = "2";
BODY = "Q_CAP","I85": #LOCATION = "C292" !CDS_LOCATION = "C292" &SEC = "1" #&CDS_SEC = "1";
"A":   PN = "1"  !CDS_PN = "1";
"B":   PN = "2"  !CDS_PN = "2";
BODY = "Q_CAP","I86": #LOCATION = "C290" !CDS_LOCATION = "C290" &SEC = "1" #&CDS_SEC = "1";
"A":   PN = "1"  !CDS_PN = "1";
"B":   PN = "2"  !CDS_PN = "2";
BODY = "Q_CAP","I87": #LOCATION = "C333" !CDS_LOCATION = "C333" &SEC = "1" #&CDS_SEC = "1";
"A":   PN = "1"  !CDS_PN = "1";
"B":   PN = "2"  !CDS_PN = "2";
BODY = "Q_INDUCTOR","I88": #LOCATION = "L31" !CDS_LOCATION = "L31" &SEC = "1" #&CDS_SEC = "1";
"1":   PN = "1"  !CDS_PN = "1";
"2":   PN = "2"  !CDS_PN = "2";
BODY = "Q_RES","I89": #LOCATION = "R704" !CDS_LOCATION = "R704" &SEC = "1" #&CDS_SEC = "1";
"A":   PN = "1"  !CDS_PN = "1";
"B":   PN = "2"  !CDS_PN = "2";
BODY = "Q_CAP","I90": #LOCATION = "C306" !CDS_LOCATION = "C306" &SEC = "1" #&CDS_SEC = "1";
"A":   PN = "1"  !CDS_PN = "1";
"B":   PN = "2"  !CDS_PN = "2";
BODY = "Q_CAP","I91": #LOCATION = "C315" !CDS_LOCATION = "C315" &SEC = "1" #&CDS_SEC = "1";
"A":   PN = "1"  !CDS_PN = "1";
"B":   PN = "2"  !CDS_PN = "2";
BODY = "Q_CAP","I92": #LOCATION = "C341" !CDS_LOCATION = "C341" &SEC = "1" #&CDS_SEC = "1";
"A":   PN = "1"  !CDS_PN = "1";
"B":   PN = "2"  !CDS_PN = "2";
BODY = "Q_CAP","I93": #LOCATION = "C350" !CDS_LOCATION = "C350" &SEC = "1" #&CDS_SEC = "1";
"A":   PN = "1"  !CDS_PN = "1";
"B":   PN = "2"  !CDS_PN = "2";
BODY = "Q_CAPP","I94": #LOCATION = "C7023" !CDS_LOCATION = "C7023" &SEC = "1" #&CDS_SEC = "1";
"A":   PN = "1"  !CDS_PN = "1";
"B":   PN = "2"  !CDS_PN = "2";
BODY = "Q_CAPP","I95": #LOCATION = "C7024" !CDS_LOCATION = "C7024" &SEC = "1" #&CDS_SEC = "1";
"A":   PN = "1"  !CDS_PN = "1";
"B":   PN = "2"  !CDS_PN = "2";
BODY = "Q_CAP","I96": #LOCATION = "C7025" !CDS_LOCATION = "C7025" &SEC = "1" #&CDS_SEC = "1";
"A":   PN = "1"  !CDS_PN = "1";
"B":   PN = "2"  !CDS_PN = "2";
DRAWING = "@t6g_mb_lib.t6g(sch_1):page392";
BODY = "Q_RES","I19": #LOCATION = "R755" !CDS_LOCATION = "R755" &SEC = "1" #&CDS_SEC = "1";
"A":   PN = "1"  !CDS_PN = "1";
"B":   PN = "2"  !CDS_PN = "2";
BODY = "Q_RES","I21": #LOCATION = "R782" !CDS_LOCATION = "R782" &SEC = "1" #&CDS_SEC = "1";
"A":   PN = "1"  !CDS_PN = "1";
"B":   PN = "2"  !CDS_PN = "2";
BODY = "Q_RES","I22": #LOCATION = "R783" !CDS_LOCATION = "R783" &SEC = "1" #&CDS_SEC = "1";
"A":   PN = "1"  !CDS_PN = "1";
"B":   PN = "2"  !CDS_PN = "2";
BODY = "Q_RES","I23": #LOCATION = "R785" !CDS_LOCATION = "R785" &SEC = "1" #&CDS_SEC = "1";
"A":   PN = "1"  !CDS_PN = "1";
"B":   PN = "2"  !CDS_PN = "2";
BODY = "Q_RES","I24": #LOCATION = "R781" !CDS_LOCATION = "R781" &SEC = "1" #&CDS_SEC = "1";
"A":   PN = "1"  !CDS_PN = "1";
"B":   PN = "2"  !CDS_PN = "2";
BODY = "Q_RES","I25": #LOCATION = "R784" !CDS_LOCATION = "R784" &SEC = "1" #&CDS_SEC = "1";
"A":   PN = "1"  !CDS_PN = "1";
"B":   PN = "2"  !CDS_PN = "2";
BODY = "Q_RES","I31": #LOCATION = "R625" !CDS_LOCATION = "R625" &SEC = "1" #&CDS_SEC = "1";
"A":   PN = "1"  !CDS_PN = "1";
"B":   PN = "2"  !CDS_PN = "2";
BODY = "Q_RES","I32": #LOCATION = "R626" !CDS_LOCATION = "R626" &SEC = "1" #&CDS_SEC = "1";
"A":   PN = "1"  !CDS_PN = "1";
"B":   PN = "2"  !CDS_PN = "2";
BODY = "Q_RES","I33": #LOCATION = "R597" !CDS_LOCATION = "R597" #SEC = "1" !CDS_SEC = "1";
"A":   PN = "1"  !CDS_PN = "1";
"B":   PN = "2"  !CDS_PN = "2";
BODY = "Q_RES","I34": #LOCATION = "R598" !CDS_LOCATION = "R598" #SEC = "1" !CDS_SEC = "1";
"A":   PN = "1"  !CDS_PN = "1";
"B":   PN = "2"  !CDS_PN = "2";
BODY = "Q_RES","I35": #LOCATION = "R671" !CDS_LOCATION = "R671" &SEC = "1" #&CDS_SEC = "1";
"A":   PN = "1"  !CDS_PN = "1";
"B":   PN = "2"  !CDS_PN = "2";
BODY = "Q_RES","I36": #LOCATION = "R670" !CDS_LOCATION = "R670" &SEC = "1" #&CDS_SEC = "1";
"A":   PN = "1"  !CDS_PN = "1";
"B":   PN = "2"  !CDS_PN = "2";
BODY = "Q_RES","I43": #LOCATION = "R780" !CDS_LOCATION = "R780" &SEC = "1" #&CDS_SEC = "1";
"A":   PN = "1"  !CDS_PN = "1";
"B":   PN = "2"  !CDS_PN = "2";
BODY = "Q_RES","I44": #LOCATION = "R779" !CDS_LOCATION = "R779" &SEC = "1" #&CDS_SEC = "1";
"A":   PN = "1"  !CDS_PN = "1";
"B":   PN = "2"  !CDS_PN = "2";
BODY = "PT5161LRS","I47": #LOCATION = "U6015" !CDS_LOCATION = "U6015" &SEC = "3" #&CDS_SEC = "3";
"CLKREQ_N":   PN = "G35"  !CDS_PN = "G35";
"EE_CLK":   PN = "FF5"  !CDS_PN = "FF5";
"EE_DAT":   PN = "FJ3"  !CDS_PN = "FJ3";
"GPIO0":   PN = "FJ6"  !CDS_PN = "FJ6";
"GPIO1":   PN = "FJ23"  !CDS_PN = "FJ23";
"GPIO2":   PN = "FJ25"  !CDS_PN = "FJ25";
"GPIO3":   PN = "FJ28"  !CDS_PN = "FJ28";
"INT_N":   PN = "FJ31"  !CDS_PN = "FJ31";
"JTAG_TCK":   PN = "B3"  !CDS_PN = "B3";
"JTAG_TDI":   PN = "B6"  !CDS_PN = "B6";
"JTAG_TDO":   PN = "B9"  !CDS_PN = "B9";
"JTAG_TEST_MODE":   PN = "FF8"  !CDS_PN = "FF8";
"JTAG_TMS":   PN = "B12"  !CDS_PN = "B12";
"JTAG_TRST_N":   PN = "E8"  !CDS_PN = "E8";
"MODE":   PN = "FJ9"  !CDS_PN = "FJ9";
"PERST_N":   PN = "F2"  !CDS_PN = "F2";
"REFCLK_OUTN":   PN = "E18"  !CDS_PN = "E18";
"REFCLK_OUTP":   PN = "B16"  !CDS_PN = "B16";
"REFCLKN":   PN = "FF18"  !CDS_PN = "FF18";
"REFCLKP":   PN = "FJ16"  !CDS_PN = "FJ16";
"RESET_N":   PN = "FF11"  !CDS_PN = "FF11";
"RXDET_BYP":   PN = "E11"  !CDS_PN = "E11";
"SCAN_MODE":   PN = "FF33"  !CDS_PN = "FF33";
"SMB_ADDR1":   PN = "F34"  !CDS_PN = "F34";
"SMB_ADDR2":   PN = "B23"  !CDS_PN = "B23";
"SMB_ADDR3":   PN = "B25"  !CDS_PN = "B25";
"SMBCLK":   PN = "B31"  !CDS_PN = "B31";
"SMBDAT":   PN = "B28"  !CDS_PN = "B28";
"T_SENSE":   PN = "E30"  !CDS_PN = "E30";
"TEST0":   PN = "FF24"  !CDS_PN = "FF24";
"TEST1":   PN = "FF27"  !CDS_PN = "FF27";
"TEST2":   PN = "FF30"  !CDS_PN = "FF30";
BODY = "Q_RES","I51": #LOCATION = "R787" !CDS_LOCATION = "R787" &SEC = "1" #&CDS_SEC = "1";
"A":   PN = "1"  !CDS_PN = "1";
"B":   PN = "2"  !CDS_PN = "2";
BODY = "Q_RES","I52": #LOCATION = "R791" !CDS_LOCATION = "R791" &SEC = "1" #&CDS_SEC = "1";
"A":   PN = "1"  !CDS_PN = "1";
"B":   PN = "2"  !CDS_PN = "2";
BODY = "Q_RES","I54": #LOCATION = "R792" !CDS_LOCATION = "R792" &SEC = "1" #&CDS_SEC = "1";
"A":   PN = "1"  !CDS_PN = "1";
"B":   PN = "2"  !CDS_PN = "2";
BODY = "Q_RES","I55": #LOCATION = "R786" !CDS_LOCATION = "R786" &SEC = "1" #&CDS_SEC = "1";
"A":   PN = "1"  !CDS_PN = "1";
"B":   PN = "2"  !CDS_PN = "2";
BODY = "Q_RES","I56": #LOCATION = "R788" !CDS_LOCATION = "R788" &SEC = "1" #&CDS_SEC = "1";
"A":   PN = "1"  !CDS_PN = "1";
"B":   PN = "2"  !CDS_PN = "2";
BODY = "Q_RES","I57": #LOCATION = "R759" !CDS_LOCATION = "R759" &SEC = "1" #&CDS_SEC = "1";
"A":   PN = "1"  !CDS_PN = "1";
"B":   PN = "2"  !CDS_PN = "2";
BODY = "Q_RES","I65": #LOCATION = "R794" !CDS_LOCATION = "R794" &SEC = "1" #&CDS_SEC = "1";
"A":   PN = "1"  !CDS_PN = "1";
"B":   PN = "2"  !CDS_PN = "2";
BODY = "Q_RES","I66": #LOCATION = "R793" !CDS_LOCATION = "R793" &SEC = "1" #&CDS_SEC = "1";
"A":   PN = "1"  !CDS_PN = "1";
"B":   PN = "2"  !CDS_PN = "2";
BODY = "Q_RES","I70": #LOCATION = "R731" !CDS_LOCATION = "R731" #SEC = "1" !CDS_SEC = "1";
"A":   PN = "1"  !CDS_PN = "1";
"B":   PN = "2"  !CDS_PN = "2";
BODY = "Q_RES","I71": #LOCATION = "R732" !CDS_LOCATION = "R732" &SEC = "1" #&CDS_SEC = "1";
"A":   PN = "1"  !CDS_PN = "1";
"B":   PN = "2"  !CDS_PN = "2";
BODY = "Q_RES","I92": #LOCATION = "R752" !CDS_LOCATION = "R752" &SEC = "1" #&CDS_SEC = "1";
"A":   PN = "1"  !CDS_PN = "1";
"B":   PN = "2"  !CDS_PN = "2";
BODY = "Q_RES","I93": #LOCATION = "R749" !CDS_LOCATION = "R749" &SEC = "1" #&CDS_SEC = "1";
"A":   PN = "1"  !CDS_PN = "1";
"B":   PN = "2"  !CDS_PN = "2";
BODY = "Q_RES","I94": #LOCATION = "R758" !CDS_LOCATION = "R758" &SEC = "1" #&CDS_SEC = "1";
"A":   PN = "1"  !CDS_PN = "1";
"B":   PN = "2"  !CDS_PN = "2";
BODY = "Q_RES","I101": #LOCATION = "R741" !CDS_LOCATION = "R741" &SEC = "1" #&CDS_SEC = "1";
"A":   PN = "1"  !CDS_PN = "1";
"B":   PN = "2"  !CDS_PN = "2";
BODY = "Q_RES","I102": #LOCATION = "R746" !CDS_LOCATION = "R746" &SEC = "1" #&CDS_SEC = "1";
"A":   PN = "1"  !CDS_PN = "1";
"B":   PN = "2"  !CDS_PN = "2";
BODY = "Q_RES","I103": #LOCATION = "R735" !CDS_LOCATION = "R735" &SEC = "1" #&CDS_SEC = "1";
"A":   PN = "1"  !CDS_PN = "1";
"B":   PN = "2"  !CDS_PN = "2";
BODY = "Q_RES","I104": #LOCATION = "R745" !CDS_LOCATION = "R745" &SEC = "1" #&CDS_SEC = "1";
"A":   PN = "1"  !CDS_PN = "1";
"B":   PN = "2"  !CDS_PN = "2";
BODY = "Q_RES","I105": #LOCATION = "R796" !CDS_LOCATION = "R796" &SEC = "1" #&CDS_SEC = "1";
"A":   PN = "1"  !CDS_PN = "1";
"B":   PN = "2"  !CDS_PN = "2";
BODY = "Q_RES","I110": #LOCATION = "R795" !CDS_LOCATION = "R795" &SEC = "1" #&CDS_SEC = "1";
"A":   PN = "1"  !CDS_PN = "1";
"B":   PN = "2"  !CDS_PN = "2";
BODY = "Q_RES","I111": #LOCATION = "R1376" !CDS_LOCATION = "R1376" &SEC = "1" #&CDS_SEC = "1";
"A":   PN = "1"  !CDS_PN = "1";
"B":   PN = "2"  !CDS_PN = "2";
BODY = "Q_RES","I115": #LOCATION = "R1372" !CDS_LOCATION = "R1372" &SEC = "1" #&CDS_SEC = "1";
"A":   PN = "1"  !CDS_PN = "1";
"B":   PN = "2"  !CDS_PN = "2";
BODY = "Q_RES","I125": #LOCATION = "R1377" !CDS_LOCATION = "R1377" &SEC = "1" #&CDS_SEC = "1";
"A":   PN = "1"  !CDS_PN = "1";
"B":   PN = "2"  !CDS_PN = "2";
BODY = "Q_RES","I126": #LOCATION = "R1378" !CDS_LOCATION = "R1378" &SEC = "1" #&CDS_SEC = "1";
"A":   PN = "1"  !CDS_PN = "1";
"B":   PN = "2"  !CDS_PN = "2";
BODY = "Q_RES","I132": #LOCATION = "R756" !CDS_LOCATION = "R756" &SEC = "1" #&CDS_SEC = "1";
"A":   PN = "1"  !CDS_PN = "1";
"B":   PN = "2"  !CDS_PN = "2";
BODY = "Q_RES","I145": #LOCATION = "R1454" !CDS_LOCATION = "R1454" &SEC = "1" #&CDS_SEC = "1";
"A":   PN = "1"  !CDS_PN = "1";
"B":   PN = "2"  !CDS_PN = "2";
BODY = "Q_RES","I146": #LOCATION = "R1455" !CDS_LOCATION = "R1455" &SEC = "1" #&CDS_SEC = "1";
"A":   PN = "1"  !CDS_PN = "1";
"B":   PN = "2"  !CDS_PN = "2";
BODY = "Q_RES","I150": #LOCATION = "R1373" !CDS_LOCATION = "R1373" &SEC = "1" #&CDS_SEC = "1";
"A":   PN = "1"  !CDS_PN = "1";
"B":   PN = "2"  !CDS_PN = "2";
BODY = "Q_RES","I151": #LOCATION = "R1461" !CDS_LOCATION = "R1461" &SEC = "1" #&CDS_SEC = "1";
"A":   PN = "1"  !CDS_PN = "1";
"B":   PN = "2"  !CDS_PN = "2";
BODY = "Q_RES","I153": #LOCATION = "R1456" !CDS_LOCATION = "R1456" &SEC = "1" #&CDS_SEC = "1";
"A":   PN = "1"  !CDS_PN = "1";
"B":   PN = "2"  !CDS_PN = "2";
DRAWING = "@t6g_mb_lib.t6g(sch_1):page467";
BODY = "Q_RES","I2": #LOCATION = "R6744" !CDS_LOCATION = "R6744" &SEC = "1" #&CDS_SEC = "1";
"A":   PN = "1"  !CDS_PN = "1";
"B":   PN = "2"  !CDS_PN = "2";
BODY = "Q_RES","I4": #LOCATION = "R6745" !CDS_LOCATION = "R6745" &SEC = "1" #&CDS_SEC = "1";
"A":   PN = "1"  !CDS_PN = "1";
"B":   PN = "2"  !CDS_PN = "2";
BODY = "Q_RES","I5": #LOCATION = "R6742" !CDS_LOCATION = "R6742" &SEC = "1" #&CDS_SEC = "1";
"A":   PN = "1"  !CDS_PN = "1";
"B":   PN = "2"  !CDS_PN = "2";
BODY = "Q_RES","I6": #LOCATION = "R6743" !CDS_LOCATION = "R6743" &SEC = "1" #&CDS_SEC = "1";
"A":   PN = "1"  !CDS_PN = "1";
"B":   PN = "2"  !CDS_PN = "2";
DRAWING = "@t6g_mb_lib.t6g(sch_1):page377";
BODY = "Q_RES","I2": #LOCATION = "R845" !CDS_LOCATION = "R845" &SEC = "1" #&CDS_SEC = "1";
"A":   PN = "1"  !CDS_PN = "1";
"B":   PN = "2"  !CDS_PN = "2";
BODY = "Q_RES","I3": #LOCATION = "R846" !CDS_LOCATION = "R846" &SEC = "1" #&CDS_SEC = "1";
"A":   PN = "1"  !CDS_PN = "1";
"B":   PN = "2"  !CDS_PN = "2";
BODY = "Q_RES","I4": #LOCATION = "R842" !CDS_LOCATION = "R842" &SEC = "1" #&CDS_SEC = "1";
"A":   PN = "1"  !CDS_PN = "1";
"B":   PN = "2"  !CDS_PN = "2";
BODY = "Q_RES","I5": #LOCATION = "R843" !CDS_LOCATION = "R843" &SEC = "1" #&CDS_SEC = "1";
"A":   PN = "1"  !CDS_PN = "1";
"B":   PN = "2"  !CDS_PN = "2";
BODY = "Q_RES","I8": #LOCATION = "R847" !CDS_LOCATION = "R847" &SEC = "1" #&CDS_SEC = "1";
"A":   PN = "1"  !CDS_PN = "1";
"B":   PN = "2"  !CDS_PN = "2";
BODY = "Q_RES","I9": #LOCATION = "R844" !CDS_LOCATION = "R844" &SEC = "1" #&CDS_SEC = "1";
"A":   PN = "1"  !CDS_PN = "1";
"B":   PN = "2"  !CDS_PN = "2";
BODY = "Q_RES","I16": #LOCATION = "R849" !CDS_LOCATION = "R849" &SEC = "1" #&CDS_SEC = "1";
"A":   PN = "1"  !CDS_PN = "1";
"B":   PN = "2"  !CDS_PN = "2";
BODY = "Q_RES","I17": #LOCATION = "R841" !CDS_LOCATION = "R841" &SEC = "1" #&CDS_SEC = "1";
"A":   PN = "1"  !CDS_PN = "1";
"B":   PN = "2"  !CDS_PN = "2";
BODY = "Q_RES","I18": #LOCATION = "R840" !CDS_LOCATION = "R840" &SEC = "1" #&CDS_SEC = "1";
"A":   PN = "1"  !CDS_PN = "1";
"B":   PN = "2"  !CDS_PN = "2";
BODY = "Q_RES","I19": #LOCATION = "R838" !CDS_LOCATION = "R838" &SEC = "1" #&CDS_SEC = "1";
"A":   PN = "1"  !CDS_PN = "1";
"B":   PN = "2"  !CDS_PN = "2";
BODY = "Q_RES","I20": #LOCATION = "R839" !CDS_LOCATION = "R839" &SEC = "1" #&CDS_SEC = "1";
"A":   PN = "1"  !CDS_PN = "1";
"B":   PN = "2"  !CDS_PN = "2";
BODY = "Q_RES","I21": #LOCATION = "R837" !CDS_LOCATION = "R837" &SEC = "1" #&CDS_SEC = "1";
"A":   PN = "1"  !CDS_PN = "1";
"B":   PN = "2"  !CDS_PN = "2";
BODY = "Q_RES","I22": #LOCATION = "R836" !CDS_LOCATION = "R836" &SEC = "1" #&CDS_SEC = "1";
"A":   PN = "1"  !CDS_PN = "1";
"B":   PN = "2"  !CDS_PN = "2";
BODY = "Q_RES","I23": #LOCATION = "R835" !CDS_LOCATION = "R835" &SEC = "1" #&CDS_SEC = "1";
"A":   PN = "1"  !CDS_PN = "1";
"B":   PN = "2"  !CDS_PN = "2";
BODY = "Q_RES","I24": #LOCATION = "R834" !CDS_LOCATION = "R834" &SEC = "1" #&CDS_SEC = "1";
"A":   PN = "1"  !CDS_PN = "1";
"B":   PN = "2"  !CDS_PN = "2";
BODY = "Q_RES","I42": #LOCATION = "R848" !CDS_LOCATION = "R848" &SEC = "1" #&CDS_SEC = "1";
"A":   PN = "1"  !CDS_PN = "1";
"B":   PN = "2"  !CDS_PN = "2";
BODY = "Q_RES","I43": #LOCATION = "R807" !CDS_LOCATION = "R807" &SEC = "1" #&CDS_SEC = "1";
"A":   PN = "1"  !CDS_PN = "1";
"B":   PN = "2"  !CDS_PN = "2";
BODY = "Q_RES","I44": #LOCATION = "R809" !CDS_LOCATION = "R809" &SEC = "1" #&CDS_SEC = "1";
"A":   PN = "1"  !CDS_PN = "1";
"B":   PN = "2"  !CDS_PN = "2";
BODY = "Q_RES","I45": #LOCATION = "R808" !CDS_LOCATION = "R808" &SEC = "1" #&CDS_SEC = "1";
"A":   PN = "1"  !CDS_PN = "1";
"B":   PN = "2"  !CDS_PN = "2";
BODY = "Q_RES","I46": #LOCATION = "R805" !CDS_LOCATION = "R805" &SEC = "1" #&CDS_SEC = "1";
"A":   PN = "1"  !CDS_PN = "1";
"B":   PN = "2"  !CDS_PN = "2";
BODY = "Q_RES","I47": #LOCATION = "R806" !CDS_LOCATION = "R806" &SEC = "1" #&CDS_SEC = "1";
"A":   PN = "1"  !CDS_PN = "1";
"B":   PN = "2"  !CDS_PN = "2";
BODY = "Q_RES","I48": #LOCATION = "R803" !CDS_LOCATION = "R803" &SEC = "1" #&CDS_SEC = "1";
"A":   PN = "1"  !CDS_PN = "1";
"B":   PN = "2"  !CDS_PN = "2";
BODY = "Q_RES","I49": #LOCATION = "R801" !CDS_LOCATION = "R801" #SEC = "1" !CDS_SEC = "1";
"A":   PN = "1"  !CDS_PN = "1";
"B":   PN = "2"  !CDS_PN = "2";
BODY = "Q_RES","I50": #LOCATION = "R802" !CDS_LOCATION = "R802" #SEC = "1" !CDS_SEC = "1";
"A":   PN = "1"  !CDS_PN = "1";
"B":   PN = "2"  !CDS_PN = "2";
BODY = "Q_CAP","I55": #LOCATION = "C365" !CDS_LOCATION = "C365" &SEC = "1" #&CDS_SEC = "1";
"A":   PN = "1"  !CDS_PN = "1";
"B":   PN = "2"  !CDS_PN = "2";
BODY = "Q_RES","I58": #LOCATION = "R827" !CDS_LOCATION = "R827" &SEC = "1" #&CDS_SEC = "1";
"A":   PN = "1"  !CDS_PN = "1";
"B":   PN = "2"  !CDS_PN = "2";
BODY = "Q_RES","I59": #LOCATION = "R826" !CDS_LOCATION = "R826" &SEC = "1" #&CDS_SEC = "1";
"A":   PN = "1"  !CDS_PN = "1";
"B":   PN = "2"  !CDS_PN = "2";
BODY = "Q_RES","I60": #LOCATION = "R812" !CDS_LOCATION = "R812" &SEC = "1" #&CDS_SEC = "1";
"A":   PN = "1"  !CDS_PN = "1";
"B":   PN = "2"  !CDS_PN = "2";
BODY = "Q_RES","I61": #LOCATION = "R810" !CDS_LOCATION = "R810" &SEC = "1" #&CDS_SEC = "1";
"A":   PN = "1"  !CDS_PN = "1";
"B":   PN = "2"  !CDS_PN = "2";
BODY = "Q_RES","I62": #LOCATION = "R6734" !CDS_LOCATION = "R6734" &SEC = "1" #&CDS_SEC = "1";
"A":   PN = "1"  !CDS_PN = "1";
"B":   PN = "2"  !CDS_PN = "2";
BODY = "Q_RES","I63": #LOCATION = "R6735" !CDS_LOCATION = "R6735" &SEC = "1" #&CDS_SEC = "1";
"A":   PN = "1"  !CDS_PN = "1";
"B":   PN = "2"  !CDS_PN = "2";
BODY = "Q_RES","I64": #LOCATION = "R6707" !CDS_LOCATION = "R6707" &SEC = "1" #&CDS_SEC = "1";
"A":   PN = "1"  !CDS_PN = "1";
"B":   PN = "2"  !CDS_PN = "2";
BODY = "Q_RES","I65": #LOCATION = "R6706" !CDS_LOCATION = "R6706" &SEC = "1" #&CDS_SEC = "1";
"A":   PN = "1"  !CDS_PN = "1";
"B":   PN = "2"  !CDS_PN = "2";
BODY = "Q_RES","I73": #LOCATION = "R833" !CDS_LOCATION = "R833" &SEC = "1" #&CDS_SEC = "1";
"A":   PN = "1"  !CDS_PN = "1";
"B":   PN = "2"  !CDS_PN = "2";
BODY = "Q_RES","I74": #LOCATION = "R831" !CDS_LOCATION = "R831" &SEC = "1" #&CDS_SEC = "1";
"A":   PN = "1"  !CDS_PN = "1";
"B":   PN = "2"  !CDS_PN = "2";
BODY = "Q_RES","I75": #LOCATION = "R832" !CDS_LOCATION = "R832" &SEC = "1" #&CDS_SEC = "1";
"A":   PN = "1"  !CDS_PN = "1";
"B":   PN = "2"  !CDS_PN = "2";
BODY = "Q_RES","I76": #LOCATION = "R828" !CDS_LOCATION = "R828" &SEC = "1" #&CDS_SEC = "1";
"A":   PN = "1"  !CDS_PN = "1";
"B":   PN = "2"  !CDS_PN = "2";
BODY = "Q_RES","I77": #LOCATION = "R829" !CDS_LOCATION = "R829" &SEC = "1" #&CDS_SEC = "1";
"A":   PN = "1"  !CDS_PN = "1";
"B":   PN = "2"  !CDS_PN = "2";
BODY = "Q_RES","I78": #LOCATION = "R830" !CDS_LOCATION = "R830" &SEC = "1" #&CDS_SEC = "1";
"A":   PN = "1"  !CDS_PN = "1";
"B":   PN = "2"  !CDS_PN = "2";
BODY = "Q_RES","I79": #LOCATION = "R799" !CDS_LOCATION = "R799" #SEC = "1" !CDS_SEC = "1";
"A":   PN = "1"  !CDS_PN = "1";
"B":   PN = "2"  !CDS_PN = "2";
BODY = "Q_RES","I80": #LOCATION = "R797" !CDS_LOCATION = "R797" #SEC = "1" !CDS_SEC = "1";
"A":   PN = "1"  !CDS_PN = "1";
"B":   PN = "2"  !CDS_PN = "2";
BODY = "Q_RES","I81": #LOCATION = "R850" !CDS_LOCATION = "R850" &SEC = "1" #&CDS_SEC = "1";
"A":   PN = "1"  !CDS_PN = "1";
"B":   PN = "2"  !CDS_PN = "2";
BODY = "Q_RES","I82": #LOCATION = "R851" !CDS_LOCATION = "R851" &SEC = "1" #&CDS_SEC = "1";
"A":   PN = "1"  !CDS_PN = "1";
"B":   PN = "2"  !CDS_PN = "2";
BODY = "TCA9548APWR","I94": #LOCATION = "U22" !CDS_LOCATION = "U22" &SEC = "1" #&CDS_SEC = "1";
"A0":   PN = "1"  !CDS_PN = "1";
"A1":   PN = "2"  !CDS_PN = "2";
"A2":   PN = "21"  !CDS_PN = "21";
"GND":   PN = "12"  !CDS_PN = "12";
"RESET#":   PN = "3"  !CDS_PN = "3";
"SC0":   PN = "5"  !CDS_PN = "5";
"SC1":   PN = "7"  !CDS_PN = "7";
"SC2":   PN = "9"  !CDS_PN = "9";
"SC3":   PN = "11"  !CDS_PN = "11";
"SC4":   PN = "14"  !CDS_PN = "14";
"SC5":   PN = "16"  !CDS_PN = "16";
"SC6":   PN = "18"  !CDS_PN = "18";
"SC7":   PN = "20"  !CDS_PN = "20";
"SCL":   PN = "22"  !CDS_PN = "22";
"SD0":   PN = "4"  !CDS_PN = "4";
"SD1":   PN = "6"  !CDS_PN = "6";
"SD2":   PN = "8"  !CDS_PN = "8";
"SD3":   PN = "10"  !CDS_PN = "10";
"SD4":   PN = "13"  !CDS_PN = "13";
"SD5":   PN = "15"  !CDS_PN = "15";
"SD6":   PN = "17"  !CDS_PN = "17";
"SD7":   PN = "19"  !CDS_PN = "19";
"SDA":   PN = "23"  !CDS_PN = "23";
"VCC":   PN = "24"  !CDS_PN = "24";
BODY = "Q_RES","I104": #LOCATION = "R1361" !CDS_LOCATION = "R1361" #SEC = "1" !CDS_SEC = "1";
"A":   PN = "1"  !CDS_PN = "1";
"B":   PN = "2"  !CDS_PN = "2";
BODY = "Q_RES","I105": #LOCATION = "R1390" !CDS_LOCATION = "R1390" &SEC = "1" #&CDS_SEC = "1";
"A":   PN = "1"  !CDS_PN = "1";
"B":   PN = "2"  !CDS_PN = "2";
BODY = "Q_RES","I106": #LOCATION = "R1393" !CDS_LOCATION = "R1393" &SEC = "1" #&CDS_SEC = "1";
"A":   PN = "1"  !CDS_PN = "1";
"B":   PN = "2"  !CDS_PN = "2";
BODY = "Q_RES","I107": #LOCATION = "R1394" !CDS_LOCATION = "R1394" &SEC = "1" #&CDS_SEC = "1";
"A":   PN = "1"  !CDS_PN = "1";
"B":   PN = "2"  !CDS_PN = "2";
BODY = "Q_RES","I108": #LOCATION = "R1399" !CDS_LOCATION = "R1399" &SEC = "1" #&CDS_SEC = "1";
"A":   PN = "1"  !CDS_PN = "1";
"B":   PN = "2"  !CDS_PN = "2";
BODY = "Q_RES","I109": #LOCATION = "R1402" !CDS_LOCATION = "R1402" &SEC = "1" #&CDS_SEC = "1";
"A":   PN = "1"  !CDS_PN = "1";
"B":   PN = "2"  !CDS_PN = "2";
BODY = "Q_RES","I110": #LOCATION = "R1403" !CDS_LOCATION = "R1403" &SEC = "1" #&CDS_SEC = "1";
"A":   PN = "1"  !CDS_PN = "1";
"B":   PN = "2"  !CDS_PN = "2";
BODY = "Q_RES","I111": #LOCATION = "R1407" !CDS_LOCATION = "R1407" &SEC = "1" #&CDS_SEC = "1";
"A":   PN = "1"  !CDS_PN = "1";
"B":   PN = "2"  !CDS_PN = "2";
BODY = "Q_RES","I121": #LOCATION = "R1367" !CDS_LOCATION = "R1367" &SEC = "1" #&CDS_SEC = "1";
"A":   PN = "1"  !CDS_PN = "1";
"B":   PN = "2"  !CDS_PN = "2";
BODY = "Q_RES","I122": #LOCATION = "R1366" !CDS_LOCATION = "R1366" &SEC = "1" #&CDS_SEC = "1";
"A":   PN = "1"  !CDS_PN = "1";
"B":   PN = "2"  !CDS_PN = "2";
BODY = "Q_RES","I123": #LOCATION = "R1374" !CDS_LOCATION = "R1374" &SEC = "1" #&CDS_SEC = "1";
"A":   PN = "1"  !CDS_PN = "1";
"B":   PN = "2"  !CDS_PN = "2";
BODY = "Q_RES","I124": #LOCATION = "R1371" !CDS_LOCATION = "R1371" &SEC = "1" #&CDS_SEC = "1";
"A":   PN = "1"  !CDS_PN = "1";
"B":   PN = "2"  !CDS_PN = "2";
BODY = "Q_RES","I125": #LOCATION = "R1375" !CDS_LOCATION = "R1375" &SEC = "1" #&CDS_SEC = "1";
"A":   PN = "1"  !CDS_PN = "1";
"B":   PN = "2"  !CDS_PN = "2";
BODY = "Q_RES","I126": #LOCATION = "R1379" !CDS_LOCATION = "R1379" &SEC = "1" #&CDS_SEC = "1";
"A":   PN = "1"  !CDS_PN = "1";
"B":   PN = "2"  !CDS_PN = "2";
BODY = "Q_RES","I127": #LOCATION = "R1382" !CDS_LOCATION = "R1382" &SEC = "1" #&CDS_SEC = "1";
"A":   PN = "1"  !CDS_PN = "1";
"B":   PN = "2"  !CDS_PN = "2";
BODY = "Q_RES","I128": #LOCATION = "R1383" !CDS_LOCATION = "R1383" &SEC = "1" #&CDS_SEC = "1";
"A":   PN = "1"  !CDS_PN = "1";
"B":   PN = "2"  !CDS_PN = "2";
BODY = "Q_RES","I164": #LOCATION = "R1410" !CDS_LOCATION = "R1410" &SEC = "1" #&CDS_SEC = "1";
"A":   PN = "1"  !CDS_PN = "1";
"B":   PN = "2"  !CDS_PN = "2";
BODY = "Q_RES","I165": #LOCATION = "R1411" !CDS_LOCATION = "R1411" &SEC = "1" #&CDS_SEC = "1";
"A":   PN = "1"  !CDS_PN = "1";
"B":   PN = "2"  !CDS_PN = "2";
BODY = "Q_RES","I166": #LOCATION = "R1415" !CDS_LOCATION = "R1415" &SEC = "1" #&CDS_SEC = "1";
"A":   PN = "1"  !CDS_PN = "1";
"B":   PN = "2"  !CDS_PN = "2";
BODY = "Q_RES","I167": #LOCATION = "R1418" !CDS_LOCATION = "R1418" &SEC = "1" #&CDS_SEC = "1";
"A":   PN = "1"  !CDS_PN = "1";
"B":   PN = "2"  !CDS_PN = "2";
BODY = "Q_RES","I168": #LOCATION = "R1420" !CDS_LOCATION = "R1420" &SEC = "1" #&CDS_SEC = "1";
"A":   PN = "1"  !CDS_PN = "1";
"B":   PN = "2"  !CDS_PN = "2";
BODY = "Q_RES","I169": #LOCATION = "R1428" !CDS_LOCATION = "R1428" &SEC = "1" #&CDS_SEC = "1";
"A":   PN = "1"  !CDS_PN = "1";
"B":   PN = "2"  !CDS_PN = "2";
BODY = "Q_RES","I170": #LOCATION = "R1431" !CDS_LOCATION = "R1431" &SEC = "1" #&CDS_SEC = "1";
"A":   PN = "1"  !CDS_PN = "1";
"B":   PN = "2"  !CDS_PN = "2";
BODY = "Q_RES","I171": #LOCATION = "R1432" !CDS_LOCATION = "R1432" &SEC = "1" #&CDS_SEC = "1";
"A":   PN = "1"  !CDS_PN = "1";
"B":   PN = "2"  !CDS_PN = "2";
BODY = "Q_RES","I172": #LOCATION = "R1437" !CDS_LOCATION = "R1437" &SEC = "1" #&CDS_SEC = "1";
"A":   PN = "1"  !CDS_PN = "1";
"B":   PN = "2"  !CDS_PN = "2";
BODY = "Q_RES","I173": #LOCATION = "R1436" !CDS_LOCATION = "R1436" &SEC = "1" #&CDS_SEC = "1";
"A":   PN = "1"  !CDS_PN = "1";
"B":   PN = "2"  !CDS_PN = "2";
BODY = "Q_RES","I174": #LOCATION = "R1448" !CDS_LOCATION = "R1448" &SEC = "1" #&CDS_SEC = "1";
"A":   PN = "1"  !CDS_PN = "1";
"B":   PN = "2"  !CDS_PN = "2";
BODY = "Q_RES","I175": #LOCATION = "R1451" !CDS_LOCATION = "R1451" &SEC = "1" #&CDS_SEC = "1";
"A":   PN = "1"  !CDS_PN = "1";
"B":   PN = "2"  !CDS_PN = "2";
BODY = "Q_RES","I176": #LOCATION = "R1462" !CDS_LOCATION = "R1462" &SEC = "1" #&CDS_SEC = "1";
"A":   PN = "1"  !CDS_PN = "1";
"B":   PN = "2"  !CDS_PN = "2";
BODY = "Q_RES","I177": #LOCATION = "R1463" !CDS_LOCATION = "R1463" &SEC = "1" #&CDS_SEC = "1";
"A":   PN = "1"  !CDS_PN = "1";
"B":   PN = "2"  !CDS_PN = "2";
BODY = "Q_RES","I178": #LOCATION = "R1468" !CDS_LOCATION = "R1468" &SEC = "1" #&CDS_SEC = "1";
"A":   PN = "1"  !CDS_PN = "1";
"B":   PN = "2"  !CDS_PN = "2";
BODY = "Q_RES","I179": #LOCATION = "R1469" !CDS_LOCATION = "R1469" &SEC = "1" #&CDS_SEC = "1";
"A":   PN = "1"  !CDS_PN = "1";
"B":   PN = "2"  !CDS_PN = "2";
DRAWING = "@t6g_mb_lib.t6g(sch_1):page451";
BODY = "Q_RES","I17": #LOCATION = "R868" !CDS_LOCATION = "R868" &SEC = "1" #&CDS_SEC = "1";
"A":   PN = "1"  !CDS_PN = "1";
"B":   PN = "2"  !CDS_PN = "2";
BODY = "Q_RES","I19": #LOCATION = "R875" !CDS_LOCATION = "R875" &SEC = "1" #&CDS_SEC = "1";
"A":   PN = "1"  !CDS_PN = "1";
"B":   PN = "2"  !CDS_PN = "2";
BODY = "Q_RES","I20": #LOCATION = "R876" !CDS_LOCATION = "R876" &SEC = "1" #&CDS_SEC = "1";
"A":   PN = "1"  !CDS_PN = "1";
"B":   PN = "2"  !CDS_PN = "2";
BODY = "Q_RES","I21": #LOCATION = "R874" !CDS_LOCATION = "R874" &SEC = "1" #&CDS_SEC = "1";
"A":   PN = "1"  !CDS_PN = "1";
"B":   PN = "2"  !CDS_PN = "2";
BODY = "Q_RES","I27": #LOCATION = "R620" !CDS_LOCATION = "R620" #SEC = "1" !CDS_SEC = "1";
"A":   PN = "1"  !CDS_PN = "1";
"B":   PN = "2"  !CDS_PN = "2";
BODY = "Q_RES","I28": #LOCATION = "R619" !CDS_LOCATION = "R619" #SEC = "1" !CDS_SEC = "1";
"A":   PN = "1"  !CDS_PN = "1";
"B":   PN = "2"  !CDS_PN = "2";
BODY = "Q_RES","I29": #LOCATION = "R692" !CDS_LOCATION = "R692" &SEC = "1" #&CDS_SEC = "1";
"A":   PN = "1"  !CDS_PN = "1";
"B":   PN = "2"  !CDS_PN = "2";
BODY = "Q_RES","I30": #LOCATION = "R691" !CDS_LOCATION = "R691" &SEC = "1" #&CDS_SEC = "1";
"A":   PN = "1"  !CDS_PN = "1";
"B":   PN = "2"  !CDS_PN = "2";
BODY = "Q_RES","I34": #LOCATION = "R872" !CDS_LOCATION = "R872" &SEC = "1" #&CDS_SEC = "1";
"A":   PN = "1"  !CDS_PN = "1";
"B":   PN = "2"  !CDS_PN = "2";
BODY = "Q_RES","I35": #LOCATION = "R873" !CDS_LOCATION = "R873" &SEC = "1" #&CDS_SEC = "1";
"A":   PN = "1"  !CDS_PN = "1";
"B":   PN = "2"  !CDS_PN = "2";
BODY = "Q_RES","I36": #LOCATION = "R640" !CDS_LOCATION = "R640" &SEC = "1" #&CDS_SEC = "1";
"A":   PN = "1"  !CDS_PN = "1";
"B":   PN = "2"  !CDS_PN = "2";
BODY = "Q_RES","I42": #LOCATION = "R879" !CDS_LOCATION = "R879" &SEC = "1" #&CDS_SEC = "1";
"A":   PN = "1"  !CDS_PN = "1";
"B":   PN = "2"  !CDS_PN = "2";
BODY = "Q_RES","I43": #LOCATION = "R881" !CDS_LOCATION = "R881" &SEC = "1" #&CDS_SEC = "1";
"A":   PN = "1"  !CDS_PN = "1";
"B":   PN = "2"  !CDS_PN = "2";
BODY = "Q_RES","I45": #LOCATION = "R883" !CDS_LOCATION = "R883" &SEC = "1" #&CDS_SEC = "1";
"A":   PN = "1"  !CDS_PN = "1";
"B":   PN = "2"  !CDS_PN = "2";
BODY = "Q_RES","I46": #LOCATION = "R884" !CDS_LOCATION = "R884" &SEC = "1" #&CDS_SEC = "1";
"A":   PN = "1"  !CDS_PN = "1";
"B":   PN = "2"  !CDS_PN = "2";
BODY = "Q_RES","I47": #LOCATION = "R878" !CDS_LOCATION = "R878" &SEC = "1" #&CDS_SEC = "1";
"A":   PN = "1"  !CDS_PN = "1";
"B":   PN = "2"  !CDS_PN = "2";
BODY = "Q_RES","I48": #LOCATION = "R880" !CDS_LOCATION = "R880" &SEC = "1" #&CDS_SEC = "1";
"A":   PN = "1"  !CDS_PN = "1";
"B":   PN = "2"  !CDS_PN = "2";
BODY = "Q_RES","I49": #LOCATION = "R882" !CDS_LOCATION = "R882" &SEC = "1" #&CDS_SEC = "1";
"A":   PN = "1"  !CDS_PN = "1";
"B":   PN = "2"  !CDS_PN = "2";
BODY = "Q_RES","I50": #LOCATION = "R871" !CDS_LOCATION = "R871" &SEC = "1" #&CDS_SEC = "1";
"A":   PN = "1"  !CDS_PN = "1";
"B":   PN = "2"  !CDS_PN = "2";
BODY = "Q_RES","I58": #LOCATION = "R886" !CDS_LOCATION = "R886" &SEC = "1" #&CDS_SEC = "1";
"A":   PN = "1"  !CDS_PN = "1";
"B":   PN = "2"  !CDS_PN = "2";
BODY = "Q_RES","I59": #LOCATION = "R885" !CDS_LOCATION = "R885" &SEC = "1" #&CDS_SEC = "1";
"A":   PN = "1"  !CDS_PN = "1";
"B":   PN = "2"  !CDS_PN = "2";
BODY = "Q_RES","I62": #LOCATION = "R860" !CDS_LOCATION = "R860" &SEC = "1" #&CDS_SEC = "1";
"A":   PN = "1"  !CDS_PN = "1";
"B":   PN = "2"  !CDS_PN = "2";
BODY = "Q_RES","I63": #LOCATION = "R854" !CDS_LOCATION = "R854" #SEC = "1" !CDS_SEC = "1";
"A":   PN = "1"  !CDS_PN = "1";
"B":   PN = "2"  !CDS_PN = "2";
BODY = "Q_RES","I71": #LOCATION = "R863" !CDS_LOCATION = "R863" &SEC = "1" #&CDS_SEC = "1";
"A":   PN = "1"  !CDS_PN = "1";
"B":   PN = "2"  !CDS_PN = "2";
BODY = "Q_RES","I72": #LOCATION = "R865" !CDS_LOCATION = "R865" &SEC = "1" #&CDS_SEC = "1";
"A":   PN = "1"  !CDS_PN = "1";
"B":   PN = "2"  !CDS_PN = "2";
BODY = "Q_RES","I74": #LOCATION = "R861" !CDS_LOCATION = "R861" &SEC = "1" #&CDS_SEC = "1";
"A":   PN = "1"  !CDS_PN = "1";
"B":   PN = "2"  !CDS_PN = "2";
BODY = "Q_RES","I75": #LOCATION = "R864" !CDS_LOCATION = "R864" &SEC = "1" #&CDS_SEC = "1";
"A":   PN = "1"  !CDS_PN = "1";
"B":   PN = "2"  !CDS_PN = "2";
BODY = "Q_RES","I76": #LOCATION = "R892" !CDS_LOCATION = "R892" &SEC = "1" #&CDS_SEC = "1";
"A":   PN = "1"  !CDS_PN = "1";
"B":   PN = "2"  !CDS_PN = "2";
BODY = "Q_RES","I77": #LOCATION = "R887" !CDS_LOCATION = "R887" &SEC = "1" #&CDS_SEC = "1";
"A":   PN = "1"  !CDS_PN = "1";
"B":   PN = "2"  !CDS_PN = "2";
BODY = "Q_RES","I80": #LOCATION = "R867" !CDS_LOCATION = "R867" &SEC = "1" #&CDS_SEC = "1";
"A":   PN = "1"  !CDS_PN = "1";
"B":   PN = "2"  !CDS_PN = "2";
BODY = "Q_RES","I82": #LOCATION = "R866" !CDS_LOCATION = "R866" &SEC = "1" #&CDS_SEC = "1";
"A":   PN = "1"  !CDS_PN = "1";
"B":   PN = "2"  !CDS_PN = "2";
BODY = "Q_RES","I86": #LOCATION = "R870" !CDS_LOCATION = "R870" &SEC = "1" #&CDS_SEC = "1";
"A":   PN = "1"  !CDS_PN = "1";
"B":   PN = "2"  !CDS_PN = "2";
BODY = "Q_RES","I92": #LOCATION = "R637" !CDS_LOCATION = "R637" &SEC = "1" #&CDS_SEC = "1";
"A":   PN = "1"  !CDS_PN = "1";
"B":   PN = "2"  !CDS_PN = "2";
BODY = "PT5161LRS","I97": #LOCATION = "U6016" !CDS_LOCATION = "U6016" &SEC = "3" #&CDS_SEC = "3";
"CLKREQ_N":   PN = "G35"  !CDS_PN = "G35";
"EE_CLK":   PN = "FF5"  !CDS_PN = "FF5";
"EE_DAT":   PN = "FJ3"  !CDS_PN = "FJ3";
"GPIO0":   PN = "FJ6"  !CDS_PN = "FJ6";
"GPIO1":   PN = "FJ23"  !CDS_PN = "FJ23";
"GPIO2":   PN = "FJ25"  !CDS_PN = "FJ25";
"GPIO3":   PN = "FJ28"  !CDS_PN = "FJ28";
"INT_N":   PN = "FJ31"  !CDS_PN = "FJ31";
"JTAG_TCK":   PN = "B3"  !CDS_PN = "B3";
"JTAG_TDI":   PN = "B6"  !CDS_PN = "B6";
"JTAG_TDO":   PN = "B9"  !CDS_PN = "B9";
"JTAG_TEST_MODE":   PN = "FF8"  !CDS_PN = "FF8";
"JTAG_TMS":   PN = "B12"  !CDS_PN = "B12";
"JTAG_TRST_N":   PN = "E8"  !CDS_PN = "E8";
"MODE":   PN = "FJ9"  !CDS_PN = "FJ9";
"PERST_N":   PN = "F2"  !CDS_PN = "F2";
"REFCLK_OUTN":   PN = "E18"  !CDS_PN = "E18";
"REFCLK_OUTP":   PN = "B16"  !CDS_PN = "B16";
"REFCLKN":   PN = "FF18"  !CDS_PN = "FF18";
"REFCLKP":   PN = "FJ16"  !CDS_PN = "FJ16";
"RESET_N":   PN = "FF11"  !CDS_PN = "FF11";
"RXDET_BYP":   PN = "E11"  !CDS_PN = "E11";
"SCAN_MODE":   PN = "FF33"  !CDS_PN = "FF33";
"SMB_ADDR1":   PN = "F34"  !CDS_PN = "F34";
"SMB_ADDR2":   PN = "B23"  !CDS_PN = "B23";
"SMB_ADDR3":   PN = "B25"  !CDS_PN = "B25";
"SMBCLK":   PN = "B31"  !CDS_PN = "B31";
"SMBDAT":   PN = "B28"  !CDS_PN = "B28";
"T_SENSE":   PN = "E30"  !CDS_PN = "E30";
"TEST0":   PN = "FF24"  !CDS_PN = "FF24";
"TEST1":   PN = "FF27"  !CDS_PN = "FF27";
"TEST2":   PN = "FF30"  !CDS_PN = "FF30";
BODY = "Q_RES","I98": #LOCATION = "R1421" !CDS_LOCATION = "R1421" &SEC = "1" #&CDS_SEC = "1";
"A":   PN = "1"  !CDS_PN = "1";
"B":   PN = "2"  !CDS_PN = "2";
BODY = "Q_RES","I102": #LOCATION = "R1416" !CDS_LOCATION = "R1416" &SEC = "1" #&CDS_SEC = "1";
"A":   PN = "1"  !CDS_PN = "1";
"B":   PN = "2"  !CDS_PN = "2";
BODY = "Q_RES","I113": #LOCATION = "R1427" !CDS_LOCATION = "R1427" &SEC = "1" #&CDS_SEC = "1";
"A":   PN = "1"  !CDS_PN = "1";
"B":   PN = "2"  !CDS_PN = "2";
BODY = "Q_RES","I114": #LOCATION = "R1426" !CDS_LOCATION = "R1426" &SEC = "1" #&CDS_SEC = "1";
"A":   PN = "1"  !CDS_PN = "1";
"B":   PN = "2"  !CDS_PN = "2";
BODY = "Q_RES","I119": #LOCATION = "R869" !CDS_LOCATION = "R869" &SEC = "1" #&CDS_SEC = "1";
"A":   PN = "1"  !CDS_PN = "1";
"B":   PN = "2"  !CDS_PN = "2";
BODY = "Q_RES","I132": #LOCATION = "R1488" !CDS_LOCATION = "R1488" &SEC = "1" #&CDS_SEC = "1";
"A":   PN = "1"  !CDS_PN = "1";
"B":   PN = "2"  !CDS_PN = "2";
BODY = "Q_RES","I136": #LOCATION = "R1417" !CDS_LOCATION = "R1417" &SEC = "1" #&CDS_SEC = "1";
"A":   PN = "1"  !CDS_PN = "1";
"B":   PN = "2"  !CDS_PN = "2";
BODY = "Q_RES","I137": #LOCATION = "R1499" !CDS_LOCATION = "R1499" &SEC = "1" #&CDS_SEC = "1";
"A":   PN = "1"  !CDS_PN = "1";
"B":   PN = "2"  !CDS_PN = "2";
BODY = "Q_RES","I139": #LOCATION = "R1490" !CDS_LOCATION = "R1490" &SEC = "1" #&CDS_SEC = "1";
"A":   PN = "1"  !CDS_PN = "1";
"B":   PN = "2"  !CDS_PN = "2";
BODY = "Q_RES","I140": #LOCATION = "R1489" !CDS_LOCATION = "R1489" &SEC = "1" #&CDS_SEC = "1";
"A":   PN = "1"  !CDS_PN = "1";
"B":   PN = "2"  !CDS_PN = "2";
DRAWING = "@t6g_mb_lib.t6g(sch_1):page452";
BODY = "PT5161LRS","I7": #LOCATION = "U6016" !CDS_LOCATION = "U6016" &SEC = "4" #&CDS_SEC = "4";
"PWR_1A_1":   PN = "BV20"  !CDS_PN = "BV20";
"PWR_1A_2":   PN = "CE17"  !CDS_PN = "CE17";
"PWR_1A_3":   PN = "CE20"  !CDS_PN = "CE20";
"PWR_1A_4":   PN = "CM17"  !CDS_PN = "CM17";
"PWR_1A_5":   PN = "CM20"  !CDS_PN = "CM20";
"PWR_1D":   PN = "BV17"  !CDS_PN = "BV17";
"PWR_2A_1":   PN = "AC17"  !CDS_PN = "AC17";
"PWR_2A_2":   PN = "AC20"  !CDS_PN = "AC20";
"PWR_2A_3":   PN = "AK17"  !CDS_PN = "AK17";
"PWR_2A_4":   PN = "AK20"  !CDS_PN = "AK20";
"PWR_2A_5":   PN = "AU17"  !CDS_PN = "AU17";
"PWR_2A_6":   PN = "AU20"  !CDS_PN = "AU20";
"PWR_2A_7":   PN = "BD17"  !CDS_PN = "BD17";
"PWR_2A_8":   PN = "BD20"  !CDS_PN = "BD20";
"PWR_2A_9":   PN = "DF17"  !CDS_PN = "DF17";
"PWR_2A_10":   PN = "DF20"  !CDS_PN = "DF20";
"PWR_2A_11":   PN = "DN17"  !CDS_PN = "DN17";
"PWR_2A_12":   PN = "DN20"  !CDS_PN = "DN20";
"PWR_2A_13":   PN = "DY17"  !CDS_PN = "DY17";
"PWR_2A_14":   PN = "DY20"  !CDS_PN = "DY20";
"PWR_2A_15":   PN = "EG17"  !CDS_PN = "EG17";
"PWR_2A_16":   PN = "EG20"  !CDS_PN = "EG20";
"PWR_2A_17":   PN = "EP17"  !CDS_PN = "EP17";
"PWR_2A_18":   PN = "EP20"  !CDS_PN = "EP20";
"PWR_2A_19":   PN = "T17"  !CDS_PN = "T17";
"PWR_2A_20":   PN = "T20"  !CDS_PN = "T20";
"PWR_2D_1":   PN = "BL17"  !CDS_PN = "BL17";
"PWR_2D_2":   PN = "BL20"  !CDS_PN = "BL20";
"PWR_2D_3":   PN = "CW17"  !CDS_PN = "CW17";
"PWR_2D_4":   PN = "CW20"  !CDS_PN = "CW20";
"VQPS":   PN = "G1"  !CDS_PN = "G1";
BODY = "Q_RES","I15": #LOCATION = "R6797" !CDS_LOCATION = "R6797" &SEC = "1" #&CDS_SEC = "1";
"A":   PN = "1"  !CDS_PN = "1";
"B":   PN = "2"  !CDS_PN = "2";
BODY = "Q_RES","I18": #LOCATION = "R6796" !CDS_LOCATION = "R6796" &SEC = "1" #&CDS_SEC = "1";
"A":   PN = "1"  !CDS_PN = "1";
"B":   PN = "2"  !CDS_PN = "2";
BODY = "PT5161LRS","I19": #LOCATION = "U6016" !CDS_LOCATION = "U6016" &SEC = "5" #&CDS_SEC = "5";
"GND1":   PN = "AC13"  !CDS_PN = "AC13";
"GND2":   PN = "AC22"  !CDS_PN = "AC22";
"GND3":   PN = "AC32"  !CDS_PN = "AC32";
"GND4":   PN = "AC4"  !CDS_PN = "AC4";
"GND5":   PN = "AD2"  !CDS_PN = "AD2";
"GND6":   PN = "AD34"  !CDS_PN = "AD34";
"GND7":   PN = "AE1"  !CDS_PN = "AE1";
"GND8":   PN = "AE35"  !CDS_PN = "AE35";
"GND9":   PN = "AK13"  !CDS_PN = "AK13";
"GND10":   PN = "AK22"  !CDS_PN = "AK22";
"GND11":   PN = "AK32"  !CDS_PN = "AK32";
"GND12":   PN = "AK4"  !CDS_PN = "AK4";
"GND13":   PN = "AL2"  !CDS_PN = "AL2";
"GND14":   PN = "AL34"  !CDS_PN = "AL34";
"GND15":   PN = "AM1"  !CDS_PN = "AM1";
"GND16":   PN = "AM35"  !CDS_PN = "AM35";
"GND17":   PN = "AU13"  !CDS_PN = "AU13";
"GND18":   PN = "AU22"  !CDS_PN = "AU22";
"GND19":   PN = "AU32"  !CDS_PN = "AU32";
"GND20":   PN = "AU4"  !CDS_PN = "AU4";
"GND21":   PN = "AV2"  !CDS_PN = "AV2";
"GND22":   PN = "AV34"  !CDS_PN = "AV34";
"GND23":   PN = "AW1"  !CDS_PN = "AW1";
"GND24":   PN = "AW35"  !CDS_PN = "AW35";
"GND25":   PN = "B19"  !CDS_PN = "B19";
"GND26":   PN = "BD13"  !CDS_PN = "BD13";
"GND27":   PN = "BD22"  !CDS_PN = "BD22";
"GND28":   PN = "BD32"  !CDS_PN = "BD32";
"GND29":   PN = "BD4"  !CDS_PN = "BD4";
"GND30":   PN = "BE2"  !CDS_PN = "BE2";
"GND31":   PN = "BE34"  !CDS_PN = "BE34";
"GND32":   PN = "BF1"  !CDS_PN = "BF1";
"GND33":   PN = "BF35"  !CDS_PN = "BF35";
"GND34":   PN = "BL13"  !CDS_PN = "BL13";
"GND35":   PN = "BL22"  !CDS_PN = "BL22";
"GND36":   PN = "BL32"  !CDS_PN = "BL32";
"GND37":   PN = "BL4"  !CDS_PN = "BL4";
"GND38":   PN = "BM2"  !CDS_PN = "BM2";
"GND39":   PN = "BM34"  !CDS_PN = "BM34";
"GND40":   PN = "BN1"  !CDS_PN = "BN1";
"GND41":   PN = "BN35"  !CDS_PN = "BN35";
"GND42":   PN = "BV13"  !CDS_PN = "BV13";
"GND43":   PN = "BV22"  !CDS_PN = "BV22";
"GND44":   PN = "BV32"  !CDS_PN = "BV32";
"GND45":   PN = "BV4"  !CDS_PN = "BV4";
"GND46":   PN = "BW2"  !CDS_PN = "BW2";
"GND47":   PN = "BW34"  !CDS_PN = "BW34";
"GND48":   PN = "BY1"  !CDS_PN = "BY1";
"GND49":   PN = "BY35"  !CDS_PN = "BY35";
"GND50":   PN = "CE13"  !CDS_PN = "CE13";
"GND51":   PN = "CE22"  !CDS_PN = "CE22";
"GND52":   PN = "CE32"  !CDS_PN = "CE32";
"GND53":   PN = "CE4"  !CDS_PN = "CE4";
"GND54":   PN = "CF2"  !CDS_PN = "CF2";
"GND55":   PN = "CF34"  !CDS_PN = "CF34";
"GND56":   PN = "CG1"  !CDS_PN = "CG1";
"GND57":   PN = "CG35"  !CDS_PN = "CG35";
"GND58":   PN = "CM13"  !CDS_PN = "CM13";
"GND59":   PN = "CM22"  !CDS_PN = "CM22";
"GND60":   PN = "CM32"  !CDS_PN = "CM32";
"GND61":   PN = "CM4"  !CDS_PN = "CM4";
"GND62":   PN = "CN2"  !CDS_PN = "CN2";
"GND63":   PN = "CN34"  !CDS_PN = "CN34";
"GND64":   PN = "CP1"  !CDS_PN = "CP1";
"GND65":   PN = "CP35"  !CDS_PN = "CP35";
"GND66":   PN = "CW13"  !CDS_PN = "CW13";
"GND67":   PN = "CW22"  !CDS_PN = "CW22";
"GND68":   PN = "CW32"  !CDS_PN = "CW32";
"GND69":   PN = "CW4"  !CDS_PN = "CW4";
"GND70":   PN = "CY2"  !CDS_PN = "CY2";
"GND71":   PN = "CY34"  !CDS_PN = "CY34";
"GND72":   PN = "DA1"  !CDS_PN = "DA1";
"GND73":   PN = "DA35"  !CDS_PN = "DA35";
"GND74":   PN = "DF13"  !CDS_PN = "DF13";
"GND75":   PN = "DF22"  !CDS_PN = "DF22";
"GND76":   PN = "DF32"  !CDS_PN = "DF32";
"GND77":   PN = "DF4"  !CDS_PN = "DF4";
"GND78":   PN = "DG2"  !CDS_PN = "DG2";
"GND79":   PN = "DG34"  !CDS_PN = "DG34";
"GND80":   PN = "DH1"  !CDS_PN = "DH1";
"GND81":   PN = "DH35"  !CDS_PN = "DH35";
"GND82":   PN = "DN13"  !CDS_PN = "DN13";
"GND83":   PN = "DN22"  !CDS_PN = "DN22";
"GND84":   PN = "DN32"  !CDS_PN = "DN32";
"GND85":   PN = "DN4"  !CDS_PN = "DN4";
"GND86":   PN = "DP2"  !CDS_PN = "DP2";
"GND87":   PN = "DP34"  !CDS_PN = "DP34";
"GND88":   PN = "DR1"  !CDS_PN = "DR1";
"GND89":   PN = "DR35"  !CDS_PN = "DR35";
"GND90":   PN = "DY13"  !CDS_PN = "DY13";
"GND91":   PN = "DY22"  !CDS_PN = "DY22";
"GND92":   PN = "DY32"  !CDS_PN = "DY32";
"GND93":   PN = "DY4"  !CDS_PN = "DY4";
"GND94":   PN = "E14"  !CDS_PN = "E14";
"GND95":   PN = "E27"  !CDS_PN = "E27";
"GND96":   PN = "E33"  !CDS_PN = "E33";
"GND97":   PN = "EA2"  !CDS_PN = "EA2";
"GND98":   PN = "EA34"  !CDS_PN = "EA34";
"GND99":   PN = "EB1"  !CDS_PN = "EB1";
"GND100":   PN = "EB35"  !CDS_PN = "EB35";
"GND101":   PN = "EG13"  !CDS_PN = "EG13";
"GND102":   PN = "EG22"  !CDS_PN = "EG22";
"GND103":   PN = "EG32"  !CDS_PN = "EG32";
"GND104":   PN = "EG4"  !CDS_PN = "EG4";
"GND105":   PN = "EH2"  !CDS_PN = "EH2";
"GND106":   PN = "EH34"  !CDS_PN = "EH34";
"GND107":   PN = "EJ1"  !CDS_PN = "EJ1";
"GND108":   PN = "EJ35"  !CDS_PN = "EJ35";
"GND109":   PN = "EP13"  !CDS_PN = "EP13";
"GND110":   PN = "EP22"  !CDS_PN = "EP22";
"GND111":   PN = "EP32"  !CDS_PN = "EP32";
"GND112":   PN = "EP4"  !CDS_PN = "EP4";
"GND113":   PN = "ER2"  !CDS_PN = "ER2";
"GND114":   PN = "ER34"  !CDS_PN = "ER34";
"GND115":   PN = "ET1"  !CDS_PN = "ET1";
"GND116":   PN = "ET35"  !CDS_PN = "ET35";
"GND117":   PN = "FA15"  !CDS_PN = "FA15";
"GND118":   PN = "FA32"  !CDS_PN = "FA32";
"GND119":   PN = "FB2"  !CDS_PN = "FB2";
"GND120":   PN = "FB34"  !CDS_PN = "FB34";
"GND121":   PN = "FC19"  !CDS_PN = "FC19";
"GND122":   PN = "FC23"  !CDS_PN = "FC23";
"GND123":   PN = "FC25"  !CDS_PN = "FC25";
"GND124":   PN = "FC28"  !CDS_PN = "FC28";
"GND125":   PN = "FC3"  !CDS_PN = "FC3";
"GND126":   PN = "FC6"  !CDS_PN = "FC6";
"GND127":   PN = "FC9"  !CDS_PN = "FC9";
"GND128":   PN = "FD1"  !CDS_PN = "FD1";
"GND129":   PN = "FD35"  !CDS_PN = "FD35";
"GND130":   PN = "FF14"  !CDS_PN = "FF14";
"GND131":   PN = "FF21"  !CDS_PN = "FF21";
"GND132":   PN = "FJ12"  !CDS_PN = "FJ12";
"GND133":   PN = "FJ19"  !CDS_PN = "FJ19";
"GND134":   PN = "H12"  !CDS_PN = "H12";
"GND135":   PN = "H16"  !CDS_PN = "H16";
"GND136":   PN = "H19"  !CDS_PN = "H19";
"GND137":   PN = "H31"  !CDS_PN = "H31";
"GND138":   PN = "J22"  !CDS_PN = "J22";
"GND139":   PN = "J4"  !CDS_PN = "J4";
"GND140":   PN = "K2"  !CDS_PN = "K2";
"GND141":   PN = "K34"  !CDS_PN = "K34";
"GND142":   PN = "L1"  !CDS_PN = "L1";
"GND143":   PN = "L35"  !CDS_PN = "L35";
"GND144":   PN = "T13"  !CDS_PN = "T13";
"GND145":   PN = "T22"  !CDS_PN = "T22";
"GND146":   PN = "T32"  !CDS_PN = "T32";
"GND147":   PN = "T4"  !CDS_PN = "T4";
"GND148":   PN = "U2"  !CDS_PN = "U2";
"GND149":   PN = "U34"  !CDS_PN = "U34";
"GND150":   PN = "V1"  !CDS_PN = "V1";
"GND151":   PN = "V35"  !CDS_PN = "V35";
"NCF_GND1":   PN = "A1"  !CDS_PN = "A1";
"NCF_GND2":   PN = "A35"  !CDS_PN = "A35";
"NCF_GND3":   PN = "C2"  !CDS_PN = "C2";
"NCF_GND4":   PN = "C34"  !CDS_PN = "C34";
"NCF_GND5":   PN = "D1"  !CDS_PN = "D1";
"NCF_GND6":   PN = "D35"  !CDS_PN = "D35";
"NCF_GND7":   PN = "FE2"  !CDS_PN = "FE2";
"NCF_GND8":   PN = "FE34"  !CDS_PN = "FE34";
"NCF_GND9":   PN = "FG1"  !CDS_PN = "FG1";
"NCF_GND10":   PN = "FG35"  !CDS_PN = "FG35";
"NCF_GND11":   PN = "FH2"  !CDS_PN = "FH2";
"NCF_GND12":   PN = "FH34"  !CDS_PN = "FH34";
BODY = "Q_RES","I20": #LOCATION = "R6795" !CDS_LOCATION = "R6795" &SEC = "1" #&CDS_SEC = "1";
"A":   PN = "1"  !CDS_PN = "1";
"B":   PN = "2"  !CDS_PN = "2";
BODY = "Q_RES","I21": #LOCATION = "R6794" !CDS_LOCATION = "R6794" &SEC = "1" #&CDS_SEC = "1";
"A":   PN = "1"  !CDS_PN = "1";
"B":   PN = "2"  !CDS_PN = "2";
DRAWING = "@t6g_mb_lib.t6g(sch_1):page454";
BODY = "Q_RES","I2": #LOCATION = "R852" !CDS_LOCATION = "R852" #SEC = "1" !CDS_SEC = "1";
"A":   PN = "1"  !CDS_PN = "1";
"B":   PN = "2"  !CDS_PN = "2";
BODY = "Q_RES","I3": #LOCATION = "R853" !CDS_LOCATION = "R853" #SEC = "1" !CDS_SEC = "1";
"A":   PN = "1"  !CDS_PN = "1";
"B":   PN = "2"  !CDS_PN = "2";
BODY = "Q_CAP","I5": #LOCATION = "C367" !CDS_LOCATION = "C367" &SEC = "1" #&CDS_SEC = "1";
"A":   PN = "1"  !CDS_PN = "1";
"B":   PN = "2"  !CDS_PN = "2";
BODY = "Q_CAP","I6": #LOCATION = "C375" !CDS_LOCATION = "C375" &SEC = "1" #&CDS_SEC = "1";
"A":   PN = "1"  !CDS_PN = "1";
"B":   PN = "2"  !CDS_PN = "2";
BODY = "Q_CAP","I8": #LOCATION = "C378" !CDS_LOCATION = "C378" &SEC = "1" #&CDS_SEC = "1";
"A":   PN = "1"  !CDS_PN = "1";
"B":   PN = "2"  !CDS_PN = "2";
BODY = "Q_CAP","I10": #LOCATION = "C369" !CDS_LOCATION = "C369" &SEC = "1" #&CDS_SEC = "1";
"A":   PN = "1"  !CDS_PN = "1";
"B":   PN = "2"  !CDS_PN = "2";
BODY = "Q_CAP","I11": #LOCATION = "C372" !CDS_LOCATION = "C372" &SEC = "1" #&CDS_SEC = "1";
"A":   PN = "1"  !CDS_PN = "1";
"B":   PN = "2"  !CDS_PN = "2";
BODY = "Q_CAP","I12": #LOCATION = "C371" !CDS_LOCATION = "C371" &SEC = "1" #&CDS_SEC = "1";
"A":   PN = "1"  !CDS_PN = "1";
"B":   PN = "2"  !CDS_PN = "2";
BODY = "Q_CAP","I13": #LOCATION = "C374" !CDS_LOCATION = "C374" &SEC = "1" #&CDS_SEC = "1";
"A":   PN = "1"  !CDS_PN = "1";
"B":   PN = "2"  !CDS_PN = "2";
BODY = "Q_CAP","I15": #LOCATION = "C376" !CDS_LOCATION = "C376" &SEC = "1" #&CDS_SEC = "1";
"A":   PN = "1"  !CDS_PN = "1";
"B":   PN = "2"  !CDS_PN = "2";
BODY = "Q_CAP","I16": #LOCATION = "C377" !CDS_LOCATION = "C377" &SEC = "1" #&CDS_SEC = "1";
"A":   PN = "1"  !CDS_PN = "1";
"B":   PN = "2"  !CDS_PN = "2";
BODY = "Q_CAP","I17": #LOCATION = "C379" !CDS_LOCATION = "C379" &SEC = "1" #&CDS_SEC = "1";
"A":   PN = "1"  !CDS_PN = "1";
"B":   PN = "2"  !CDS_PN = "2";
BODY = "Q_CAP","I18": #LOCATION = "C380" !CDS_LOCATION = "C380" &SEC = "1" #&CDS_SEC = "1";
"A":   PN = "1"  !CDS_PN = "1";
"B":   PN = "2"  !CDS_PN = "2";
BODY = "Q_CAP","I19": #LOCATION = "C381" !CDS_LOCATION = "C381" &SEC = "1" #&CDS_SEC = "1";
"A":   PN = "1"  !CDS_PN = "1";
"B":   PN = "2"  !CDS_PN = "2";
BODY = "Q_RES","I20": #LOCATION = "R858" !CDS_LOCATION = "R858" &SEC = "1" #&CDS_SEC = "1";
"A":   PN = "1"  !CDS_PN = "1";
"B":   PN = "2"  !CDS_PN = "2";
BODY = "Q_INDUCTOR","I21": #LOCATION = "L7" !CDS_LOCATION = "L7" &SEC = "1" #&CDS_SEC = "1";
"1":   PN = "1"  !CDS_PN = "1";
"2":   PN = "2"  !CDS_PN = "2";
BODY = "Q_CAP","I24": #LOCATION = "C366" !CDS_LOCATION = "C366" &SEC = "1" #&CDS_SEC = "1";
"A":   PN = "1"  !CDS_PN = "1";
"B":   PN = "2"  !CDS_PN = "2";
BODY = "Q_CAP","I25": #LOCATION = "C368" !CDS_LOCATION = "C368" &SEC = "1" #&CDS_SEC = "1";
"A":   PN = "1"  !CDS_PN = "1";
"B":   PN = "2"  !CDS_PN = "2";
BODY = "Q_CAP","I27": #LOCATION = "C370" !CDS_LOCATION = "C370" &SEC = "1" #&CDS_SEC = "1";
"A":   PN = "1"  !CDS_PN = "1";
"B":   PN = "2"  !CDS_PN = "2";
BODY = "Q_CAP","I28": #LOCATION = "C373" !CDS_LOCATION = "C373" &SEC = "1" #&CDS_SEC = "1";
"A":   PN = "1"  !CDS_PN = "1";
"B":   PN = "2"  !CDS_PN = "2";
BODY = "Q_CAP","I31": #LOCATION = "C421" !CDS_LOCATION = "C421" &SEC = "1" #&CDS_SEC = "1";
"A":   PN = "1"  !CDS_PN = "1";
"B":   PN = "2"  !CDS_PN = "2";
BODY = "Q_CAP","I35": #LOCATION = "C396" !CDS_LOCATION = "C396" &SEC = "1" #&CDS_SEC = "1";
"A":   PN = "1"  !CDS_PN = "1";
"B":   PN = "2"  !CDS_PN = "2";
BODY = "Q_CAP","I36": #LOCATION = "C397" !CDS_LOCATION = "C397" &SEC = "1" #&CDS_SEC = "1";
"A":   PN = "1"  !CDS_PN = "1";
"B":   PN = "2"  !CDS_PN = "2";
BODY = "Q_CAP","I37": #LOCATION = "C427" !CDS_LOCATION = "C427" &SEC = "1" #&CDS_SEC = "1";
"A":   PN = "1"  !CDS_PN = "1";
"B":   PN = "2"  !CDS_PN = "2";
BODY = "Q_CAP","I38": #LOCATION = "C393" !CDS_LOCATION = "C393" &SEC = "1" #&CDS_SEC = "1";
"A":   PN = "1"  !CDS_PN = "1";
"B":   PN = "2"  !CDS_PN = "2";
BODY = "Q_CAP","I39": #LOCATION = "C430" !CDS_LOCATION = "C430" &SEC = "1" #&CDS_SEC = "1";
"A":   PN = "1"  !CDS_PN = "1";
"B":   PN = "2"  !CDS_PN = "2";
BODY = "Q_CAP","I40": #LOCATION = "C400" !CDS_LOCATION = "C400" &SEC = "1" #&CDS_SEC = "1";
"A":   PN = "1"  !CDS_PN = "1";
"B":   PN = "2"  !CDS_PN = "2";
BODY = "Q_RES","I41": #LOCATION = "R859" !CDS_LOCATION = "R859" &SEC = "1" #&CDS_SEC = "1";
"A":   PN = "1"  !CDS_PN = "1";
"B":   PN = "2"  !CDS_PN = "2";
BODY = "Q_CAP","I42": #LOCATION = "C384" !CDS_LOCATION = "C384" &SEC = "1" #&CDS_SEC = "1";
"A":   PN = "1"  !CDS_PN = "1";
"B":   PN = "2"  !CDS_PN = "2";
BODY = "Q_CAP","I43": #LOCATION = "C387" !CDS_LOCATION = "C387" &SEC = "1" #&CDS_SEC = "1";
"A":   PN = "1"  !CDS_PN = "1";
"B":   PN = "2"  !CDS_PN = "2";
BODY = "Q_CAP","I44": #LOCATION = "C410" !CDS_LOCATION = "C410" &SEC = "1" #&CDS_SEC = "1";
"A":   PN = "1"  !CDS_PN = "1";
"B":   PN = "2"  !CDS_PN = "2";
BODY = "Q_CAP","I45": #LOCATION = "C420" !CDS_LOCATION = "C420" &SEC = "1" #&CDS_SEC = "1";
"A":   PN = "1"  !CDS_PN = "1";
"B":   PN = "2"  !CDS_PN = "2";
BODY = "Q_CAP","I46": #LOCATION = "C398" !CDS_LOCATION = "C398" &SEC = "1" #&CDS_SEC = "1";
"A":   PN = "1"  !CDS_PN = "1";
"B":   PN = "2"  !CDS_PN = "2";
BODY = "Q_CAP","I47": #LOCATION = "C401" !CDS_LOCATION = "C401" &SEC = "1" #&CDS_SEC = "1";
"A":   PN = "1"  !CDS_PN = "1";
"B":   PN = "2"  !CDS_PN = "2";
BODY = "Q_CAP","I48": #LOCATION = "C406" !CDS_LOCATION = "C406" &SEC = "1" #&CDS_SEC = "1";
"A":   PN = "1"  !CDS_PN = "1";
"B":   PN = "2"  !CDS_PN = "2";
BODY = "Q_CAP","I49": #LOCATION = "C407" !CDS_LOCATION = "C407" &SEC = "1" #&CDS_SEC = "1";
"A":   PN = "1"  !CDS_PN = "1";
"B":   PN = "2"  !CDS_PN = "2";
BODY = "Q_CAP","I50": #LOCATION = "C391" !CDS_LOCATION = "C391" &SEC = "1" #&CDS_SEC = "1";
"A":   PN = "1"  !CDS_PN = "1";
"B":   PN = "2"  !CDS_PN = "2";
BODY = "Q_CAP","I51": #LOCATION = "C415" !CDS_LOCATION = "C415" &SEC = "1" #&CDS_SEC = "1";
"A":   PN = "1"  !CDS_PN = "1";
"B":   PN = "2"  !CDS_PN = "2";
BODY = "Q_CAP","I52": #LOCATION = "C418" !CDS_LOCATION = "C418" &SEC = "1" #&CDS_SEC = "1";
"A":   PN = "1"  !CDS_PN = "1";
"B":   PN = "2"  !CDS_PN = "2";
BODY = "Q_CAP","I53": #LOCATION = "C422" !CDS_LOCATION = "C422" &SEC = "1" #&CDS_SEC = "1";
"A":   PN = "1"  !CDS_PN = "1";
"B":   PN = "2"  !CDS_PN = "2";
BODY = "Q_CAP","I54": #LOCATION = "C416" !CDS_LOCATION = "C416" &SEC = "1" #&CDS_SEC = "1";
"A":   PN = "1"  !CDS_PN = "1";
"B":   PN = "2"  !CDS_PN = "2";
BODY = "Q_CAP","I55": #LOCATION = "C413" !CDS_LOCATION = "C413" &SEC = "1" #&CDS_SEC = "1";
"A":   PN = "1"  !CDS_PN = "1";
"B":   PN = "2"  !CDS_PN = "2";
BODY = "Q_CAP","I56": #LOCATION = "C417" !CDS_LOCATION = "C417" &SEC = "1" #&CDS_SEC = "1";
"A":   PN = "1"  !CDS_PN = "1";
"B":   PN = "2"  !CDS_PN = "2";
BODY = "Q_CAP","I57": #LOCATION = "C412" !CDS_LOCATION = "C412" &SEC = "1" #&CDS_SEC = "1";
"A":   PN = "1"  !CDS_PN = "1";
"B":   PN = "2"  !CDS_PN = "2";
BODY = "Q_CAP","I58": #LOCATION = "C386" !CDS_LOCATION = "C386" &SEC = "1" #&CDS_SEC = "1";
"A":   PN = "1"  !CDS_PN = "1";
"B":   PN = "2"  !CDS_PN = "2";
BODY = "Q_CAP","I59": #LOCATION = "C399" !CDS_LOCATION = "C399" &SEC = "1" #&CDS_SEC = "1";
"A":   PN = "1"  !CDS_PN = "1";
"B":   PN = "2"  !CDS_PN = "2";
BODY = "Q_CAP","I60": #LOCATION = "C402" !CDS_LOCATION = "C402" &SEC = "1" #&CDS_SEC = "1";
"A":   PN = "1"  !CDS_PN = "1";
"B":   PN = "2"  !CDS_PN = "2";
BODY = "Q_CAP","I61": #LOCATION = "C403" !CDS_LOCATION = "C403" &SEC = "1" #&CDS_SEC = "1";
"A":   PN = "1"  !CDS_PN = "1";
"B":   PN = "2"  !CDS_PN = "2";
BODY = "Q_CAP","I62": #LOCATION = "C411" !CDS_LOCATION = "C411" &SEC = "1" #&CDS_SEC = "1";
"A":   PN = "1"  !CDS_PN = "1";
"B":   PN = "2"  !CDS_PN = "2";
BODY = "Q_CAP","I64": #LOCATION = "C395" !CDS_LOCATION = "C395" &SEC = "1" #&CDS_SEC = "1";
"A":   PN = "1"  !CDS_PN = "1";
"B":   PN = "2"  !CDS_PN = "2";
BODY = "Q_CAP","I67": #LOCATION = "C425" !CDS_LOCATION = "C425" &SEC = "1" #&CDS_SEC = "1";
"A":   PN = "1"  !CDS_PN = "1";
"B":   PN = "2"  !CDS_PN = "2";
BODY = "Q_CAP","I68": #LOCATION = "C389" !CDS_LOCATION = "C389" &SEC = "1" #&CDS_SEC = "1";
"A":   PN = "1"  !CDS_PN = "1";
"B":   PN = "2"  !CDS_PN = "2";
BODY = "Q_CAP","I69": #LOCATION = "C424" !CDS_LOCATION = "C424" &SEC = "1" #&CDS_SEC = "1";
"A":   PN = "1"  !CDS_PN = "1";
"B":   PN = "2"  !CDS_PN = "2";
BODY = "Q_CAP","I70": #LOCATION = "C429" !CDS_LOCATION = "C429" &SEC = "1" #&CDS_SEC = "1";
"A":   PN = "1"  !CDS_PN = "1";
"B":   PN = "2"  !CDS_PN = "2";
BODY = "Q_CAP","I71": #LOCATION = "C382" !CDS_LOCATION = "C382" &SEC = "1" #&CDS_SEC = "1";
"A":   PN = "1"  !CDS_PN = "1";
"B":   PN = "2"  !CDS_PN = "2";
BODY = "Q_CAP","I72": #LOCATION = "C431" !CDS_LOCATION = "C431" &SEC = "1" #&CDS_SEC = "1";
"A":   PN = "1"  !CDS_PN = "1";
"B":   PN = "2"  !CDS_PN = "2";
BODY = "Q_INDUCTOR","I74": #LOCATION = "L8" !CDS_LOCATION = "L8" &SEC = "1" #&CDS_SEC = "1";
"1":   PN = "1"  !CDS_PN = "1";
"2":   PN = "2"  !CDS_PN = "2";
BODY = "Q_CAP","I76": #LOCATION = "C404" !CDS_LOCATION = "C404" &SEC = "1" #&CDS_SEC = "1";
"A":   PN = "1"  !CDS_PN = "1";
"B":   PN = "2"  !CDS_PN = "2";
BODY = "Q_CAP","I77": #LOCATION = "C408" !CDS_LOCATION = "C408" &SEC = "1" #&CDS_SEC = "1";
"A":   PN = "1"  !CDS_PN = "1";
"B":   PN = "2"  !CDS_PN = "2";
BODY = "Q_CAP","I78": #LOCATION = "C414" !CDS_LOCATION = "C414" &SEC = "1" #&CDS_SEC = "1";
"A":   PN = "1"  !CDS_PN = "1";
"B":   PN = "2"  !CDS_PN = "2";
BODY = "Q_CAP","I79": #LOCATION = "C419" !CDS_LOCATION = "C419" &SEC = "1" #&CDS_SEC = "1";
"A":   PN = "1"  !CDS_PN = "1";
"B":   PN = "2"  !CDS_PN = "2";
BODY = "Q_CAP","I80": #LOCATION = "C423" !CDS_LOCATION = "C423" &SEC = "1" #&CDS_SEC = "1";
"A":   PN = "1"  !CDS_PN = "1";
"B":   PN = "2"  !CDS_PN = "2";
BODY = "Q_CAP","I82": #LOCATION = "C383" !CDS_LOCATION = "C383" &SEC = "1" #&CDS_SEC = "1";
"A":   PN = "1"  !CDS_PN = "1";
"B":   PN = "2"  !CDS_PN = "2";
BODY = "Q_CAP","I83": #LOCATION = "C385" !CDS_LOCATION = "C385" &SEC = "1" #&CDS_SEC = "1";
"A":   PN = "1"  !CDS_PN = "1";
"B":   PN = "2"  !CDS_PN = "2";
BODY = "Q_CAP","I84": #LOCATION = "C388" !CDS_LOCATION = "C388" &SEC = "1" #&CDS_SEC = "1";
"A":   PN = "1"  !CDS_PN = "1";
"B":   PN = "2"  !CDS_PN = "2";
BODY = "Q_CAP","I85": #LOCATION = "C392" !CDS_LOCATION = "C392" &SEC = "1" #&CDS_SEC = "1";
"A":   PN = "1"  !CDS_PN = "1";
"B":   PN = "2"  !CDS_PN = "2";
BODY = "Q_CAP","I86": #LOCATION = "C405" !CDS_LOCATION = "C405" &SEC = "1" #&CDS_SEC = "1";
"A":   PN = "1"  !CDS_PN = "1";
"B":   PN = "2"  !CDS_PN = "2";
BODY = "Q_CAP","I87": #LOCATION = "C409" !CDS_LOCATION = "C409" &SEC = "1" #&CDS_SEC = "1";
"A":   PN = "1"  !CDS_PN = "1";
"B":   PN = "2"  !CDS_PN = "2";
BODY = "Q_INDUCTOR","I88": #LOCATION = "L32" !CDS_LOCATION = "L32" &SEC = "1" #&CDS_SEC = "1";
"1":   PN = "1"  !CDS_PN = "1";
"2":   PN = "2"  !CDS_PN = "2";
BODY = "Q_RES","I89": #LOCATION = "R857" !CDS_LOCATION = "R857" &SEC = "1" #&CDS_SEC = "1";
"A":   PN = "1"  !CDS_PN = "1";
"B":   PN = "2"  !CDS_PN = "2";
BODY = "Q_CAP","I90": #LOCATION = "C390" !CDS_LOCATION = "C390" &SEC = "1" #&CDS_SEC = "1";
"A":   PN = "1"  !CDS_PN = "1";
"B":   PN = "2"  !CDS_PN = "2";
BODY = "Q_CAP","I91": #LOCATION = "C394" !CDS_LOCATION = "C394" &SEC = "1" #&CDS_SEC = "1";
"A":   PN = "1"  !CDS_PN = "1";
"B":   PN = "2"  !CDS_PN = "2";
BODY = "Q_CAP","I92": #LOCATION = "C426" !CDS_LOCATION = "C426" &SEC = "1" #&CDS_SEC = "1";
"A":   PN = "1"  !CDS_PN = "1";
"B":   PN = "2"  !CDS_PN = "2";
BODY = "Q_CAP","I93": #LOCATION = "C428" !CDS_LOCATION = "C428" &SEC = "1" #&CDS_SEC = "1";
"A":   PN = "1"  !CDS_PN = "1";
"B":   PN = "2"  !CDS_PN = "2";
BODY = "Q_CAPP","I94": #LOCATION = "C7004" !CDS_LOCATION = "C7004" &SEC = "1" #&CDS_SEC = "1";
"A":   PN = "1"  !CDS_PN = "1";
"B":   PN = "2"  !CDS_PN = "2";
BODY = "Q_CAPP","I95": #LOCATION = "C7005" !CDS_LOCATION = "C7005" &SEC = "1" #&CDS_SEC = "1";
"A":   PN = "1"  !CDS_PN = "1";
"B":   PN = "2"  !CDS_PN = "2";
BODY = "Q_CAP","I96": #LOCATION = "C7006" !CDS_LOCATION = "C7006" &SEC = "1" #&CDS_SEC = "1";
"A":   PN = "1"  !CDS_PN = "1";
"B":   PN = "2"  !CDS_PN = "2";
BODY = "Q_CAP","I97": #LOCATION = "C7007" !CDS_LOCATION = "C7007" &SEC = "1" #&CDS_SEC = "1";
"A":   PN = "1"  !CDS_PN = "1";
"B":   PN = "2"  !CDS_PN = "2";
BODY = "Q_CAPP","I98": #LOCATION = "C7026" !CDS_LOCATION = "C7026" &SEC = "1" #&CDS_SEC = "1";
"A":   PN = "1"  !CDS_PN = "1";
"B":   PN = "2"  !CDS_PN = "2";
BODY = "Q_CAPP","I99": #LOCATION = "C7027" !CDS_LOCATION = "C7027" &SEC = "1" #&CDS_SEC = "1";
"A":   PN = "1"  !CDS_PN = "1";
"B":   PN = "2"  !CDS_PN = "2";
BODY = "Q_CAP","I100": #LOCATION = "C7028" !CDS_LOCATION = "C7028" &SEC = "1" #&CDS_SEC = "1";
"A":   PN = "1"  !CDS_PN = "1";
"B":   PN = "2"  !CDS_PN = "2";
BODY = "Q_CAPP","I101": #LOCATION = "C7037" !CDS_LOCATION = "C7037" &SEC = "1" #&CDS_SEC = "1";
"A":   PN = "1"  !CDS_PN = "1";
"B":   PN = "2"  !CDS_PN = "2";
BODY = "Q_CAP","I102": #LOCATION = "C7038" !CDS_LOCATION = "C7038" &SEC = "1" #&CDS_SEC = "1";
"A":   PN = "1"  !CDS_PN = "1";
"B":   PN = "2"  !CDS_PN = "2";
BODY = "Q_CAP","I103": #LOCATION = "C7039" !CDS_LOCATION = "C7039" &SEC = "1" #&CDS_SEC = "1";
"A":   PN = "1"  !CDS_PN = "1";
"B":   PN = "2"  !CDS_PN = "2";
BODY = "Q_CAP","I104": #LOCATION = "C7040" !CDS_LOCATION = "C7040" &SEC = "1" #&CDS_SEC = "1";
"A":   PN = "1"  !CDS_PN = "1";
"B":   PN = "2"  !CDS_PN = "2";
BODY = "Q_CAP","I105": #LOCATION = "C7041" !CDS_LOCATION = "C7041" &SEC = "1" #&CDS_SEC = "1";
"A":   PN = "1"  !CDS_PN = "1";
"B":   PN = "2"  !CDS_PN = "2";
DRAWING = "@t6g_mb_lib.t6g(sch_1):page462";
BODY = "Q_RES","I17": #LOCATION = "R909" !CDS_LOCATION = "R909" &SEC = "1" #&CDS_SEC = "1";
"A":   PN = "1"  !CDS_PN = "1";
"B":   PN = "2"  !CDS_PN = "2";
BODY = "Q_RES","I19": #LOCATION = "R916" !CDS_LOCATION = "R916" &SEC = "1" #&CDS_SEC = "1";
"A":   PN = "1"  !CDS_PN = "1";
"B":   PN = "2"  !CDS_PN = "2";
BODY = "Q_RES","I20": #LOCATION = "R917" !CDS_LOCATION = "R917" &SEC = "1" #&CDS_SEC = "1";
"A":   PN = "1"  !CDS_PN = "1";
"B":   PN = "2"  !CDS_PN = "2";
BODY = "Q_RES","I21": #LOCATION = "R919" !CDS_LOCATION = "R919" &SEC = "1" #&CDS_SEC = "1";
"A":   PN = "1"  !CDS_PN = "1";
"B":   PN = "2"  !CDS_PN = "2";
BODY = "Q_RES","I22": #LOCATION = "R915" !CDS_LOCATION = "R915" &SEC = "1" #&CDS_SEC = "1";
"A":   PN = "1"  !CDS_PN = "1";
"B":   PN = "2"  !CDS_PN = "2";
BODY = "Q_RES","I23": #LOCATION = "R918" !CDS_LOCATION = "R918" &SEC = "1" #&CDS_SEC = "1";
"A":   PN = "1"  !CDS_PN = "1";
"B":   PN = "2"  !CDS_PN = "2";
BODY = "Q_RES","I30": #LOCATION = "R641" !CDS_LOCATION = "R641" &SEC = "1" #&CDS_SEC = "1";
"A":   PN = "1"  !CDS_PN = "1";
"B":   PN = "2"  !CDS_PN = "2";
BODY = "Q_RES","I31": #LOCATION = "R622" !CDS_LOCATION = "R622" #SEC = "1" !CDS_SEC = "1";
"A":   PN = "1"  !CDS_PN = "1";
"B":   PN = "2"  !CDS_PN = "2";
BODY = "Q_RES","I32": #LOCATION = "R621" !CDS_LOCATION = "R621" #SEC = "1" !CDS_SEC = "1";
"A":   PN = "1"  !CDS_PN = "1";
"B":   PN = "2"  !CDS_PN = "2";
BODY = "Q_RES","I33": #LOCATION = "R696" !CDS_LOCATION = "R696" &SEC = "1" #&CDS_SEC = "1";
"A":   PN = "1"  !CDS_PN = "1";
"B":   PN = "2"  !CDS_PN = "2";
BODY = "Q_RES","I41": #LOCATION = "R914" !CDS_LOCATION = "R914" &SEC = "1" #&CDS_SEC = "1";
"A":   PN = "1"  !CDS_PN = "1";
"B":   PN = "2"  !CDS_PN = "2";
BODY = "Q_RES","I42": #LOCATION = "R913" !CDS_LOCATION = "R913" &SEC = "1" #&CDS_SEC = "1";
"A":   PN = "1"  !CDS_PN = "1";
"B":   PN = "2"  !CDS_PN = "2";
BODY = "Q_RES","I46": #LOCATION = "R642" !CDS_LOCATION = "R642" &SEC = "1" #&CDS_SEC = "1";
"A":   PN = "1"  !CDS_PN = "1";
"B":   PN = "2"  !CDS_PN = "2";
BODY = "Q_RES","I50": #LOCATION = "R921" !CDS_LOCATION = "R921" &SEC = "1" #&CDS_SEC = "1";
"A":   PN = "1"  !CDS_PN = "1";
"B":   PN = "2"  !CDS_PN = "2";
BODY = "Q_RES","I51": #LOCATION = "R923" !CDS_LOCATION = "R923" &SEC = "1" #&CDS_SEC = "1";
"A":   PN = "1"  !CDS_PN = "1";
"B":   PN = "2"  !CDS_PN = "2";
BODY = "Q_RES","I53": #LOCATION = "R924" !CDS_LOCATION = "R924" &SEC = "1" #&CDS_SEC = "1";
"A":   PN = "1"  !CDS_PN = "1";
"B":   PN = "2"  !CDS_PN = "2";
BODY = "Q_RES","I54": #LOCATION = "R920" !CDS_LOCATION = "R920" &SEC = "1" #&CDS_SEC = "1";
"A":   PN = "1"  !CDS_PN = "1";
"B":   PN = "2"  !CDS_PN = "2";
BODY = "Q_RES","I55": #LOCATION = "R922" !CDS_LOCATION = "R922" &SEC = "1" #&CDS_SEC = "1";
"A":   PN = "1"  !CDS_PN = "1";
"B":   PN = "2"  !CDS_PN = "2";
BODY = "Q_RES","I56": #LOCATION = "R912" !CDS_LOCATION = "R912" &SEC = "1" #&CDS_SEC = "1";
"A":   PN = "1"  !CDS_PN = "1";
"B":   PN = "2"  !CDS_PN = "2";
BODY = "Q_RES","I64": #LOCATION = "R926" !CDS_LOCATION = "R926" &SEC = "1" #&CDS_SEC = "1";
"A":   PN = "1"  !CDS_PN = "1";
"B":   PN = "2"  !CDS_PN = "2";
BODY = "Q_RES","I65": #LOCATION = "R925" !CDS_LOCATION = "R925" &SEC = "1" #&CDS_SEC = "1";
"A":   PN = "1"  !CDS_PN = "1";
"B":   PN = "2"  !CDS_PN = "2";
BODY = "Q_RES","I69": #LOCATION = "R895" !CDS_LOCATION = "R895" #SEC = "1" !CDS_SEC = "1";
"A":   PN = "1"  !CDS_PN = "1";
"B":   PN = "2"  !CDS_PN = "2";
BODY = "Q_RES","I70": #LOCATION = "R901" !CDS_LOCATION = "R901" &SEC = "1" #&CDS_SEC = "1";
"A":   PN = "1"  !CDS_PN = "1";
"B":   PN = "2"  !CDS_PN = "2";
BODY = "Q_RES","I79": #LOCATION = "R903" !CDS_LOCATION = "R903" &SEC = "1" #&CDS_SEC = "1";
"A":   PN = "1"  !CDS_PN = "1";
"B":   PN = "2"  !CDS_PN = "2";
BODY = "Q_RES","I80": #LOCATION = "R902" !CDS_LOCATION = "R902" &SEC = "1" #&CDS_SEC = "1";
"A":   PN = "1"  !CDS_PN = "1";
"B":   PN = "2"  !CDS_PN = "2";
BODY = "Q_RES","I81": #LOCATION = "R906" !CDS_LOCATION = "R906" &SEC = "1" #&CDS_SEC = "1";
"A":   PN = "1"  !CDS_PN = "1";
"B":   PN = "2"  !CDS_PN = "2";
BODY = "Q_RES","I82": #LOCATION = "R904" !CDS_LOCATION = "R904" &SEC = "1" #&CDS_SEC = "1";
"A":   PN = "1"  !CDS_PN = "1";
"B":   PN = "2"  !CDS_PN = "2";
BODY = "Q_RES","I83": #LOCATION = "R949" !CDS_LOCATION = "R949" &SEC = "1" #&CDS_SEC = "1";
"A":   PN = "1"  !CDS_PN = "1";
"B":   PN = "2"  !CDS_PN = "2";
BODY = "Q_RES","I84": #LOCATION = "R927" !CDS_LOCATION = "R927" &SEC = "1" #&CDS_SEC = "1";
"A":   PN = "1"  !CDS_PN = "1";
"B":   PN = "2"  !CDS_PN = "2";
BODY = "Q_RES","I90": #LOCATION = "R908" !CDS_LOCATION = "R908" &SEC = "1" #&CDS_SEC = "1";
"A":   PN = "1"  !CDS_PN = "1";
"B":   PN = "2"  !CDS_PN = "2";
BODY = "Q_RES","I92": #LOCATION = "R907" !CDS_LOCATION = "R907" &SEC = "1" #&CDS_SEC = "1";
"A":   PN = "1"  !CDS_PN = "1";
"B":   PN = "2"  !CDS_PN = "2";
BODY = "Q_RES","I93": #LOCATION = "R911" !CDS_LOCATION = "R911" &SEC = "1" #&CDS_SEC = "1";
"A":   PN = "1"  !CDS_PN = "1";
"B":   PN = "2"  !CDS_PN = "2";
BODY = "PT5161LRS","I97": #LOCATION = "U6017" !CDS_LOCATION = "U6017" &SEC = "3" #&CDS_SEC = "3";
"CLKREQ_N":   PN = "G35"  !CDS_PN = "G35";
"EE_CLK":   PN = "FF5"  !CDS_PN = "FF5";
"EE_DAT":   PN = "FJ3"  !CDS_PN = "FJ3";
"GPIO0":   PN = "FJ6"  !CDS_PN = "FJ6";
"GPIO1":   PN = "FJ23"  !CDS_PN = "FJ23";
"GPIO2":   PN = "FJ25"  !CDS_PN = "FJ25";
"GPIO3":   PN = "FJ28"  !CDS_PN = "FJ28";
"INT_N":   PN = "FJ31"  !CDS_PN = "FJ31";
"JTAG_TCK":   PN = "B3"  !CDS_PN = "B3";
"JTAG_TDI":   PN = "B6"  !CDS_PN = "B6";
"JTAG_TDO":   PN = "B9"  !CDS_PN = "B9";
"JTAG_TEST_MODE":   PN = "FF8"  !CDS_PN = "FF8";
"JTAG_TMS":   PN = "B12"  !CDS_PN = "B12";
"JTAG_TRST_N":   PN = "E8"  !CDS_PN = "E8";
"MODE":   PN = "FJ9"  !CDS_PN = "FJ9";
"PERST_N":   PN = "F2"  !CDS_PN = "F2";
"REFCLK_OUTN":   PN = "E18"  !CDS_PN = "E18";
"REFCLK_OUTP":   PN = "B16"  !CDS_PN = "B16";
"REFCLKN":   PN = "FF18"  !CDS_PN = "FF18";
"REFCLKP":   PN = "FJ16"  !CDS_PN = "FJ16";
"RESET_N":   PN = "FF11"  !CDS_PN = "FF11";
"RXDET_BYP":   PN = "E11"  !CDS_PN = "E11";
"SCAN_MODE":   PN = "FF33"  !CDS_PN = "FF33";
"SMB_ADDR1":   PN = "F34"  !CDS_PN = "F34";
"SMB_ADDR2":   PN = "B23"  !CDS_PN = "B23";
"SMB_ADDR3":   PN = "B25"  !CDS_PN = "B25";
"SMBCLK":   PN = "B31"  !CDS_PN = "B31";
"SMBDAT":   PN = "B28"  !CDS_PN = "B28";
"T_SENSE":   PN = "E30"  !CDS_PN = "E30";
"TEST0":   PN = "FF24"  !CDS_PN = "FF24";
"TEST1":   PN = "FF27"  !CDS_PN = "FF27";
"TEST2":   PN = "FF30"  !CDS_PN = "FF30";
BODY = "Q_RES","I98": #LOCATION = "R1433" !CDS_LOCATION = "R1433" &SEC = "1" #&CDS_SEC = "1";
"A":   PN = "1"  !CDS_PN = "1";
"B":   PN = "2"  !CDS_PN = "2";
BODY = "Q_RES","I103": #LOCATION = "R1429" !CDS_LOCATION = "R1429" &SEC = "1" #&CDS_SEC = "1";
"A":   PN = "1"  !CDS_PN = "1";
"B":   PN = "2"  !CDS_PN = "2";
BODY = "Q_RES","I114": #LOCATION = "R1435" !CDS_LOCATION = "R1435" &SEC = "1" #&CDS_SEC = "1";
"A":   PN = "1"  !CDS_PN = "1";
"B":   PN = "2"  !CDS_PN = "2";
BODY = "Q_RES","I115": #LOCATION = "R1434" !CDS_LOCATION = "R1434" &SEC = "1" #&CDS_SEC = "1";
"A":   PN = "1"  !CDS_PN = "1";
"B":   PN = "2"  !CDS_PN = "2";
BODY = "Q_RES","I119": #LOCATION = "R910" !CDS_LOCATION = "R910" &SEC = "1" #&CDS_SEC = "1";
"A":   PN = "1"  !CDS_PN = "1";
"B":   PN = "2"  !CDS_PN = "2";
BODY = "Q_RES","I132": #LOCATION = "R1511" !CDS_LOCATION = "R1511" &SEC = "1" #&CDS_SEC = "1";
"A":   PN = "1"  !CDS_PN = "1";
"B":   PN = "2"  !CDS_PN = "2";
BODY = "Q_RES","I136": #LOCATION = "R1430" !CDS_LOCATION = "R1430" &SEC = "1" #&CDS_SEC = "1";
"A":   PN = "1"  !CDS_PN = "1";
"B":   PN = "2"  !CDS_PN = "2";
BODY = "Q_RES","I137": #LOCATION = "R1513" !CDS_LOCATION = "R1513" &SEC = "1" #&CDS_SEC = "1";
"A":   PN = "1"  !CDS_PN = "1";
"B":   PN = "2"  !CDS_PN = "2";
BODY = "Q_RES","I139": #LOCATION = "R1510" !CDS_LOCATION = "R1510" &SEC = "1" #&CDS_SEC = "1";
"A":   PN = "1"  !CDS_PN = "1";
"B":   PN = "2"  !CDS_PN = "2";
BODY = "Q_RES","I140": #LOCATION = "R1512" !CDS_LOCATION = "R1512" &SEC = "1" #&CDS_SEC = "1";
"A":   PN = "1"  !CDS_PN = "1";
"B":   PN = "2"  !CDS_PN = "2";
BODY = "Q_RES","I146": #LOCATION = "R695" !CDS_LOCATION = "R695" #SEC = "1" !CDS_SEC = "1";
"A":   PN = "1"  !CDS_PN = "1";
"B":   PN = "2"  !CDS_PN = "2";
DRAWING = "@t6g_mb_lib.t6g(sch_1):page463";
BODY = "PT5161LRS","I5": #LOCATION = "U6017" !CDS_LOCATION = "U6017" &SEC = "4" #&CDS_SEC = "4";
"PWR_1A_1":   PN = "BV20"  !CDS_PN = "BV20";
"PWR_1A_2":   PN = "CE17"  !CDS_PN = "CE17";
"PWR_1A_3":   PN = "CE20"  !CDS_PN = "CE20";
"PWR_1A_4":   PN = "CM17"  !CDS_PN = "CM17";
"PWR_1A_5":   PN = "CM20"  !CDS_PN = "CM20";
"PWR_1D":   PN = "BV17"  !CDS_PN = "BV17";
"PWR_2A_1":   PN = "AC17"  !CDS_PN = "AC17";
"PWR_2A_2":   PN = "AC20"  !CDS_PN = "AC20";
"PWR_2A_3":   PN = "AK17"  !CDS_PN = "AK17";
"PWR_2A_4":   PN = "AK20"  !CDS_PN = "AK20";
"PWR_2A_5":   PN = "AU17"  !CDS_PN = "AU17";
"PWR_2A_6":   PN = "AU20"  !CDS_PN = "AU20";
"PWR_2A_7":   PN = "BD17"  !CDS_PN = "BD17";
"PWR_2A_8":   PN = "BD20"  !CDS_PN = "BD20";
"PWR_2A_9":   PN = "DF17"  !CDS_PN = "DF17";
"PWR_2A_10":   PN = "DF20"  !CDS_PN = "DF20";
"PWR_2A_11":   PN = "DN17"  !CDS_PN = "DN17";
"PWR_2A_12":   PN = "DN20"  !CDS_PN = "DN20";
"PWR_2A_13":   PN = "DY17"  !CDS_PN = "DY17";
"PWR_2A_14":   PN = "DY20"  !CDS_PN = "DY20";
"PWR_2A_15":   PN = "EG17"  !CDS_PN = "EG17";
"PWR_2A_16":   PN = "EG20"  !CDS_PN = "EG20";
"PWR_2A_17":   PN = "EP17"  !CDS_PN = "EP17";
"PWR_2A_18":   PN = "EP20"  !CDS_PN = "EP20";
"PWR_2A_19":   PN = "T17"  !CDS_PN = "T17";
"PWR_2A_20":   PN = "T20"  !CDS_PN = "T20";
"PWR_2D_1":   PN = "BL17"  !CDS_PN = "BL17";
"PWR_2D_2":   PN = "BL20"  !CDS_PN = "BL20";
"PWR_2D_3":   PN = "CW17"  !CDS_PN = "CW17";
"PWR_2D_4":   PN = "CW20"  !CDS_PN = "CW20";
"VQPS":   PN = "G1"  !CDS_PN = "G1";
BODY = "Q_RES","I13": #LOCATION = "R6903" !CDS_LOCATION = "R6903" &SEC = "1" #&CDS_SEC = "1";
"A":   PN = "1"  !CDS_PN = "1";
"B":   PN = "2"  !CDS_PN = "2";
BODY = "Q_RES","I15": #LOCATION = "R6902" !CDS_LOCATION = "R6902" &SEC = "1" #&CDS_SEC = "1";
"A":   PN = "1"  !CDS_PN = "1";
"B":   PN = "2"  !CDS_PN = "2";
BODY = "PT5161LRS","I17": #LOCATION = "U6017" !CDS_LOCATION = "U6017" &SEC = "5" #&CDS_SEC = "5";
"GND1":   PN = "AC13"  !CDS_PN = "AC13";
"GND2":   PN = "AC22"  !CDS_PN = "AC22";
"GND3":   PN = "AC32"  !CDS_PN = "AC32";
"GND4":   PN = "AC4"  !CDS_PN = "AC4";
"GND5":   PN = "AD2"  !CDS_PN = "AD2";
"GND6":   PN = "AD34"  !CDS_PN = "AD34";
"GND7":   PN = "AE1"  !CDS_PN = "AE1";
"GND8":   PN = "AE35"  !CDS_PN = "AE35";
"GND9":   PN = "AK13"  !CDS_PN = "AK13";
"GND10":   PN = "AK22"  !CDS_PN = "AK22";
"GND11":   PN = "AK32"  !CDS_PN = "AK32";
"GND12":   PN = "AK4"  !CDS_PN = "AK4";
"GND13":   PN = "AL2"  !CDS_PN = "AL2";
"GND14":   PN = "AL34"  !CDS_PN = "AL34";
"GND15":   PN = "AM1"  !CDS_PN = "AM1";
"GND16":   PN = "AM35"  !CDS_PN = "AM35";
"GND17":   PN = "AU13"  !CDS_PN = "AU13";
"GND18":   PN = "AU22"  !CDS_PN = "AU22";
"GND19":   PN = "AU32"  !CDS_PN = "AU32";
"GND20":   PN = "AU4"  !CDS_PN = "AU4";
"GND21":   PN = "AV2"  !CDS_PN = "AV2";
"GND22":   PN = "AV34"  !CDS_PN = "AV34";
"GND23":   PN = "AW1"  !CDS_PN = "AW1";
"GND24":   PN = "AW35"  !CDS_PN = "AW35";
"GND25":   PN = "B19"  !CDS_PN = "B19";
"GND26":   PN = "BD13"  !CDS_PN = "BD13";
"GND27":   PN = "BD22"  !CDS_PN = "BD22";
"GND28":   PN = "BD32"  !CDS_PN = "BD32";
"GND29":   PN = "BD4"  !CDS_PN = "BD4";
"GND30":   PN = "BE2"  !CDS_PN = "BE2";
"GND31":   PN = "BE34"  !CDS_PN = "BE34";
"GND32":   PN = "BF1"  !CDS_PN = "BF1";
"GND33":   PN = "BF35"  !CDS_PN = "BF35";
"GND34":   PN = "BL13"  !CDS_PN = "BL13";
"GND35":   PN = "BL22"  !CDS_PN = "BL22";
"GND36":   PN = "BL32"  !CDS_PN = "BL32";
"GND37":   PN = "BL4"  !CDS_PN = "BL4";
"GND38":   PN = "BM2"  !CDS_PN = "BM2";
"GND39":   PN = "BM34"  !CDS_PN = "BM34";
"GND40":   PN = "BN1"  !CDS_PN = "BN1";
"GND41":   PN = "BN35"  !CDS_PN = "BN35";
"GND42":   PN = "BV13"  !CDS_PN = "BV13";
"GND43":   PN = "BV22"  !CDS_PN = "BV22";
"GND44":   PN = "BV32"  !CDS_PN = "BV32";
"GND45":   PN = "BV4"  !CDS_PN = "BV4";
"GND46":   PN = "BW2"  !CDS_PN = "BW2";
"GND47":   PN = "BW34"  !CDS_PN = "BW34";
"GND48":   PN = "BY1"  !CDS_PN = "BY1";
"GND49":   PN = "BY35"  !CDS_PN = "BY35";
"GND50":   PN = "CE13"  !CDS_PN = "CE13";
"GND51":   PN = "CE22"  !CDS_PN = "CE22";
"GND52":   PN = "CE32"  !CDS_PN = "CE32";
"GND53":   PN = "CE4"  !CDS_PN = "CE4";
"GND54":   PN = "CF2"  !CDS_PN = "CF2";
"GND55":   PN = "CF34"  !CDS_PN = "CF34";
"GND56":   PN = "CG1"  !CDS_PN = "CG1";
"GND57":   PN = "CG35"  !CDS_PN = "CG35";
"GND58":   PN = "CM13"  !CDS_PN = "CM13";
"GND59":   PN = "CM22"  !CDS_PN = "CM22";
"GND60":   PN = "CM32"  !CDS_PN = "CM32";
"GND61":   PN = "CM4"  !CDS_PN = "CM4";
"GND62":   PN = "CN2"  !CDS_PN = "CN2";
"GND63":   PN = "CN34"  !CDS_PN = "CN34";
"GND64":   PN = "CP1"  !CDS_PN = "CP1";
"GND65":   PN = "CP35"  !CDS_PN = "CP35";
"GND66":   PN = "CW13"  !CDS_PN = "CW13";
"GND67":   PN = "CW22"  !CDS_PN = "CW22";
"GND68":   PN = "CW32"  !CDS_PN = "CW32";
"GND69":   PN = "CW4"  !CDS_PN = "CW4";
"GND70":   PN = "CY2"  !CDS_PN = "CY2";
"GND71":   PN = "CY34"  !CDS_PN = "CY34";
"GND72":   PN = "DA1"  !CDS_PN = "DA1";
"GND73":   PN = "DA35"  !CDS_PN = "DA35";
"GND74":   PN = "DF13"  !CDS_PN = "DF13";
"GND75":   PN = "DF22"  !CDS_PN = "DF22";
"GND76":   PN = "DF32"  !CDS_PN = "DF32";
"GND77":   PN = "DF4"  !CDS_PN = "DF4";
"GND78":   PN = "DG2"  !CDS_PN = "DG2";
"GND79":   PN = "DG34"  !CDS_PN = "DG34";
"GND80":   PN = "DH1"  !CDS_PN = "DH1";
"GND81":   PN = "DH35"  !CDS_PN = "DH35";
"GND82":   PN = "DN13"  !CDS_PN = "DN13";
"GND83":   PN = "DN22"  !CDS_PN = "DN22";
"GND84":   PN = "DN32"  !CDS_PN = "DN32";
"GND85":   PN = "DN4"  !CDS_PN = "DN4";
"GND86":   PN = "DP2"  !CDS_PN = "DP2";
"GND87":   PN = "DP34"  !CDS_PN = "DP34";
"GND88":   PN = "DR1"  !CDS_PN = "DR1";
"GND89":   PN = "DR35"  !CDS_PN = "DR35";
"GND90":   PN = "DY13"  !CDS_PN = "DY13";
"GND91":   PN = "DY22"  !CDS_PN = "DY22";
"GND92":   PN = "DY32"  !CDS_PN = "DY32";
"GND93":   PN = "DY4"  !CDS_PN = "DY4";
"GND94":   PN = "E14"  !CDS_PN = "E14";
"GND95":   PN = "E27"  !CDS_PN = "E27";
"GND96":   PN = "E33"  !CDS_PN = "E33";
"GND97":   PN = "EA2"  !CDS_PN = "EA2";
"GND98":   PN = "EA34"  !CDS_PN = "EA34";
"GND99":   PN = "EB1"  !CDS_PN = "EB1";
"GND100":   PN = "EB35"  !CDS_PN = "EB35";
"GND101":   PN = "EG13"  !CDS_PN = "EG13";
"GND102":   PN = "EG22"  !CDS_PN = "EG22";
"GND103":   PN = "EG32"  !CDS_PN = "EG32";
"GND104":   PN = "EG4"  !CDS_PN = "EG4";
"GND105":   PN = "EH2"  !CDS_PN = "EH2";
"GND106":   PN = "EH34"  !CDS_PN = "EH34";
"GND107":   PN = "EJ1"  !CDS_PN = "EJ1";
"GND108":   PN = "EJ35"  !CDS_PN = "EJ35";
"GND109":   PN = "EP13"  !CDS_PN = "EP13";
"GND110":   PN = "EP22"  !CDS_PN = "EP22";
"GND111":   PN = "EP32"  !CDS_PN = "EP32";
"GND112":   PN = "EP4"  !CDS_PN = "EP4";
"GND113":   PN = "ER2"  !CDS_PN = "ER2";
"GND114":   PN = "ER34"  !CDS_PN = "ER34";
"GND115":   PN = "ET1"  !CDS_PN = "ET1";
"GND116":   PN = "ET35"  !CDS_PN = "ET35";
"GND117":   PN = "FA15"  !CDS_PN = "FA15";
"GND118":   PN = "FA32"  !CDS_PN = "FA32";
"GND119":   PN = "FB2"  !CDS_PN = "FB2";
"GND120":   PN = "FB34"  !CDS_PN = "FB34";
"GND121":   PN = "FC19"  !CDS_PN = "FC19";
"GND122":   PN = "FC23"  !CDS_PN = "FC23";
"GND123":   PN = "FC25"  !CDS_PN = "FC25";
"GND124":   PN = "FC28"  !CDS_PN = "FC28";
"GND125":   PN = "FC3"  !CDS_PN = "FC3";
"GND126":   PN = "FC6"  !CDS_PN = "FC6";
"GND127":   PN = "FC9"  !CDS_PN = "FC9";
"GND128":   PN = "FD1"  !CDS_PN = "FD1";
"GND129":   PN = "FD35"  !CDS_PN = "FD35";
"GND130":   PN = "FF14"  !CDS_PN = "FF14";
"GND131":   PN = "FF21"  !CDS_PN = "FF21";
"GND132":   PN = "FJ12"  !CDS_PN = "FJ12";
"GND133":   PN = "FJ19"  !CDS_PN = "FJ19";
"GND134":   PN = "H12"  !CDS_PN = "H12";
"GND135":   PN = "H16"  !CDS_PN = "H16";
"GND136":   PN = "H19"  !CDS_PN = "H19";
"GND137":   PN = "H31"  !CDS_PN = "H31";
"GND138":   PN = "J22"  !CDS_PN = "J22";
"GND139":   PN = "J4"  !CDS_PN = "J4";
"GND140":   PN = "K2"  !CDS_PN = "K2";
"GND141":   PN = "K34"  !CDS_PN = "K34";
"GND142":   PN = "L1"  !CDS_PN = "L1";
"GND143":   PN = "L35"  !CDS_PN = "L35";
"GND144":   PN = "T13"  !CDS_PN = "T13";
"GND145":   PN = "T22"  !CDS_PN = "T22";
"GND146":   PN = "T32"  !CDS_PN = "T32";
"GND147":   PN = "T4"  !CDS_PN = "T4";
"GND148":   PN = "U2"  !CDS_PN = "U2";
"GND149":   PN = "U34"  !CDS_PN = "U34";
"GND150":   PN = "V1"  !CDS_PN = "V1";
"GND151":   PN = "V35"  !CDS_PN = "V35";
"NCF_GND1":   PN = "A1"  !CDS_PN = "A1";
"NCF_GND2":   PN = "A35"  !CDS_PN = "A35";
"NCF_GND3":   PN = "C2"  !CDS_PN = "C2";
"NCF_GND4":   PN = "C34"  !CDS_PN = "C34";
"NCF_GND5":   PN = "D1"  !CDS_PN = "D1";
"NCF_GND6":   PN = "D35"  !CDS_PN = "D35";
"NCF_GND7":   PN = "FE2"  !CDS_PN = "FE2";
"NCF_GND8":   PN = "FE34"  !CDS_PN = "FE34";
"NCF_GND9":   PN = "FG1"  !CDS_PN = "FG1";
"NCF_GND10":   PN = "FG35"  !CDS_PN = "FG35";
"NCF_GND11":   PN = "FH2"  !CDS_PN = "FH2";
"NCF_GND12":   PN = "FH34"  !CDS_PN = "FH34";
BODY = "Q_RES","I18": #LOCATION = "R6901" !CDS_LOCATION = "R6901" &SEC = "1" #&CDS_SEC = "1";
"A":   PN = "1"  !CDS_PN = "1";
"B":   PN = "2"  !CDS_PN = "2";
BODY = "Q_RES","I19": #LOCATION = "R6900" !CDS_LOCATION = "R6900" &SEC = "1" #&CDS_SEC = "1";
"A":   PN = "1"  !CDS_PN = "1";
"B":   PN = "2"  !CDS_PN = "2";
DRAWING = "@t6g_mb_lib.t6g(sch_1):page465";
BODY = "Q_RES","I1": #LOCATION = "R894" !CDS_LOCATION = "R894" #SEC = "1" !CDS_SEC = "1";
"A":   PN = "1"  !CDS_PN = "1";
"B":   PN = "2"  !CDS_PN = "2";
BODY = "Q_RES","I2": #LOCATION = "R893" !CDS_LOCATION = "R893" #SEC = "1" !CDS_SEC = "1";
"A":   PN = "1"  !CDS_PN = "1";
"B":   PN = "2"  !CDS_PN = "2";
BODY = "Q_CAP","I4": #LOCATION = "C441" !CDS_LOCATION = "C441" &SEC = "1" #&CDS_SEC = "1";
"A":   PN = "1"  !CDS_PN = "1";
"B":   PN = "2"  !CDS_PN = "2";
BODY = "Q_CAP","I6": #LOCATION = "C444" !CDS_LOCATION = "C444" &SEC = "1" #&CDS_SEC = "1";
"A":   PN = "1"  !CDS_PN = "1";
"B":   PN = "2"  !CDS_PN = "2";
BODY = "Q_RES","I8": #LOCATION = "R898" !CDS_LOCATION = "R898" &SEC = "1" #&CDS_SEC = "1";
"A":   PN = "1"  !CDS_PN = "1";
"B":   PN = "2"  !CDS_PN = "2";
BODY = "Q_INDUCTOR","I11": #LOCATION = "L9" !CDS_LOCATION = "L9" &SEC = "1" #&CDS_SEC = "1";
"1":   PN = "1"  !CDS_PN = "1";
"2":   PN = "2"  !CDS_PN = "2";
BODY = "Q_CAP","I14": #LOCATION = "C433" !CDS_LOCATION = "C433" &SEC = "1" #&CDS_SEC = "1";
"A":   PN = "1"  !CDS_PN = "1";
"B":   PN = "2"  !CDS_PN = "2";
BODY = "Q_CAP","I15": #LOCATION = "C435" !CDS_LOCATION = "C435" &SEC = "1" #&CDS_SEC = "1";
"A":   PN = "1"  !CDS_PN = "1";
"B":   PN = "2"  !CDS_PN = "2";
BODY = "Q_CAP","I16": #LOCATION = "C437" !CDS_LOCATION = "C437" &SEC = "1" #&CDS_SEC = "1";
"A":   PN = "1"  !CDS_PN = "1";
"B":   PN = "2"  !CDS_PN = "2";
BODY = "Q_CAP","I17": #LOCATION = "C432" !CDS_LOCATION = "C432" &SEC = "1" #&CDS_SEC = "1";
"A":   PN = "1"  !CDS_PN = "1";
"B":   PN = "2"  !CDS_PN = "2";
BODY = "Q_CAP","I18": #LOCATION = "C434" !CDS_LOCATION = "C434" &SEC = "1" #&CDS_SEC = "1";
"A":   PN = "1"  !CDS_PN = "1";
"B":   PN = "2"  !CDS_PN = "2";
BODY = "Q_CAP","I19": #LOCATION = "C438" !CDS_LOCATION = "C438" &SEC = "1" #&CDS_SEC = "1";
"A":   PN = "1"  !CDS_PN = "1";
"B":   PN = "2"  !CDS_PN = "2";
BODY = "Q_CAP","I20": #LOCATION = "C440" !CDS_LOCATION = "C440" &SEC = "1" #&CDS_SEC = "1";
"A":   PN = "1"  !CDS_PN = "1";
"B":   PN = "2"  !CDS_PN = "2";
BODY = "Q_CAP","I21": #LOCATION = "C436" !CDS_LOCATION = "C436" &SEC = "1" #&CDS_SEC = "1";
"A":   PN = "1"  !CDS_PN = "1";
"B":   PN = "2"  !CDS_PN = "2";
BODY = "Q_CAP","I23": #LOCATION = "C439" !CDS_LOCATION = "C439" &SEC = "1" #&CDS_SEC = "1";
"A":   PN = "1"  !CDS_PN = "1";
"B":   PN = "2"  !CDS_PN = "2";
BODY = "Q_CAP","I24": #LOCATION = "C442" !CDS_LOCATION = "C442" &SEC = "1" #&CDS_SEC = "1";
"A":   PN = "1"  !CDS_PN = "1";
"B":   PN = "2"  !CDS_PN = "2";
BODY = "Q_CAP","I25": #LOCATION = "C443" !CDS_LOCATION = "C443" &SEC = "1" #&CDS_SEC = "1";
"A":   PN = "1"  !CDS_PN = "1";
"B":   PN = "2"  !CDS_PN = "2";
BODY = "Q_CAP","I26": #LOCATION = "C445" !CDS_LOCATION = "C445" &SEC = "1" #&CDS_SEC = "1";
"A":   PN = "1"  !CDS_PN = "1";
"B":   PN = "2"  !CDS_PN = "2";
BODY = "Q_CAP","I27": #LOCATION = "C446" !CDS_LOCATION = "C446" &SEC = "1" #&CDS_SEC = "1";
"A":   PN = "1"  !CDS_PN = "1";
"B":   PN = "2"  !CDS_PN = "2";
BODY = "Q_CAP","I28": #LOCATION = "C447" !CDS_LOCATION = "C447" &SEC = "1" #&CDS_SEC = "1";
"A":   PN = "1"  !CDS_PN = "1";
"B":   PN = "2"  !CDS_PN = "2";
BODY = "Q_CAP","I34": #LOCATION = "C463" !CDS_LOCATION = "C463" &SEC = "1" #&CDS_SEC = "1";
"A":   PN = "1"  !CDS_PN = "1";
"B":   PN = "2"  !CDS_PN = "2";
BODY = "Q_CAP","I35": #LOCATION = "C464" !CDS_LOCATION = "C464" &SEC = "1" #&CDS_SEC = "1";
"A":   PN = "1"  !CDS_PN = "1";
"B":   PN = "2"  !CDS_PN = "2";
BODY = "Q_RES","I36": #LOCATION = "R900" !CDS_LOCATION = "R900" &SEC = "1" #&CDS_SEC = "1";
"A":   PN = "1"  !CDS_PN = "1";
"B":   PN = "2"  !CDS_PN = "2";
BODY = "Q_CAP","I37": #LOCATION = "C495" !CDS_LOCATION = "C495" &SEC = "1" #&CDS_SEC = "1";
"A":   PN = "1"  !CDS_PN = "1";
"B":   PN = "2"  !CDS_PN = "2";
BODY = "Q_CAP","I38": #LOCATION = "C470" !CDS_LOCATION = "C470" &SEC = "1" #&CDS_SEC = "1";
"A":   PN = "1"  !CDS_PN = "1";
"B":   PN = "2"  !CDS_PN = "2";
BODY = "Q_CAP","I39": #LOCATION = "C459" !CDS_LOCATION = "C459" &SEC = "1" #&CDS_SEC = "1";
"A":   PN = "1"  !CDS_PN = "1";
"B":   PN = "2"  !CDS_PN = "2";
BODY = "Q_CAP","I40": #LOCATION = "C480" !CDS_LOCATION = "C480" &SEC = "1" #&CDS_SEC = "1";
"A":   PN = "1"  !CDS_PN = "1";
"B":   PN = "2"  !CDS_PN = "2";
BODY = "Q_CAP","I41": #LOCATION = "C490" !CDS_LOCATION = "C490" &SEC = "1" #&CDS_SEC = "1";
"A":   PN = "1"  !CDS_PN = "1";
"B":   PN = "2"  !CDS_PN = "2";
BODY = "Q_CAP","I42": #LOCATION = "C500" !CDS_LOCATION = "C500" &SEC = "1" #&CDS_SEC = "1";
"A":   PN = "1"  !CDS_PN = "1";
"B":   PN = "2"  !CDS_PN = "2";
BODY = "Q_CAP","I43": #LOCATION = "C473" !CDS_LOCATION = "C473" &SEC = "1" #&CDS_SEC = "1";
"A":   PN = "1"  !CDS_PN = "1";
"B":   PN = "2"  !CDS_PN = "2";
BODY = "Q_CAP","I44": #LOCATION = "C448" !CDS_LOCATION = "C448" &SEC = "1" #&CDS_SEC = "1";
"A":   PN = "1"  !CDS_PN = "1";
"B":   PN = "2"  !CDS_PN = "2";
BODY = "Q_CAP","I45": #LOCATION = "C453" !CDS_LOCATION = "C453" &SEC = "1" #&CDS_SEC = "1";
"A":   PN = "1"  !CDS_PN = "1";
"B":   PN = "2"  !CDS_PN = "2";
BODY = "Q_CAP","I46": #LOCATION = "C477" !CDS_LOCATION = "C477" &SEC = "1" #&CDS_SEC = "1";
"A":   PN = "1"  !CDS_PN = "1";
"B":   PN = "2"  !CDS_PN = "2";
BODY = "Q_CAP","I47": #LOCATION = "C450" !CDS_LOCATION = "C450" &SEC = "1" #&CDS_SEC = "1";
"A":   PN = "1"  !CDS_PN = "1";
"B":   PN = "2"  !CDS_PN = "2";
BODY = "Q_CAP","I48": #LOCATION = "C485" !CDS_LOCATION = "C485" &SEC = "1" #&CDS_SEC = "1";
"A":   PN = "1"  !CDS_PN = "1";
"B":   PN = "2"  !CDS_PN = "2";
BODY = "Q_CAP","I49": #LOCATION = "C488" !CDS_LOCATION = "C488" &SEC = "1" #&CDS_SEC = "1";
"A":   PN = "1"  !CDS_PN = "1";
"B":   PN = "2"  !CDS_PN = "2";
BODY = "Q_CAP","I50": #LOCATION = "C472" !CDS_LOCATION = "C472" &SEC = "1" #&CDS_SEC = "1";
"A":   PN = "1"  !CDS_PN = "1";
"B":   PN = "2"  !CDS_PN = "2";
BODY = "Q_CAP","I51": #LOCATION = "C469" !CDS_LOCATION = "C469" &SEC = "1" #&CDS_SEC = "1";
"A":   PN = "1"  !CDS_PN = "1";
"B":   PN = "2"  !CDS_PN = "2";
BODY = "Q_CAP","I52": #LOCATION = "C494" !CDS_LOCATION = "C494" &SEC = "1" #&CDS_SEC = "1";
"A":   PN = "1"  !CDS_PN = "1";
"B":   PN = "2"  !CDS_PN = "2";
BODY = "Q_CAP","I53": #LOCATION = "C491" !CDS_LOCATION = "C491" &SEC = "1" #&CDS_SEC = "1";
"A":   PN = "1"  !CDS_PN = "1";
"B":   PN = "2"  !CDS_PN = "2";
BODY = "Q_CAP","I54": #LOCATION = "C492" !CDS_LOCATION = "C492" &SEC = "1" #&CDS_SEC = "1";
"A":   PN = "1"  !CDS_PN = "1";
"B":   PN = "2"  !CDS_PN = "2";
BODY = "Q_CAP","I56": #LOCATION = "C481" !CDS_LOCATION = "C481" &SEC = "1" #&CDS_SEC = "1";
"A":   PN = "1"  !CDS_PN = "1";
"B":   PN = "2"  !CDS_PN = "2";
BODY = "Q_CAP","I57": #LOCATION = "C457" !CDS_LOCATION = "C457" &SEC = "1" #&CDS_SEC = "1";
"A":   PN = "1"  !CDS_PN = "1";
"B":   PN = "2"  !CDS_PN = "2";
BODY = "Q_CAP","I60": #LOCATION = "C497" !CDS_LOCATION = "C497" &SEC = "1" #&CDS_SEC = "1";
"A":   PN = "1"  !CDS_PN = "1";
"B":   PN = "2"  !CDS_PN = "2";
BODY = "Q_CAP","I61": #LOCATION = "C455" !CDS_LOCATION = "C455" &SEC = "1" #&CDS_SEC = "1";
"A":   PN = "1"  !CDS_PN = "1";
"B":   PN = "2"  !CDS_PN = "2";
BODY = "Q_INDUCTOR","I63": #LOCATION = "L10" !CDS_LOCATION = "L10" &SEC = "1" #&CDS_SEC = "1";
"1":   PN = "1"  !CDS_PN = "1";
"2":   PN = "2"  !CDS_PN = "2";
BODY = "Q_CAP","I64": #LOCATION = "C466" !CDS_LOCATION = "C466" &SEC = "1" #&CDS_SEC = "1";
"A":   PN = "1"  !CDS_PN = "1";
"B":   PN = "2"  !CDS_PN = "2";
BODY = "Q_CAP","I65": #LOCATION = "C471" !CDS_LOCATION = "C471" &SEC = "1" #&CDS_SEC = "1";
"A":   PN = "1"  !CDS_PN = "1";
"B":   PN = "2"  !CDS_PN = "2";
BODY = "Q_CAP","I67": #LOCATION = "C474" !CDS_LOCATION = "C474" &SEC = "1" #&CDS_SEC = "1";
"A":   PN = "1"  !CDS_PN = "1";
"B":   PN = "2"  !CDS_PN = "2";
BODY = "Q_CAP","I68": #LOCATION = "C478" !CDS_LOCATION = "C478" &SEC = "1" #&CDS_SEC = "1";
"A":   PN = "1"  !CDS_PN = "1";
"B":   PN = "2"  !CDS_PN = "2";
BODY = "Q_CAP","I69": #LOCATION = "C475" !CDS_LOCATION = "C475" &SEC = "1" #&CDS_SEC = "1";
"A":   PN = "1"  !CDS_PN = "1";
"B":   PN = "2"  !CDS_PN = "2";
BODY = "Q_CAP","I70": #LOCATION = "C501" !CDS_LOCATION = "C501" &SEC = "1" #&CDS_SEC = "1";
"A":   PN = "1"  !CDS_PN = "1";
"B":   PN = "2"  !CDS_PN = "2";
BODY = "Q_CAP","I71": #LOCATION = "C476" !CDS_LOCATION = "C476" &SEC = "1" #&CDS_SEC = "1";
"A":   PN = "1"  !CDS_PN = "1";
"B":   PN = "2"  !CDS_PN = "2";
BODY = "Q_CAP","I72": #LOCATION = "C489" !CDS_LOCATION = "C489" &SEC = "1" #&CDS_SEC = "1";
"A":   PN = "1"  !CDS_PN = "1";
"B":   PN = "2"  !CDS_PN = "2";
BODY = "Q_CAP","I73": #LOCATION = "C484" !CDS_LOCATION = "C484" &SEC = "1" #&CDS_SEC = "1";
"A":   PN = "1"  !CDS_PN = "1";
"B":   PN = "2"  !CDS_PN = "2";
BODY = "Q_CAP","I74": #LOCATION = "C454" !CDS_LOCATION = "C454" &SEC = "1" #&CDS_SEC = "1";
"A":   PN = "1"  !CDS_PN = "1";
"B":   PN = "2"  !CDS_PN = "2";
BODY = "Q_CAP","I75": #LOCATION = "C487" !CDS_LOCATION = "C487" &SEC = "1" #&CDS_SEC = "1";
"A":   PN = "1"  !CDS_PN = "1";
"B":   PN = "2"  !CDS_PN = "2";
BODY = "Q_CAP","I76": #LOCATION = "C499" !CDS_LOCATION = "C499" &SEC = "1" #&CDS_SEC = "1";
"A":   PN = "1"  !CDS_PN = "1";
"B":   PN = "2"  !CDS_PN = "2";
BODY = "Q_CAP","I77": #LOCATION = "C482" !CDS_LOCATION = "C482" &SEC = "1" #&CDS_SEC = "1";
"A":   PN = "1"  !CDS_PN = "1";
"B":   PN = "2"  !CDS_PN = "2";
BODY = "Q_CAP","I78": #LOCATION = "C449" !CDS_LOCATION = "C449" &SEC = "1" #&CDS_SEC = "1";
"A":   PN = "1"  !CDS_PN = "1";
"B":   PN = "2"  !CDS_PN = "2";
BODY = "Q_CAP","I79": #LOCATION = "C451" !CDS_LOCATION = "C451" &SEC = "1" #&CDS_SEC = "1";
"A":   PN = "1"  !CDS_PN = "1";
"B":   PN = "2"  !CDS_PN = "2";
BODY = "Q_CAP","I80": #LOCATION = "C493" !CDS_LOCATION = "C493" &SEC = "1" #&CDS_SEC = "1";
"A":   PN = "1"  !CDS_PN = "1";
"B":   PN = "2"  !CDS_PN = "2";
BODY = "Q_CAP","I82": #LOCATION = "C458" !CDS_LOCATION = "C458" &SEC = "1" #&CDS_SEC = "1";
"A":   PN = "1"  !CDS_PN = "1";
"B":   PN = "2"  !CDS_PN = "2";
BODY = "Q_CAP","I83": #LOCATION = "C462" !CDS_LOCATION = "C462" &SEC = "1" #&CDS_SEC = "1";
"A":   PN = "1"  !CDS_PN = "1";
"B":   PN = "2"  !CDS_PN = "2";
BODY = "Q_CAP","I84": #LOCATION = "C452" !CDS_LOCATION = "C452" &SEC = "1" #&CDS_SEC = "1";
"A":   PN = "1"  !CDS_PN = "1";
"B":   PN = "2"  !CDS_PN = "2";
BODY = "Q_CAP","I85": #LOCATION = "C486" !CDS_LOCATION = "C486" &SEC = "1" #&CDS_SEC = "1";
"A":   PN = "1"  !CDS_PN = "1";
"B":   PN = "2"  !CDS_PN = "2";
BODY = "Q_CAP","I86": #LOCATION = "C483" !CDS_LOCATION = "C483" &SEC = "1" #&CDS_SEC = "1";
"A":   PN = "1"  !CDS_PN = "1";
"B":   PN = "2"  !CDS_PN = "2";
BODY = "Q_CAP","I87": #LOCATION = "C479" !CDS_LOCATION = "C479" &SEC = "1" #&CDS_SEC = "1";
"A":   PN = "1"  !CDS_PN = "1";
"B":   PN = "2"  !CDS_PN = "2";
BODY = "Q_INDUCTOR","I88": #LOCATION = "L33" !CDS_LOCATION = "L33" &SEC = "1" #&CDS_SEC = "1";
"1":   PN = "1"  !CDS_PN = "1";
"2":   PN = "2"  !CDS_PN = "2";
BODY = "Q_RES","I89": #LOCATION = "R897" !CDS_LOCATION = "R897" &SEC = "1" #&CDS_SEC = "1";
"A":   PN = "1"  !CDS_PN = "1";
"B":   PN = "2"  !CDS_PN = "2";
BODY = "Q_CAP","I90": #LOCATION = "C456" !CDS_LOCATION = "C456" &SEC = "1" #&CDS_SEC = "1";
"A":   PN = "1"  !CDS_PN = "1";
"B":   PN = "2"  !CDS_PN = "2";
BODY = "Q_CAP","I91": #LOCATION = "C460" !CDS_LOCATION = "C460" &SEC = "1" #&CDS_SEC = "1";
"A":   PN = "1"  !CDS_PN = "1";
"B":   PN = "2"  !CDS_PN = "2";
BODY = "Q_CAP","I92": #LOCATION = "C496" !CDS_LOCATION = "C496" &SEC = "1" #&CDS_SEC = "1";
"A":   PN = "1"  !CDS_PN = "1";
"B":   PN = "2"  !CDS_PN = "2";
BODY = "Q_CAP","I93": #LOCATION = "C498" !CDS_LOCATION = "C498" &SEC = "1" #&CDS_SEC = "1";
"A":   PN = "1"  !CDS_PN = "1";
"B":   PN = "2"  !CDS_PN = "2";
BODY = "Q_CAPP","I94": #LOCATION = "C7029" !CDS_LOCATION = "C7029" &SEC = "1" #&CDS_SEC = "1";
"A":   PN = "1"  !CDS_PN = "1";
"B":   PN = "2"  !CDS_PN = "2";
BODY = "Q_CAPP","I95": #LOCATION = "C7030" !CDS_LOCATION = "C7030" &SEC = "1" #&CDS_SEC = "1";
"A":   PN = "1"  !CDS_PN = "1";
"B":   PN = "2"  !CDS_PN = "2";
BODY = "Q_CAP","I96": #LOCATION = "C7031" !CDS_LOCATION = "C7031" &SEC = "1" #&CDS_SEC = "1";
"A":   PN = "1"  !CDS_PN = "1";
"B":   PN = "2"  !CDS_PN = "2";
DRAWING = "@t6g_mb_lib.t6g(sch_1):page332";
BODY = "Q_RES","I2": #LOCATION = "R4154" !CDS_LOCATION = "R4154" &SEC = "1" #&CDS_SEC = "1";
"A":   PN = "1"  !CDS_PN = "1";
"B":   PN = "2"  !CDS_PN = "2";
BODY = "Q_RES","I4": #LOCATION = "R4153" !CDS_LOCATION = "R4153" &SEC = "1" #&CDS_SEC = "1";
"A":   PN = "1"  !CDS_PN = "1";
"B":   PN = "2"  !CDS_PN = "2";
BODY = "MOSFET_NCH_DUAL","I6": #LOCATION = "Q134" !CDS_LOCATION = "Q134" &SEC = "1" #&CDS_SEC = "1";
"D1":   PN = "6"  !CDS_PN = "6";
"G1":   PN = "2"  !CDS_PN = "2";
"S1":   PN = "1"  !CDS_PN = "1";
BODY = "Q_RES","I8": #LOCATION = "R4155" !CDS_LOCATION = "R4155" &SEC = "1" #&CDS_SEC = "1";
"A":   PN = "1"  !CDS_PN = "1";
"B":   PN = "2"  !CDS_PN = "2";
BODY = "MOSFET_NCH_DUAL","I10": #LOCATION = "Q134" !CDS_LOCATION = "Q134" &SEC = "2" #&CDS_SEC = "2";
"D2":   PN = "3"  !CDS_PN = "3";
"G2":   PN = "5"  !CDS_PN = "5";
"S2":   PN = "4"  !CDS_PN = "4";
BODY = "Q_RES","I13": #LOCATION = "R4122" !CDS_LOCATION = "R4122" &SEC = "1" #&CDS_SEC = "1";
"A":   PN = "1"  !CDS_PN = "1";
"B":   PN = "2"  !CDS_PN = "2";
BODY = "Q_RES","I14": #LOCATION = "R4121" !CDS_LOCATION = "R4121" &SEC = "1" #&CDS_SEC = "1";
"A":   PN = "1"  !CDS_PN = "1";
"B":   PN = "2"  !CDS_PN = "2";
BODY = "Q_RES","I18": #LOCATION = "R4123" !CDS_LOCATION = "R4123" &SEC = "1" #&CDS_SEC = "1";
"A":   PN = "1"  !CDS_PN = "1";
"B":   PN = "2"  !CDS_PN = "2";
BODY = "Q_RES","I22": #LOCATION = "R4120" !CDS_LOCATION = "R4120" &SEC = "1" #&CDS_SEC = "1";
"A":   PN = "1"  !CDS_PN = "1";
"B":   PN = "2"  !CDS_PN = "2";
BODY = "Q_RES","I23": #LOCATION = "R4119" !CDS_LOCATION = "R4119" &SEC = "1" #&CDS_SEC = "1";
"A":   PN = "1"  !CDS_PN = "1";
"B":   PN = "2"  !CDS_PN = "2";
BODY = "MOSFET_NCH_DUAL","I25": #LOCATION = "Q132" !CDS_LOCATION = "Q132" &SEC = "1" #&CDS_SEC = "1";
"D1":   PN = "6"  !CDS_PN = "6";
"G1":   PN = "2"  !CDS_PN = "2";
"S1":   PN = "1"  !CDS_PN = "1";
BODY = "Q_RES","I27": #LOCATION = "R4126" !CDS_LOCATION = "R4126" &SEC = "1" #&CDS_SEC = "1";
"A":   PN = "1"  !CDS_PN = "1";
"B":   PN = "2"  !CDS_PN = "2";
BODY = "MOSFET_NCH_DUAL","I30": #LOCATION = "Q131" !CDS_LOCATION = "Q131" &SEC = "1" #&CDS_SEC = "1";
"D1":   PN = "6"  !CDS_PN = "6";
"G1":   PN = "2"  !CDS_PN = "2";
"S1":   PN = "1"  !CDS_PN = "1";
BODY = "Q_RES","I31": #LOCATION = "R4574" !CDS_LOCATION = "R4574" &SEC = "1" #&CDS_SEC = "1";
"A":   PN = "1"  !CDS_PN = "1";
"B":   PN = "2"  !CDS_PN = "2";
BODY = "MOSFET_NCH_DUAL","I32": #LOCATION = "Q132" !CDS_LOCATION = "Q132" &SEC = "2" #&CDS_SEC = "2";
"D2":   PN = "3"  !CDS_PN = "3";
"G2":   PN = "5"  !CDS_PN = "5";
"S2":   PN = "4"  !CDS_PN = "4";
BODY = "Q_RES","I33": #LOCATION = "R4573" !CDS_LOCATION = "R4573" &SEC = "1" #&CDS_SEC = "1";
"A":   PN = "1"  !CDS_PN = "1";
"B":   PN = "2"  !CDS_PN = "2";
BODY = "Q_RES","I35": #LOCATION = "R4127" !CDS_LOCATION = "R4127" &SEC = "1" #&CDS_SEC = "1";
"A":   PN = "1"  !CDS_PN = "1";
"B":   PN = "2"  !CDS_PN = "2";
BODY = "MOSFET_NCH_DUAL","I37": #LOCATION = "Q128" !CDS_LOCATION = "Q128" &SEC = "1" #&CDS_SEC = "1";
"D1":   PN = "6"  !CDS_PN = "6";
"G1":   PN = "2"  !CDS_PN = "2";
"S1":   PN = "1"  !CDS_PN = "1";
BODY = "Q_RES","I39": #LOCATION = "R4125" !CDS_LOCATION = "R4125" &SEC = "1" #&CDS_SEC = "1";
"A":   PN = "1"  !CDS_PN = "1";
"B":   PN = "2"  !CDS_PN = "2";
BODY = "MOSFET_NCH_DUAL","I40": #LOCATION = "Q131" !CDS_LOCATION = "Q131" &SEC = "2" #&CDS_SEC = "2";
"D2":   PN = "3"  !CDS_PN = "3";
"G2":   PN = "5"  !CDS_PN = "5";
"S2":   PN = "4"  !CDS_PN = "4";
BODY = "Q_RES","I41": #LOCATION = "R4572" !CDS_LOCATION = "R4572" &SEC = "1" #&CDS_SEC = "1";
"A":   PN = "1"  !CDS_PN = "1";
"B":   PN = "2"  !CDS_PN = "2";
BODY = "MOSFET_NCH_DUAL","I42": #LOCATION = "Q128" !CDS_LOCATION = "Q128" &SEC = "2" #&CDS_SEC = "2";
"D2":   PN = "3"  !CDS_PN = "3";
"G2":   PN = "5"  !CDS_PN = "5";
"S2":   PN = "4"  !CDS_PN = "4";
BODY = "Q_RES","I44": #LOCATION = "R4575" !CDS_LOCATION = "R4575" &SEC = "1" #&CDS_SEC = "1";
"A":   PN = "1"  !CDS_PN = "1";
"B":   PN = "2"  !CDS_PN = "2";
BODY = "Q_RES","I48": #LOCATION = "R4156" !CDS_LOCATION = "R4156" &SEC = "1" #&CDS_SEC = "1";
"A":   PN = "1"  !CDS_PN = "1";
"B":   PN = "2"  !CDS_PN = "2";
BODY = "Q_CAP","I50": #LOCATION = "C15" !CDS_LOCATION = "C15" &SEC = "1" #&CDS_SEC = "1";
"A":   PN = "1"  !CDS_PN = "1";
"B":   PN = "2"  !CDS_PN = "2";
BODY = "Q_RES","I54": #LOCATION = "R4559" !CDS_LOCATION = "R4559" &SEC = "1" #&CDS_SEC = "1";
"A":   PN = "1"  !CDS_PN = "1";
"B":   PN = "2"  !CDS_PN = "2";
BODY = "Q_RES","I55": #LOCATION = "R4562" !CDS_LOCATION = "R4562" &SEC = "1" #&CDS_SEC = "1";
"A":   PN = "1"  !CDS_PN = "1";
"B":   PN = "2"  !CDS_PN = "2";
BODY = "MOSFET_NCH_DUAL","I57": #LOCATION = "Q146" !CDS_LOCATION = "Q146" &SEC = "1" #&CDS_SEC = "1";
"D1":   PN = "6"  !CDS_PN = "6";
"G1":   PN = "2"  !CDS_PN = "2";
"S1":   PN = "1"  !CDS_PN = "1";
BODY = "Q_CAP","I61": #LOCATION = "C18" !CDS_LOCATION = "C18" &SEC = "1" #&CDS_SEC = "1";
"A":   PN = "1"  !CDS_PN = "1";
"B":   PN = "2"  !CDS_PN = "2";
BODY = "Q_RES","I62": #LOCATION = "R4560" !CDS_LOCATION = "R4560" &SEC = "1" #&CDS_SEC = "1";
"A":   PN = "1"  !CDS_PN = "1";
"B":   PN = "2"  !CDS_PN = "2";
BODY = "Q_CAP","I64": #LOCATION = "C13" !CDS_LOCATION = "C13" &SEC = "1" #&CDS_SEC = "1";
"A":   PN = "1"  !CDS_PN = "1";
"B":   PN = "2"  !CDS_PN = "2";
BODY = "Q_RES","I66": #LOCATION = "R4129" !CDS_LOCATION = "R4129" &SEC = "1" #&CDS_SEC = "1";
"A":   PN = "1"  !CDS_PN = "1";
"B":   PN = "2"  !CDS_PN = "2";
BODY = "Q_RES","I70": #LOCATION = "R4130" !CDS_LOCATION = "R4130" &SEC = "1" #&CDS_SEC = "1";
"A":   PN = "1"  !CDS_PN = "1";
"B":   PN = "2"  !CDS_PN = "2";
BODY = "Q_CAP","I73": #LOCATION = "C14" !CDS_LOCATION = "C14" &SEC = "1" #&CDS_SEC = "1";
"A":   PN = "1"  !CDS_PN = "1";
"B":   PN = "2"  !CDS_PN = "2";
BODY = "Q_CAP","I75": #LOCATION = "C12" !CDS_LOCATION = "C12" &SEC = "1" #&CDS_SEC = "1";
"A":   PN = "1"  !CDS_PN = "1";
"B":   PN = "2"  !CDS_PN = "2";
BODY = "Q_RES","I81": #LOCATION = "R4134" !CDS_LOCATION = "R4134" &SEC = "1" #&CDS_SEC = "1";
"A":   PN = "1"  !CDS_PN = "1";
"B":   PN = "2"  !CDS_PN = "2";
BODY = "Q_RES","I82": #LOCATION = "R4133" !CDS_LOCATION = "R4133" &SEC = "1" #&CDS_SEC = "1";
"A":   PN = "1"  !CDS_PN = "1";
"B":   PN = "2"  !CDS_PN = "2";
BODY = "MOSFET_NCH_DUAL","I86": #LOCATION = "Q129" !CDS_LOCATION = "Q129" &SEC = "1" #&CDS_SEC = "1";
"D1":   PN = "6"  !CDS_PN = "6";
"G1":   PN = "2"  !CDS_PN = "2";
"S1":   PN = "1"  !CDS_PN = "1";
BODY = "Q_RES","I88": #LOCATION = "R4138" !CDS_LOCATION = "R4138" &SEC = "1" #&CDS_SEC = "1";
"A":   PN = "1"  !CDS_PN = "1";
"B":   PN = "2"  !CDS_PN = "2";
BODY = "Q_RES","I91": #LOCATION = "R4576" !CDS_LOCATION = "R4576" &SEC = "1" #&CDS_SEC = "1";
"A":   PN = "1"  !CDS_PN = "1";
"B":   PN = "2"  !CDS_PN = "2";
BODY = "Q_RES","I92": #LOCATION = "R4136" !CDS_LOCATION = "R4136" &SEC = "1" #&CDS_SEC = "1";
"A":   PN = "1"  !CDS_PN = "1";
"B":   PN = "2"  !CDS_PN = "2";
BODY = "Q_RES","I93": #LOCATION = "R4135" !CDS_LOCATION = "R4135" &SEC = "1" #&CDS_SEC = "1";
"A":   PN = "1"  !CDS_PN = "1";
"B":   PN = "2"  !CDS_PN = "2";
BODY = "Q_RES","I96": #LOCATION = "R4132" !CDS_LOCATION = "R4132" &SEC = "1" #&CDS_SEC = "1";
"A":   PN = "1"  !CDS_PN = "1";
"B":   PN = "2"  !CDS_PN = "2";
BODY = "Q_RES","I97": #LOCATION = "R4131" !CDS_LOCATION = "R4131" &SEC = "1" #&CDS_SEC = "1";
"A":   PN = "1"  !CDS_PN = "1";
"B":   PN = "2"  !CDS_PN = "2";
BODY = "MOSFET_NCH_DUAL","I98": #LOCATION = "Q133" !CDS_LOCATION = "Q133" &SEC = "1" #&CDS_SEC = "1";
"D1":   PN = "6"  !CDS_PN = "6";
"G1":   PN = "2"  !CDS_PN = "2";
"S1":   PN = "1"  !CDS_PN = "1";
BODY = "Q_RES","I99": #LOCATION = "R4139" !CDS_LOCATION = "R4139" &SEC = "1" #&CDS_SEC = "1";
"A":   PN = "1"  !CDS_PN = "1";
"B":   PN = "2"  !CDS_PN = "2";
BODY = "MOSFET_NCH_DUAL","I102": #LOCATION = "Q130" !CDS_LOCATION = "Q130" &SEC = "1" #&CDS_SEC = "1";
"D1":   PN = "6"  !CDS_PN = "6";
"G1":   PN = "2"  !CDS_PN = "2";
"S1":   PN = "1"  !CDS_PN = "1";
BODY = "Q_RES","I103": #LOCATION = "R4578" !CDS_LOCATION = "R4578" &SEC = "1" #&CDS_SEC = "1";
"A":   PN = "1"  !CDS_PN = "1";
"B":   PN = "2"  !CDS_PN = "2";
BODY = "Q_RES","I104": #LOCATION = "R4128" !CDS_LOCATION = "R4128" &SEC = "1" #&CDS_SEC = "1";
"A":   PN = "1"  !CDS_PN = "1";
"B":   PN = "2"  !CDS_PN = "2";
BODY = "Q_RES","I107": #LOCATION = "R4137" !CDS_LOCATION = "R4137" &SEC = "1" #&CDS_SEC = "1";
"A":   PN = "1"  !CDS_PN = "1";
"B":   PN = "2"  !CDS_PN = "2";
BODY = "Q_RES","I109": #LOCATION = "R4577" !CDS_LOCATION = "R4577" &SEC = "1" #&CDS_SEC = "1";
"A":   PN = "1"  !CDS_PN = "1";
"B":   PN = "2"  !CDS_PN = "2";
BODY = "Q_RES","I110": #LOCATION = "R4561" !CDS_LOCATION = "R4561" &SEC = "1" #&CDS_SEC = "1";
"A":   PN = "1"  !CDS_PN = "1";
"B":   PN = "2"  !CDS_PN = "2";
BODY = "MOSFET_NCH_DUAL","I113": #LOCATION = "Q129" !CDS_LOCATION = "Q129" &SEC = "2" #&CDS_SEC = "2";
"D2":   PN = "3"  !CDS_PN = "3";
"G2":   PN = "5"  !CDS_PN = "5";
"S2":   PN = "4"  !CDS_PN = "4";
BODY = "Q_RES","I114": #LOCATION = "R4141" !CDS_LOCATION = "R4141" &SEC = "1" #&CDS_SEC = "1";
"A":   PN = "1"  !CDS_PN = "1";
"B":   PN = "2"  !CDS_PN = "2";
BODY = "Q_CAP","I118": #LOCATION = "C17" !CDS_LOCATION = "C17" &SEC = "1" #&CDS_SEC = "1";
"A":   PN = "1"  !CDS_PN = "1";
"B":   PN = "2"  !CDS_PN = "2";
BODY = "MOSFET_NCH_DUAL","I120": #LOCATION = "Q133" !CDS_LOCATION = "Q133" &SEC = "2" #&CDS_SEC = "2";
"D2":   PN = "3"  !CDS_PN = "3";
"G2":   PN = "5"  !CDS_PN = "5";
"S2":   PN = "4"  !CDS_PN = "4";
BODY = "Q_RES","I122": #LOCATION = "R4142" !CDS_LOCATION = "R4142" &SEC = "1" #&CDS_SEC = "1";
"A":   PN = "1"  !CDS_PN = "1";
"B":   PN = "2"  !CDS_PN = "2";
BODY = "MOSFET_NCH_DUAL","I123": #LOCATION = "Q130" !CDS_LOCATION = "Q130" &SEC = "2" #&CDS_SEC = "2";
"D2":   PN = "3"  !CDS_PN = "3";
"G2":   PN = "5"  !CDS_PN = "5";
"S2":   PN = "4"  !CDS_PN = "4";
BODY = "Q_CAP","I127": #LOCATION = "C19" !CDS_LOCATION = "C19" &SEC = "1" #&CDS_SEC = "1";
"A":   PN = "1"  !CDS_PN = "1";
"B":   PN = "2"  !CDS_PN = "2";
BODY = "Q_CAP","I130": #LOCATION = "C16" !CDS_LOCATION = "C16" &SEC = "1" #&CDS_SEC = "1";
"A":   PN = "1"  !CDS_PN = "1";
"B":   PN = "2"  !CDS_PN = "2";
BODY = "Q_RES","I131": #LOCATION = "R4140" !CDS_LOCATION = "R4140" &SEC = "1" #&CDS_SEC = "1";
"A":   PN = "1"  !CDS_PN = "1";
"B":   PN = "2"  !CDS_PN = "2";
BODY = "MOSFET_NCH_DUAL","I134": #LOCATION = "Q146" !CDS_LOCATION = "Q146" &SEC = "2" #&CDS_SEC = "2";
"D2":   PN = "3"  !CDS_PN = "3";
"G2":   PN = "5"  !CDS_PN = "5";
"S2":   PN = "4"  !CDS_PN = "4";
BODY = "Q_RES","I135": #LOCATION = "R4124" !CDS_LOCATION = "R4124" &SEC = "1" #&CDS_SEC = "1";
"A":   PN = "1"  !CDS_PN = "1";
"B":   PN = "2"  !CDS_PN = "2";
DRAWING = "@t6g_mb_lib.t6g(sch_1):page385";
BODY = "Q_RES","I25": #LOCATION = "R972" !CDS_LOCATION = "R972" &SEC = "1" #&CDS_SEC = "1";
"A":   PN = "1"  !CDS_PN = "1";
"B":   PN = "2"  !CDS_PN = "2";
BODY = "Q_RES","I27": #LOCATION = "R979" !CDS_LOCATION = "R979" &SEC = "1" #&CDS_SEC = "1";
"A":   PN = "1"  !CDS_PN = "1";
"B":   PN = "2"  !CDS_PN = "2";
BODY = "Q_RES","I28": #LOCATION = "R980" !CDS_LOCATION = "R980" &SEC = "1" #&CDS_SEC = "1";
"A":   PN = "1"  !CDS_PN = "1";
"B":   PN = "2"  !CDS_PN = "2";
BODY = "Q_RES","I29": #LOCATION = "R982" !CDS_LOCATION = "R982" &SEC = "1" #&CDS_SEC = "1";
"A":   PN = "1"  !CDS_PN = "1";
"B":   PN = "2"  !CDS_PN = "2";
BODY = "Q_RES","I30": #LOCATION = "R978" !CDS_LOCATION = "R978" &SEC = "1" #&CDS_SEC = "1";
"A":   PN = "1"  !CDS_PN = "1";
"B":   PN = "2"  !CDS_PN = "2";
BODY = "Q_RES","I31": #LOCATION = "R981" !CDS_LOCATION = "R981" &SEC = "1" #&CDS_SEC = "1";
"A":   PN = "1"  !CDS_PN = "1";
"B":   PN = "2"  !CDS_PN = "2";
BODY = "Q_RES","I37": #LOCATION = "R623" !CDS_LOCATION = "R623" &SEC = "1" #&CDS_SEC = "1";
"A":   PN = "1"  !CDS_PN = "1";
"B":   PN = "2"  !CDS_PN = "2";
BODY = "Q_RES","I38": #LOCATION = "R624" !CDS_LOCATION = "R624" &SEC = "1" #&CDS_SEC = "1";
"A":   PN = "1"  !CDS_PN = "1";
"B":   PN = "2"  !CDS_PN = "2";
BODY = "Q_RES","I39": #LOCATION = "R595" !CDS_LOCATION = "R595" #SEC = "1" !CDS_SEC = "1";
"A":   PN = "1"  !CDS_PN = "1";
"B":   PN = "2"  !CDS_PN = "2";
BODY = "Q_RES","I40": #LOCATION = "R596" !CDS_LOCATION = "R596" #SEC = "1" !CDS_SEC = "1";
"A":   PN = "1"  !CDS_PN = "1";
"B":   PN = "2"  !CDS_PN = "2";
BODY = "Q_RES","I41": #LOCATION = "R667" !CDS_LOCATION = "R667" &SEC = "1" #&CDS_SEC = "1";
"A":   PN = "1"  !CDS_PN = "1";
"B":   PN = "2"  !CDS_PN = "2";
BODY = "Q_RES","I42": #LOCATION = "R666" !CDS_LOCATION = "R666" &SEC = "1" #&CDS_SEC = "1";
"A":   PN = "1"  !CDS_PN = "1";
"B":   PN = "2"  !CDS_PN = "2";
BODY = "Q_RES","I49": #LOCATION = "R977" !CDS_LOCATION = "R977" &SEC = "1" #&CDS_SEC = "1";
"A":   PN = "1"  !CDS_PN = "1";
"B":   PN = "2"  !CDS_PN = "2";
BODY = "Q_RES","I50": #LOCATION = "R976" !CDS_LOCATION = "R976" &SEC = "1" #&CDS_SEC = "1";
"A":   PN = "1"  !CDS_PN = "1";
"B":   PN = "2"  !CDS_PN = "2";
BODY = "PT5161LRS","I53": #LOCATION = "U6010" !CDS_LOCATION = "U6010" &SEC = "3" #&CDS_SEC = "3";
"CLKREQ_N":   PN = "G35"  !CDS_PN = "G35";
"EE_CLK":   PN = "FF5"  !CDS_PN = "FF5";
"EE_DAT":   PN = "FJ3"  !CDS_PN = "FJ3";
"GPIO0":   PN = "FJ6"  !CDS_PN = "FJ6";
"GPIO1":   PN = "FJ23"  !CDS_PN = "FJ23";
"GPIO2":   PN = "FJ25"  !CDS_PN = "FJ25";
"GPIO3":   PN = "FJ28"  !CDS_PN = "FJ28";
"INT_N":   PN = "FJ31"  !CDS_PN = "FJ31";
"JTAG_TCK":   PN = "B3"  !CDS_PN = "B3";
"JTAG_TDI":   PN = "B6"  !CDS_PN = "B6";
"JTAG_TDO":   PN = "B9"  !CDS_PN = "B9";
"JTAG_TEST_MODE":   PN = "FF8"  !CDS_PN = "FF8";
"JTAG_TMS":   PN = "B12"  !CDS_PN = "B12";
"JTAG_TRST_N":   PN = "E8"  !CDS_PN = "E8";
"MODE":   PN = "FJ9"  !CDS_PN = "FJ9";
"PERST_N":   PN = "F2"  !CDS_PN = "F2";
"REFCLK_OUTN":   PN = "E18"  !CDS_PN = "E18";
"REFCLK_OUTP":   PN = "B16"  !CDS_PN = "B16";
"REFCLKN":   PN = "FF18"  !CDS_PN = "FF18";
"REFCLKP":   PN = "FJ16"  !CDS_PN = "FJ16";
"RESET_N":   PN = "FF11"  !CDS_PN = "FF11";
"RXDET_BYP":   PN = "E11"  !CDS_PN = "E11";
"SCAN_MODE":   PN = "FF33"  !CDS_PN = "FF33";
"SMB_ADDR1":   PN = "F34"  !CDS_PN = "F34";
"SMB_ADDR2":   PN = "B23"  !CDS_PN = "B23";
"SMB_ADDR3":   PN = "B25"  !CDS_PN = "B25";
"SMBCLK":   PN = "B31"  !CDS_PN = "B31";
"SMBDAT":   PN = "B28"  !CDS_PN = "B28";
"T_SENSE":   PN = "E30"  !CDS_PN = "E30";
"TEST0":   PN = "FF24"  !CDS_PN = "FF24";
"TEST1":   PN = "FF27"  !CDS_PN = "FF27";
"TEST2":   PN = "FF30"  !CDS_PN = "FF30";
BODY = "Q_RES","I57": #LOCATION = "R984" !CDS_LOCATION = "R984" &SEC = "1" #&CDS_SEC = "1";
"A":   PN = "1"  !CDS_PN = "1";
"B":   PN = "2"  !CDS_PN = "2";
BODY = "Q_RES","I58": #LOCATION = "R995" !CDS_LOCATION = "R995" &SEC = "1" #&CDS_SEC = "1";
"A":   PN = "1"  !CDS_PN = "1";
"B":   PN = "2"  !CDS_PN = "2";
BODY = "Q_RES","I60": #LOCATION = "R997" !CDS_LOCATION = "R997" &SEC = "1" #&CDS_SEC = "1";
"A":   PN = "1"  !CDS_PN = "1";
"B":   PN = "2"  !CDS_PN = "2";
BODY = "Q_RES","I61": #LOCATION = "R983" !CDS_LOCATION = "R983" &SEC = "1" #&CDS_SEC = "1";
"A":   PN = "1"  !CDS_PN = "1";
"B":   PN = "2"  !CDS_PN = "2";
BODY = "Q_RES","I62": #LOCATION = "R985" !CDS_LOCATION = "R985" &SEC = "1" #&CDS_SEC = "1";
"A":   PN = "1"  !CDS_PN = "1";
"B":   PN = "2"  !CDS_PN = "2";
BODY = "Q_RES","I63": #LOCATION = "R975" !CDS_LOCATION = "R975" &SEC = "1" #&CDS_SEC = "1";
"A":   PN = "1"  !CDS_PN = "1";
"B":   PN = "2"  !CDS_PN = "2";
BODY = "Q_RES","I71": #LOCATION = "R1001" !CDS_LOCATION = "R1001" &SEC = "1" #&CDS_SEC = "1";
"A":   PN = "1"  !CDS_PN = "1";
"B":   PN = "2"  !CDS_PN = "2";
BODY = "Q_RES","I72": #LOCATION = "R998" !CDS_LOCATION = "R998" &SEC = "1" #&CDS_SEC = "1";
"A":   PN = "1"  !CDS_PN = "1";
"B":   PN = "2"  !CDS_PN = "2";
BODY = "Q_RES","I76": #LOCATION = "R953" !CDS_LOCATION = "R953" #SEC = "1" !CDS_SEC = "1";
"A":   PN = "1"  !CDS_PN = "1";
"B":   PN = "2"  !CDS_PN = "2";
BODY = "Q_RES","I77": #LOCATION = "R963" !CDS_LOCATION = "R963" &SEC = "1" #&CDS_SEC = "1";
"A":   PN = "1"  !CDS_PN = "1";
"B":   PN = "2"  !CDS_PN = "2";
BODY = "Q_RES","I86": #LOCATION = "R965" !CDS_LOCATION = "R965" &SEC = "1" #&CDS_SEC = "1";
"A":   PN = "1"  !CDS_PN = "1";
"B":   PN = "2"  !CDS_PN = "2";
BODY = "Q_RES","I87": #LOCATION = "R967" !CDS_LOCATION = "R967" &SEC = "1" #&CDS_SEC = "1";
"A":   PN = "1"  !CDS_PN = "1";
"B":   PN = "2"  !CDS_PN = "2";
BODY = "Q_RES","I88": #LOCATION = "R964" !CDS_LOCATION = "R964" &SEC = "1" #&CDS_SEC = "1";
"A":   PN = "1"  !CDS_PN = "1";
"B":   PN = "2"  !CDS_PN = "2";
BODY = "Q_RES","I89": #LOCATION = "R966" !CDS_LOCATION = "R966" &SEC = "1" #&CDS_SEC = "1";
"A":   PN = "1"  !CDS_PN = "1";
"B":   PN = "2"  !CDS_PN = "2";
BODY = "Q_RES","I90": #LOCATION = "R969" !CDS_LOCATION = "R969" &SEC = "1" #&CDS_SEC = "1";
"A":   PN = "1"  !CDS_PN = "1";
"B":   PN = "2"  !CDS_PN = "2";
BODY = "Q_RES","I91": #LOCATION = "R968" !CDS_LOCATION = "R968" &SEC = "1" #&CDS_SEC = "1";
"A":   PN = "1"  !CDS_PN = "1";
"B":   PN = "2"  !CDS_PN = "2";
BODY = "Q_RES","I96": #LOCATION = "R971" !CDS_LOCATION = "R971" &SEC = "1" #&CDS_SEC = "1";
"A":   PN = "1"  !CDS_PN = "1";
"B":   PN = "2"  !CDS_PN = "2";
BODY = "Q_RES","I97": #LOCATION = "R970" !CDS_LOCATION = "R970" &SEC = "1" #&CDS_SEC = "1";
"A":   PN = "1"  !CDS_PN = "1";
"B":   PN = "2"  !CDS_PN = "2";
BODY = "Q_RES","I98": #LOCATION = "R974" !CDS_LOCATION = "R974" &SEC = "1" #&CDS_SEC = "1";
"A":   PN = "1"  !CDS_PN = "1";
"B":   PN = "2"  !CDS_PN = "2";
BODY = "Q_RES","I111": #LOCATION = "R1364" !CDS_LOCATION = "R1364" &SEC = "1" #&CDS_SEC = "1";
"A":   PN = "1"  !CDS_PN = "1";
"B":   PN = "2"  !CDS_PN = "2";
BODY = "Q_RES","I114": #LOCATION = "R1370" !CDS_LOCATION = "R1370" &SEC = "1" #&CDS_SEC = "1";
"A":   PN = "1"  !CDS_PN = "1";
"B":   PN = "2"  !CDS_PN = "2";
BODY = "Q_RES","I116": #LOCATION = "R1369" !CDS_LOCATION = "R1369" &SEC = "1" #&CDS_SEC = "1";
"A":   PN = "1"  !CDS_PN = "1";
"B":   PN = "2"  !CDS_PN = "2";
BODY = "Q_RES","I119": #LOCATION = "R1368" !CDS_LOCATION = "R1368" &SEC = "1" #&CDS_SEC = "1";
"A":   PN = "1"  !CDS_PN = "1";
"B":   PN = "2"  !CDS_PN = "2";
BODY = "Q_RES","I121": #LOCATION = "R973" !CDS_LOCATION = "R973" &SEC = "1" #&CDS_SEC = "1";
"A":   PN = "1"  !CDS_PN = "1";
"B":   PN = "2"  !CDS_PN = "2";
BODY = "Q_RES","I123": #LOCATION = "R1365" !CDS_LOCATION = "R1365" &SEC = "1" #&CDS_SEC = "1";
"A":   PN = "1"  !CDS_PN = "1";
"B":   PN = "2"  !CDS_PN = "2";
BODY = "Q_RES","I143": #LOCATION = "R1446" !CDS_LOCATION = "R1446" &SEC = "1" #&CDS_SEC = "1";
"A":   PN = "1"  !CDS_PN = "1";
"B":   PN = "2"  !CDS_PN = "2";
BODY = "Q_RES","I145": #LOCATION = "R1445" !CDS_LOCATION = "R1445" &SEC = "1" #&CDS_SEC = "1";
"A":   PN = "1"  !CDS_PN = "1";
"B":   PN = "2"  !CDS_PN = "2";
BODY = "Q_RES","I146": #LOCATION = "R1439" !CDS_LOCATION = "R1439" &SEC = "1" #&CDS_SEC = "1";
"A":   PN = "1"  !CDS_PN = "1";
"B":   PN = "2"  !CDS_PN = "2";
BODY = "Q_RES","I147": #LOCATION = "R1438" !CDS_LOCATION = "R1438" &SEC = "1" #&CDS_SEC = "1";
"A":   PN = "1"  !CDS_PN = "1";
"B":   PN = "2"  !CDS_PN = "2";
DRAWING = "@t6g_mb_lib.t6g(sch_1):page386";
BODY = "PT5161LRS","I3": #LOCATION = "U6010" !CDS_LOCATION = "U6010" &SEC = "4" #&CDS_SEC = "4";
"PWR_1A_1":   PN = "BV20"  !CDS_PN = "BV20";
"PWR_1A_2":   PN = "CE17"  !CDS_PN = "CE17";
"PWR_1A_3":   PN = "CE20"  !CDS_PN = "CE20";
"PWR_1A_4":   PN = "CM17"  !CDS_PN = "CM17";
"PWR_1A_5":   PN = "CM20"  !CDS_PN = "CM20";
"PWR_1D":   PN = "BV17"  !CDS_PN = "BV17";
"PWR_2A_1":   PN = "AC17"  !CDS_PN = "AC17";
"PWR_2A_2":   PN = "AC20"  !CDS_PN = "AC20";
"PWR_2A_3":   PN = "AK17"  !CDS_PN = "AK17";
"PWR_2A_4":   PN = "AK20"  !CDS_PN = "AK20";
"PWR_2A_5":   PN = "AU17"  !CDS_PN = "AU17";
"PWR_2A_6":   PN = "AU20"  !CDS_PN = "AU20";
"PWR_2A_7":   PN = "BD17"  !CDS_PN = "BD17";
"PWR_2A_8":   PN = "BD20"  !CDS_PN = "BD20";
"PWR_2A_9":   PN = "DF17"  !CDS_PN = "DF17";
"PWR_2A_10":   PN = "DF20"  !CDS_PN = "DF20";
"PWR_2A_11":   PN = "DN17"  !CDS_PN = "DN17";
"PWR_2A_12":   PN = "DN20"  !CDS_PN = "DN20";
"PWR_2A_13":   PN = "DY17"  !CDS_PN = "DY17";
"PWR_2A_14":   PN = "DY20"  !CDS_PN = "DY20";
"PWR_2A_15":   PN = "EG17"  !CDS_PN = "EG17";
"PWR_2A_16":   PN = "EG20"  !CDS_PN = "EG20";
"PWR_2A_17":   PN = "EP17"  !CDS_PN = "EP17";
"PWR_2A_18":   PN = "EP20"  !CDS_PN = "EP20";
"PWR_2A_19":   PN = "T17"  !CDS_PN = "T17";
"PWR_2A_20":   PN = "T20"  !CDS_PN = "T20";
"PWR_2D_1":   PN = "BL17"  !CDS_PN = "BL17";
"PWR_2D_2":   PN = "BL20"  !CDS_PN = "BL20";
"PWR_2D_3":   PN = "CW17"  !CDS_PN = "CW17";
"PWR_2D_4":   PN = "CW20"  !CDS_PN = "CW20";
"VQPS":   PN = "G1"  !CDS_PN = "G1";
BODY = "Q_RES","I13": #LOCATION = "R6821" !CDS_LOCATION = "R6821" &SEC = "1" #&CDS_SEC = "1";
"A":   PN = "1"  !CDS_PN = "1";
"B":   PN = "2"  !CDS_PN = "2";
BODY = "Q_RES","I15": #LOCATION = "R6820" !CDS_LOCATION = "R6820" &SEC = "1" #&CDS_SEC = "1";
"A":   PN = "1"  !CDS_PN = "1";
"B":   PN = "2"  !CDS_PN = "2";
BODY = "PT5161LRS","I17": #LOCATION = "U6010" !CDS_LOCATION = "U6010" &SEC = "5" #&CDS_SEC = "5";
"GND1":   PN = "AC13"  !CDS_PN = "AC13";
"GND2":   PN = "AC22"  !CDS_PN = "AC22";
"GND3":   PN = "AC32"  !CDS_PN = "AC32";
"GND4":   PN = "AC4"  !CDS_PN = "AC4";
"GND5":   PN = "AD2"  !CDS_PN = "AD2";
"GND6":   PN = "AD34"  !CDS_PN = "AD34";
"GND7":   PN = "AE1"  !CDS_PN = "AE1";
"GND8":   PN = "AE35"  !CDS_PN = "AE35";
"GND9":   PN = "AK13"  !CDS_PN = "AK13";
"GND10":   PN = "AK22"  !CDS_PN = "AK22";
"GND11":   PN = "AK32"  !CDS_PN = "AK32";
"GND12":   PN = "AK4"  !CDS_PN = "AK4";
"GND13":   PN = "AL2"  !CDS_PN = "AL2";
"GND14":   PN = "AL34"  !CDS_PN = "AL34";
"GND15":   PN = "AM1"  !CDS_PN = "AM1";
"GND16":   PN = "AM35"  !CDS_PN = "AM35";
"GND17":   PN = "AU13"  !CDS_PN = "AU13";
"GND18":   PN = "AU22"  !CDS_PN = "AU22";
"GND19":   PN = "AU32"  !CDS_PN = "AU32";
"GND20":   PN = "AU4"  !CDS_PN = "AU4";
"GND21":   PN = "AV2"  !CDS_PN = "AV2";
"GND22":   PN = "AV34"  !CDS_PN = "AV34";
"GND23":   PN = "AW1"  !CDS_PN = "AW1";
"GND24":   PN = "AW35"  !CDS_PN = "AW35";
"GND25":   PN = "B19"  !CDS_PN = "B19";
"GND26":   PN = "BD13"  !CDS_PN = "BD13";
"GND27":   PN = "BD22"  !CDS_PN = "BD22";
"GND28":   PN = "BD32"  !CDS_PN = "BD32";
"GND29":   PN = "BD4"  !CDS_PN = "BD4";
"GND30":   PN = "BE2"  !CDS_PN = "BE2";
"GND31":   PN = "BE34"  !CDS_PN = "BE34";
"GND32":   PN = "BF1"  !CDS_PN = "BF1";
"GND33":   PN = "BF35"  !CDS_PN = "BF35";
"GND34":   PN = "BL13"  !CDS_PN = "BL13";
"GND35":   PN = "BL22"  !CDS_PN = "BL22";
"GND36":   PN = "BL32"  !CDS_PN = "BL32";
"GND37":   PN = "BL4"  !CDS_PN = "BL4";
"GND38":   PN = "BM2"  !CDS_PN = "BM2";
"GND39":   PN = "BM34"  !CDS_PN = "BM34";
"GND40":   PN = "BN1"  !CDS_PN = "BN1";
"GND41":   PN = "BN35"  !CDS_PN = "BN35";
"GND42":   PN = "BV13"  !CDS_PN = "BV13";
"GND43":   PN = "BV22"  !CDS_PN = "BV22";
"GND44":   PN = "BV32"  !CDS_PN = "BV32";
"GND45":   PN = "BV4"  !CDS_PN = "BV4";
"GND46":   PN = "BW2"  !CDS_PN = "BW2";
"GND47":   PN = "BW34"  !CDS_PN = "BW34";
"GND48":   PN = "BY1"  !CDS_PN = "BY1";
"GND49":   PN = "BY35"  !CDS_PN = "BY35";
"GND50":   PN = "CE13"  !CDS_PN = "CE13";
"GND51":   PN = "CE22"  !CDS_PN = "CE22";
"GND52":   PN = "CE32"  !CDS_PN = "CE32";
"GND53":   PN = "CE4"  !CDS_PN = "CE4";
"GND54":   PN = "CF2"  !CDS_PN = "CF2";
"GND55":   PN = "CF34"  !CDS_PN = "CF34";
"GND56":   PN = "CG1"  !CDS_PN = "CG1";
"GND57":   PN = "CG35"  !CDS_PN = "CG35";
"GND58":   PN = "CM13"  !CDS_PN = "CM13";
"GND59":   PN = "CM22"  !CDS_PN = "CM22";
"GND60":   PN = "CM32"  !CDS_PN = "CM32";
"GND61":   PN = "CM4"  !CDS_PN = "CM4";
"GND62":   PN = "CN2"  !CDS_PN = "CN2";
"GND63":   PN = "CN34"  !CDS_PN = "CN34";
"GND64":   PN = "CP1"  !CDS_PN = "CP1";
"GND65":   PN = "CP35"  !CDS_PN = "CP35";
"GND66":   PN = "CW13"  !CDS_PN = "CW13";
"GND67":   PN = "CW22"  !CDS_PN = "CW22";
"GND68":   PN = "CW32"  !CDS_PN = "CW32";
"GND69":   PN = "CW4"  !CDS_PN = "CW4";
"GND70":   PN = "CY2"  !CDS_PN = "CY2";
"GND71":   PN = "CY34"  !CDS_PN = "CY34";
"GND72":   PN = "DA1"  !CDS_PN = "DA1";
"GND73":   PN = "DA35"  !CDS_PN = "DA35";
"GND74":   PN = "DF13"  !CDS_PN = "DF13";
"GND75":   PN = "DF22"  !CDS_PN = "DF22";
"GND76":   PN = "DF32"  !CDS_PN = "DF32";
"GND77":   PN = "DF4"  !CDS_PN = "DF4";
"GND78":   PN = "DG2"  !CDS_PN = "DG2";
"GND79":   PN = "DG34"  !CDS_PN = "DG34";
"GND80":   PN = "DH1"  !CDS_PN = "DH1";
"GND81":   PN = "DH35"  !CDS_PN = "DH35";
"GND82":   PN = "DN13"  !CDS_PN = "DN13";
"GND83":   PN = "DN22"  !CDS_PN = "DN22";
"GND84":   PN = "DN32"  !CDS_PN = "DN32";
"GND85":   PN = "DN4"  !CDS_PN = "DN4";
"GND86":   PN = "DP2"  !CDS_PN = "DP2";
"GND87":   PN = "DP34"  !CDS_PN = "DP34";
"GND88":   PN = "DR1"  !CDS_PN = "DR1";
"GND89":   PN = "DR35"  !CDS_PN = "DR35";
"GND90":   PN = "DY13"  !CDS_PN = "DY13";
"GND91":   PN = "DY22"  !CDS_PN = "DY22";
"GND92":   PN = "DY32"  !CDS_PN = "DY32";
"GND93":   PN = "DY4"  !CDS_PN = "DY4";
"GND94":   PN = "E14"  !CDS_PN = "E14";
"GND95":   PN = "E27"  !CDS_PN = "E27";
"GND96":   PN = "E33"  !CDS_PN = "E33";
"GND97":   PN = "EA2"  !CDS_PN = "EA2";
"GND98":   PN = "EA34"  !CDS_PN = "EA34";
"GND99":   PN = "EB1"  !CDS_PN = "EB1";
"GND100":   PN = "EB35"  !CDS_PN = "EB35";
"GND101":   PN = "EG13"  !CDS_PN = "EG13";
"GND102":   PN = "EG22"  !CDS_PN = "EG22";
"GND103":   PN = "EG32"  !CDS_PN = "EG32";
"GND104":   PN = "EG4"  !CDS_PN = "EG4";
"GND105":   PN = "EH2"  !CDS_PN = "EH2";
"GND106":   PN = "EH34"  !CDS_PN = "EH34";
"GND107":   PN = "EJ1"  !CDS_PN = "EJ1";
"GND108":   PN = "EJ35"  !CDS_PN = "EJ35";
"GND109":   PN = "EP13"  !CDS_PN = "EP13";
"GND110":   PN = "EP22"  !CDS_PN = "EP22";
"GND111":   PN = "EP32"  !CDS_PN = "EP32";
"GND112":   PN = "EP4"  !CDS_PN = "EP4";
"GND113":   PN = "ER2"  !CDS_PN = "ER2";
"GND114":   PN = "ER34"  !CDS_PN = "ER34";
"GND115":   PN = "ET1"  !CDS_PN = "ET1";
"GND116":   PN = "ET35"  !CDS_PN = "ET35";
"GND117":   PN = "FA15"  !CDS_PN = "FA15";
"GND118":   PN = "FA32"  !CDS_PN = "FA32";
"GND119":   PN = "FB2"  !CDS_PN = "FB2";
"GND120":   PN = "FB34"  !CDS_PN = "FB34";
"GND121":   PN = "FC19"  !CDS_PN = "FC19";
"GND122":   PN = "FC23"  !CDS_PN = "FC23";
"GND123":   PN = "FC25"  !CDS_PN = "FC25";
"GND124":   PN = "FC28"  !CDS_PN = "FC28";
"GND125":   PN = "FC3"  !CDS_PN = "FC3";
"GND126":   PN = "FC6"  !CDS_PN = "FC6";
"GND127":   PN = "FC9"  !CDS_PN = "FC9";
"GND128":   PN = "FD1"  !CDS_PN = "FD1";
"GND129":   PN = "FD35"  !CDS_PN = "FD35";
"GND130":   PN = "FF14"  !CDS_PN = "FF14";
"GND131":   PN = "FF21"  !CDS_PN = "FF21";
"GND132":   PN = "FJ12"  !CDS_PN = "FJ12";
"GND133":   PN = "FJ19"  !CDS_PN = "FJ19";
"GND134":   PN = "H12"  !CDS_PN = "H12";
"GND135":   PN = "H16"  !CDS_PN = "H16";
"GND136":   PN = "H19"  !CDS_PN = "H19";
"GND137":   PN = "H31"  !CDS_PN = "H31";
"GND138":   PN = "J22"  !CDS_PN = "J22";
"GND139":   PN = "J4"  !CDS_PN = "J4";
"GND140":   PN = "K2"  !CDS_PN = "K2";
"GND141":   PN = "K34"  !CDS_PN = "K34";
"GND142":   PN = "L1"  !CDS_PN = "L1";
"GND143":   PN = "L35"  !CDS_PN = "L35";
"GND144":   PN = "T13"  !CDS_PN = "T13";
"GND145":   PN = "T22"  !CDS_PN = "T22";
"GND146":   PN = "T32"  !CDS_PN = "T32";
"GND147":   PN = "T4"  !CDS_PN = "T4";
"GND148":   PN = "U2"  !CDS_PN = "U2";
"GND149":   PN = "U34"  !CDS_PN = "U34";
"GND150":   PN = "V1"  !CDS_PN = "V1";
"GND151":   PN = "V35"  !CDS_PN = "V35";
"NCF_GND1":   PN = "A1"  !CDS_PN = "A1";
"NCF_GND2":   PN = "A35"  !CDS_PN = "A35";
"NCF_GND3":   PN = "C2"  !CDS_PN = "C2";
"NCF_GND4":   PN = "C34"  !CDS_PN = "C34";
"NCF_GND5":   PN = "D1"  !CDS_PN = "D1";
"NCF_GND6":   PN = "D35"  !CDS_PN = "D35";
"NCF_GND7":   PN = "FE2"  !CDS_PN = "FE2";
"NCF_GND8":   PN = "FE34"  !CDS_PN = "FE34";
"NCF_GND9":   PN = "FG1"  !CDS_PN = "FG1";
"NCF_GND10":   PN = "FG35"  !CDS_PN = "FG35";
"NCF_GND11":   PN = "FH2"  !CDS_PN = "FH2";
"NCF_GND12":   PN = "FH34"  !CDS_PN = "FH34";
BODY = "Q_RES","I18": #LOCATION = "R6809" !CDS_LOCATION = "R6809" &SEC = "1" #&CDS_SEC = "1";
"A":   PN = "1"  !CDS_PN = "1";
"B":   PN = "2"  !CDS_PN = "2";
BODY = "Q_RES","I19": #LOCATION = "R6808" !CDS_LOCATION = "R6808" &SEC = "1" #&CDS_SEC = "1";
"A":   PN = "1"  !CDS_PN = "1";
"B":   PN = "2"  !CDS_PN = "2";
DRAWING = "@t6g_mb_lib.t6g(sch_1):page388";
BODY = "Q_RES","I4": #LOCATION = "R952" !CDS_LOCATION = "R952" #SEC = "1" !CDS_SEC = "1";
"A":   PN = "1"  !CDS_PN = "1";
"B":   PN = "2"  !CDS_PN = "2";
BODY = "Q_RES","I5": #LOCATION = "R951" !CDS_LOCATION = "R951" #SEC = "1" !CDS_SEC = "1";
"A":   PN = "1"  !CDS_PN = "1";
"B":   PN = "2"  !CDS_PN = "2";
BODY = "Q_CAP","I8": #LOCATION = "C513" !CDS_LOCATION = "C513" &SEC = "1" #&CDS_SEC = "1";
"A":   PN = "1"  !CDS_PN = "1";
"B":   PN = "2"  !CDS_PN = "2";
BODY = "Q_CAP","I9": #LOCATION = "C516" !CDS_LOCATION = "C516" &SEC = "1" #&CDS_SEC = "1";
"A":   PN = "1"  !CDS_PN = "1";
"B":   PN = "2"  !CDS_PN = "2";
BODY = "Q_RES","I10": #LOCATION = "R961" !CDS_LOCATION = "R961" &SEC = "1" #&CDS_SEC = "1";
"A":   PN = "1"  !CDS_PN = "1";
"B":   PN = "2"  !CDS_PN = "2";
BODY = "Q_RES","I11": #LOCATION = "R962" !CDS_LOCATION = "R962" &SEC = "1" #&CDS_SEC = "1";
"A":   PN = "1"  !CDS_PN = "1";
"B":   PN = "2"  !CDS_PN = "2";
BODY = "Q_INDUCTOR","I12": #LOCATION = "L11" !CDS_LOCATION = "L11" &SEC = "1" #&CDS_SEC = "1";
"1":   PN = "1"  !CDS_PN = "1";
"2":   PN = "2"  !CDS_PN = "2";
BODY = "Q_CAP","I13": #LOCATION = "C503" !CDS_LOCATION = "C503" &SEC = "1" #&CDS_SEC = "1";
"A":   PN = "1"  !CDS_PN = "1";
"B":   PN = "2"  !CDS_PN = "2";
BODY = "Q_CAP","I14": #LOCATION = "C505" !CDS_LOCATION = "C505" &SEC = "1" #&CDS_SEC = "1";
"A":   PN = "1"  !CDS_PN = "1";
"B":   PN = "2"  !CDS_PN = "2";
BODY = "Q_CAP","I16": #LOCATION = "C502" !CDS_LOCATION = "C502" &SEC = "1" #&CDS_SEC = "1";
"A":   PN = "1"  !CDS_PN = "1";
"B":   PN = "2"  !CDS_PN = "2";
BODY = "Q_CAP","I17": #LOCATION = "C507" !CDS_LOCATION = "C507" &SEC = "1" #&CDS_SEC = "1";
"A":   PN = "1"  !CDS_PN = "1";
"B":   PN = "2"  !CDS_PN = "2";
BODY = "Q_CAP","I18": #LOCATION = "C510" !CDS_LOCATION = "C510" &SEC = "1" #&CDS_SEC = "1";
"A":   PN = "1"  !CDS_PN = "1";
"B":   PN = "2"  !CDS_PN = "2";
BODY = "Q_CAP","I19": #LOCATION = "C512" !CDS_LOCATION = "C512" &SEC = "1" #&CDS_SEC = "1";
"A":   PN = "1"  !CDS_PN = "1";
"B":   PN = "2"  !CDS_PN = "2";
BODY = "Q_CAP","I22": #LOCATION = "C514" !CDS_LOCATION = "C514" &SEC = "1" #&CDS_SEC = "1";
"A":   PN = "1"  !CDS_PN = "1";
"B":   PN = "2"  !CDS_PN = "2";
BODY = "Q_CAP","I23": #LOCATION = "C515" !CDS_LOCATION = "C515" &SEC = "1" #&CDS_SEC = "1";
"A":   PN = "1"  !CDS_PN = "1";
"B":   PN = "2"  !CDS_PN = "2";
BODY = "Q_CAP","I24": #LOCATION = "C504" !CDS_LOCATION = "C504" &SEC = "1" #&CDS_SEC = "1";
"A":   PN = "1"  !CDS_PN = "1";
"B":   PN = "2"  !CDS_PN = "2";
BODY = "Q_CAP","I25": #LOCATION = "C506" !CDS_LOCATION = "C506" &SEC = "1" #&CDS_SEC = "1";
"A":   PN = "1"  !CDS_PN = "1";
"B":   PN = "2"  !CDS_PN = "2";
BODY = "Q_CAP","I26": #LOCATION = "C511" !CDS_LOCATION = "C511" &SEC = "1" #&CDS_SEC = "1";
"A":   PN = "1"  !CDS_PN = "1";
"B":   PN = "2"  !CDS_PN = "2";
BODY = "Q_CAP","I27": #LOCATION = "C517" !CDS_LOCATION = "C517" &SEC = "1" #&CDS_SEC = "1";
"A":   PN = "1"  !CDS_PN = "1";
"B":   PN = "2"  !CDS_PN = "2";
BODY = "Q_CAP","I28": #LOCATION = "C519" !CDS_LOCATION = "C519" &SEC = "1" #&CDS_SEC = "1";
"A":   PN = "1"  !CDS_PN = "1";
"B":   PN = "2"  !CDS_PN = "2";
BODY = "Q_CAP","I29": #LOCATION = "C520" !CDS_LOCATION = "C520" &SEC = "1" #&CDS_SEC = "1";
"A":   PN = "1"  !CDS_PN = "1";
"B":   PN = "2"  !CDS_PN = "2";
BODY = "Q_INDUCTOR","I30": #LOCATION = "L12" !CDS_LOCATION = "L12" &SEC = "1" #&CDS_SEC = "1";
"1":   PN = "1"  !CDS_PN = "1";
"2":   PN = "2"  !CDS_PN = "2";
BODY = "Q_CAP","I32": #LOCATION = "C538" !CDS_LOCATION = "C538" &SEC = "1" #&CDS_SEC = "1";
"A":   PN = "1"  !CDS_PN = "1";
"B":   PN = "2"  !CDS_PN = "2";
BODY = "Q_CAP","I36": #LOCATION = "C544" !CDS_LOCATION = "C544" &SEC = "1" #&CDS_SEC = "1";
"A":   PN = "1"  !CDS_PN = "1";
"B":   PN = "2"  !CDS_PN = "2";
BODY = "Q_CAP","I38": #LOCATION = "C576" !CDS_LOCATION = "C576" &SEC = "1" #&CDS_SEC = "1";
"A":   PN = "1"  !CDS_PN = "1";
"B":   PN = "2"  !CDS_PN = "2";
BODY = "Q_CAP","I39": #LOCATION = "C580" !CDS_LOCATION = "C580" &SEC = "1" #&CDS_SEC = "1";
"A":   PN = "1"  !CDS_PN = "1";
"B":   PN = "2"  !CDS_PN = "2";
BODY = "Q_CAP","I40": #LOCATION = "C555" !CDS_LOCATION = "C555" &SEC = "1" #&CDS_SEC = "1";
"A":   PN = "1"  !CDS_PN = "1";
"B":   PN = "2"  !CDS_PN = "2";
BODY = "Q_CAP","I41": #LOCATION = "C561" !CDS_LOCATION = "C561" &SEC = "1" #&CDS_SEC = "1";
"A":   PN = "1"  !CDS_PN = "1";
"B":   PN = "2"  !CDS_PN = "2";
BODY = "Q_CAP","I42": #LOCATION = "C539" !CDS_LOCATION = "C539" &SEC = "1" #&CDS_SEC = "1";
"A":   PN = "1"  !CDS_PN = "1";
"B":   PN = "2"  !CDS_PN = "2";
BODY = "Q_CAP","I43": #LOCATION = "C562" !CDS_LOCATION = "C562" &SEC = "1" #&CDS_SEC = "1";
"A":   PN = "1"  !CDS_PN = "1";
"B":   PN = "2"  !CDS_PN = "2";
BODY = "Q_CAP","I44": #LOCATION = "C579" !CDS_LOCATION = "C579" &SEC = "1" #&CDS_SEC = "1";
"A":   PN = "1"  !CDS_PN = "1";
"B":   PN = "2"  !CDS_PN = "2";
BODY = "Q_CAP","I45": #LOCATION = "C554" !CDS_LOCATION = "C554" &SEC = "1" #&CDS_SEC = "1";
"A":   PN = "1"  !CDS_PN = "1";
"B":   PN = "2"  !CDS_PN = "2";
BODY = "Q_CAP","I46": #LOCATION = "C571" !CDS_LOCATION = "C571" &SEC = "1" #&CDS_SEC = "1";
"A":   PN = "1"  !CDS_PN = "1";
"B":   PN = "2"  !CDS_PN = "2";
BODY = "Q_CAP","I48": #LOCATION = "C541" !CDS_LOCATION = "C541" &SEC = "1" #&CDS_SEC = "1";
"A":   PN = "1"  !CDS_PN = "1";
"B":   PN = "2"  !CDS_PN = "2";
BODY = "Q_CAP","I49": #LOCATION = "C582" !CDS_LOCATION = "C582" &SEC = "1" #&CDS_SEC = "1";
"A":   PN = "1"  !CDS_PN = "1";
"B":   PN = "2"  !CDS_PN = "2";
BODY = "Q_CAP","I50": #LOCATION = "C523" !CDS_LOCATION = "C523" &SEC = "1" #&CDS_SEC = "1";
"A":   PN = "1"  !CDS_PN = "1";
"B":   PN = "2"  !CDS_PN = "2";
BODY = "Q_CAP","I51": #LOCATION = "C585" !CDS_LOCATION = "C585" &SEC = "1" #&CDS_SEC = "1";
"A":   PN = "1"  !CDS_PN = "1";
"B":   PN = "2"  !CDS_PN = "2";
BODY = "Q_CAP","I52": #LOCATION = "C570" !CDS_LOCATION = "C570" &SEC = "1" #&CDS_SEC = "1";
"A":   PN = "1"  !CDS_PN = "1";
"B":   PN = "2"  !CDS_PN = "2";
BODY = "Q_CAP","I53": #LOCATION = "C573" !CDS_LOCATION = "C573" &SEC = "1" #&CDS_SEC = "1";
"A":   PN = "1"  !CDS_PN = "1";
"B":   PN = "2"  !CDS_PN = "2";
BODY = "Q_CAP","I54": #LOCATION = "C557" !CDS_LOCATION = "C557" &SEC = "1" #&CDS_SEC = "1";
"A":   PN = "1"  !CDS_PN = "1";
"B":   PN = "2"  !CDS_PN = "2";
BODY = "Q_CAP","I55": #LOCATION = "C572" !CDS_LOCATION = "C572" &SEC = "1" #&CDS_SEC = "1";
"A":   PN = "1"  !CDS_PN = "1";
"B":   PN = "2"  !CDS_PN = "2";
BODY = "Q_CAP","I56": #LOCATION = "C577" !CDS_LOCATION = "C577" &SEC = "1" #&CDS_SEC = "1";
"A":   PN = "1"  !CDS_PN = "1";
"B":   PN = "2"  !CDS_PN = "2";
BODY = "Q_CAP","I57": #LOCATION = "C581" !CDS_LOCATION = "C581" &SEC = "1" #&CDS_SEC = "1";
"A":   PN = "1"  !CDS_PN = "1";
"B":   PN = "2"  !CDS_PN = "2";
BODY = "Q_CAP","I58": #LOCATION = "C525" !CDS_LOCATION = "C525" &SEC = "1" #&CDS_SEC = "1";
"A":   PN = "1"  !CDS_PN = "1";
"B":   PN = "2"  !CDS_PN = "2";
BODY = "Q_CAP","I59": #LOCATION = "C529" !CDS_LOCATION = "C529" &SEC = "1" #&CDS_SEC = "1";
"A":   PN = "1"  !CDS_PN = "1";
"B":   PN = "2"  !CDS_PN = "2";
BODY = "Q_CAP","I60": #LOCATION = "C558" !CDS_LOCATION = "C558" &SEC = "1" #&CDS_SEC = "1";
"A":   PN = "1"  !CDS_PN = "1";
"B":   PN = "2"  !CDS_PN = "2";
BODY = "Q_CAP","I62": #LOCATION = "C543" !CDS_LOCATION = "C543" &SEC = "1" #&CDS_SEC = "1";
"A":   PN = "1"  !CDS_PN = "1";
"B":   PN = "2"  !CDS_PN = "2";
BODY = "Q_CAP","I65": #LOCATION = "C521" !CDS_LOCATION = "C521" &SEC = "1" #&CDS_SEC = "1";
"A":   PN = "1"  !CDS_PN = "1";
"B":   PN = "2"  !CDS_PN = "2";
BODY = "Q_CAP","I66": #LOCATION = "C526" !CDS_LOCATION = "C526" &SEC = "1" #&CDS_SEC = "1";
"A":   PN = "1"  !CDS_PN = "1";
"B":   PN = "2"  !CDS_PN = "2";
BODY = "Q_CAP","I67": #LOCATION = "C550" !CDS_LOCATION = "C550" &SEC = "1" #&CDS_SEC = "1";
"A":   PN = "1"  !CDS_PN = "1";
"B":   PN = "2"  !CDS_PN = "2";
BODY = "Q_CAP","I69": #LOCATION = "C556" !CDS_LOCATION = "C556" &SEC = "1" #&CDS_SEC = "1";
"A":   PN = "1"  !CDS_PN = "1";
"B":   PN = "2"  !CDS_PN = "2";
BODY = "Q_CAP","I70": #LOCATION = "C560" !CDS_LOCATION = "C560" &SEC = "1" #&CDS_SEC = "1";
"A":   PN = "1"  !CDS_PN = "1";
"B":   PN = "2"  !CDS_PN = "2";
BODY = "Q_CAP","I71": #LOCATION = "C564" !CDS_LOCATION = "C564" &SEC = "1" #&CDS_SEC = "1";
"A":   PN = "1"  !CDS_PN = "1";
"B":   PN = "2"  !CDS_PN = "2";
BODY = "Q_CAP","I72": #LOCATION = "C559" !CDS_LOCATION = "C559" &SEC = "1" #&CDS_SEC = "1";
"A":   PN = "1"  !CDS_PN = "1";
"B":   PN = "2"  !CDS_PN = "2";
BODY = "Q_CAP","I73": #LOCATION = "C574" !CDS_LOCATION = "C574" &SEC = "1" #&CDS_SEC = "1";
"A":   PN = "1"  !CDS_PN = "1";
"B":   PN = "2"  !CDS_PN = "2";
BODY = "Q_CAP","I74": #LOCATION = "C563" !CDS_LOCATION = "C563" &SEC = "1" #&CDS_SEC = "1";
"A":   PN = "1"  !CDS_PN = "1";
"B":   PN = "2"  !CDS_PN = "2";
BODY = "Q_CAP","I75": #LOCATION = "C586" !CDS_LOCATION = "C586" &SEC = "1" #&CDS_SEC = "1";
"A":   PN = "1"  !CDS_PN = "1";
"B":   PN = "2"  !CDS_PN = "2";
BODY = "Q_CAP","I76": #LOCATION = "C565" !CDS_LOCATION = "C565" &SEC = "1" #&CDS_SEC = "1";
"A":   PN = "1"  !CDS_PN = "1";
"B":   PN = "2"  !CDS_PN = "2";
BODY = "Q_CAP","I77": #LOCATION = "C575" !CDS_LOCATION = "C575" &SEC = "1" #&CDS_SEC = "1";
"A":   PN = "1"  !CDS_PN = "1";
"B":   PN = "2"  !CDS_PN = "2";
BODY = "Q_CAP","I78": #LOCATION = "C568" !CDS_LOCATION = "C568" &SEC = "1" #&CDS_SEC = "1";
"A":   PN = "1"  !CDS_PN = "1";
"B":   PN = "2"  !CDS_PN = "2";
BODY = "Q_CAP","I79": #LOCATION = "C569" !CDS_LOCATION = "C569" &SEC = "1" #&CDS_SEC = "1";
"A":   PN = "1"  !CDS_PN = "1";
"B":   PN = "2"  !CDS_PN = "2";
BODY = "Q_CAP","I80": #LOCATION = "C528" !CDS_LOCATION = "C528" &SEC = "1" #&CDS_SEC = "1";
"A":   PN = "1"  !CDS_PN = "1";
"B":   PN = "2"  !CDS_PN = "2";
BODY = "Q_CAP","I81": #LOCATION = "C522" !CDS_LOCATION = "C522" &SEC = "1" #&CDS_SEC = "1";
"A":   PN = "1"  !CDS_PN = "1";
"B":   PN = "2"  !CDS_PN = "2";
BODY = "Q_CAP","I82": #LOCATION = "C584" !CDS_LOCATION = "C584" &SEC = "1" #&CDS_SEC = "1";
"A":   PN = "1"  !CDS_PN = "1";
"B":   PN = "2"  !CDS_PN = "2";
BODY = "Q_CAP","I83": #LOCATION = "C567" !CDS_LOCATION = "C567" &SEC = "1" #&CDS_SEC = "1";
"A":   PN = "1"  !CDS_PN = "1";
"B":   PN = "2"  !CDS_PN = "2";
BODY = "Q_CAP","I84": #LOCATION = "C524" !CDS_LOCATION = "C524" &SEC = "1" #&CDS_SEC = "1";
"A":   PN = "1"  !CDS_PN = "1";
"B":   PN = "2"  !CDS_PN = "2";
BODY = "Q_CAP","I85": #LOCATION = "C578" !CDS_LOCATION = "C578" &SEC = "1" #&CDS_SEC = "1";
"A":   PN = "1"  !CDS_PN = "1";
"B":   PN = "2"  !CDS_PN = "2";
BODY = "Q_CAP","I87": #LOCATION = "C540" !CDS_LOCATION = "C540" &SEC = "1" #&CDS_SEC = "1";
"A":   PN = "1"  !CDS_PN = "1";
"B":   PN = "2"  !CDS_PN = "2";
BODY = "Q_INDUCTOR","I88": #LOCATION = "L26" !CDS_LOCATION = "L26" &SEC = "1" #&CDS_SEC = "1";
"1":   PN = "1"  !CDS_PN = "1";
"2":   PN = "2"  !CDS_PN = "2";
BODY = "Q_RES","I89": #LOCATION = "R960" !CDS_LOCATION = "R960" &SEC = "1" #&CDS_SEC = "1";
"A":   PN = "1"  !CDS_PN = "1";
"B":   PN = "2"  !CDS_PN = "2";
BODY = "Q_CAP","I90": #LOCATION = "C542" !CDS_LOCATION = "C542" &SEC = "1" #&CDS_SEC = "1";
"A":   PN = "1"  !CDS_PN = "1";
"B":   PN = "2"  !CDS_PN = "2";
BODY = "Q_CAP","I91": #LOCATION = "C545" !CDS_LOCATION = "C545" &SEC = "1" #&CDS_SEC = "1";
"A":   PN = "1"  !CDS_PN = "1";
"B":   PN = "2"  !CDS_PN = "2";
BODY = "Q_CAP","I93": #LOCATION = "C583" !CDS_LOCATION = "C583" &SEC = "1" #&CDS_SEC = "1";
"A":   PN = "1"  !CDS_PN = "1";
"B":   PN = "2"  !CDS_PN = "2";
BODY = "Q_CAP","I94": #LOCATION = "C566" !CDS_LOCATION = "C566" &SEC = "1" #&CDS_SEC = "1";
"A":   PN = "1"  !CDS_PN = "1";
"B":   PN = "2"  !CDS_PN = "2";
BODY = "Q_CAP","I95": #LOCATION = "C7003" !CDS_LOCATION = "C7003" &SEC = "1" #&CDS_SEC = "1";
"A":   PN = "1"  !CDS_PN = "1";
"B":   PN = "2"  !CDS_PN = "2";
BODY = "Q_CAP","I96": #LOCATION = "C7002" !CDS_LOCATION = "C7002" &SEC = "1" #&CDS_SEC = "1";
"A":   PN = "1"  !CDS_PN = "1";
"B":   PN = "2"  !CDS_PN = "2";
BODY = "Q_CAPP","I97": #LOCATION = "C7001" !CDS_LOCATION = "C7001" &SEC = "1" #&CDS_SEC = "1";
"A":   PN = "1"  !CDS_PN = "1";
"B":   PN = "2"  !CDS_PN = "2";
BODY = "Q_CAPP","I98": #LOCATION = "C7000" !CDS_LOCATION = "C7000" &SEC = "1" #&CDS_SEC = "1";
"A":   PN = "1"  !CDS_PN = "1";
"B":   PN = "2"  !CDS_PN = "2";
BODY = "Q_CAPP","I99": #LOCATION = "C7008" !CDS_LOCATION = "C7008" &SEC = "1" #&CDS_SEC = "1";
"A":   PN = "1"  !CDS_PN = "1";
"B":   PN = "2"  !CDS_PN = "2";
BODY = "Q_CAPP","I100": #LOCATION = "C7009" !CDS_LOCATION = "C7009" &SEC = "1" #&CDS_SEC = "1";
"A":   PN = "1"  !CDS_PN = "1";
"B":   PN = "2"  !CDS_PN = "2";
BODY = "Q_CAP","I101": #LOCATION = "C7010" !CDS_LOCATION = "C7010" &SEC = "1" #&CDS_SEC = "1";
"A":   PN = "1"  !CDS_PN = "1";
"B":   PN = "2"  !CDS_PN = "2";
BODY = "Q_CAPP","I102": #LOCATION = "C7032" !CDS_LOCATION = "C7032" &SEC = "1" #&CDS_SEC = "1";
"A":   PN = "1"  !CDS_PN = "1";
"B":   PN = "2"  !CDS_PN = "2";
BODY = "Q_CAP","I103": #LOCATION = "C7033" !CDS_LOCATION = "C7033" &SEC = "1" #&CDS_SEC = "1";
"A":   PN = "1"  !CDS_PN = "1";
"B":   PN = "2"  !CDS_PN = "2";
BODY = "Q_CAP","I104": #LOCATION = "C7034" !CDS_LOCATION = "C7034" &SEC = "1" #&CDS_SEC = "1";
"A":   PN = "1"  !CDS_PN = "1";
"B":   PN = "2"  !CDS_PN = "2";
BODY = "Q_CAP","I105": #LOCATION = "C7035" !CDS_LOCATION = "C7035" &SEC = "1" #&CDS_SEC = "1";
"A":   PN = "1"  !CDS_PN = "1";
"B":   PN = "2"  !CDS_PN = "2";
BODY = "Q_CAP","I106": #LOCATION = "C7036" !CDS_LOCATION = "C7036" &SEC = "1" #&CDS_SEC = "1";
"A":   PN = "1"  !CDS_PN = "1";
"B":   PN = "2"  !CDS_PN = "2";
DRAWING = "@t6g_mb_lib.t6g(sch_1):page409";
BODY = "PT5161LRS","I5": #LOCATION = "U6011" !CDS_LOCATION = "U6011" &SEC = "4" #&CDS_SEC = "4";
"PWR_1A_1":   PN = "BV20"  !CDS_PN = "BV20";
"PWR_1A_2":   PN = "CE17"  !CDS_PN = "CE17";
"PWR_1A_3":   PN = "CE20"  !CDS_PN = "CE20";
"PWR_1A_4":   PN = "CM17"  !CDS_PN = "CM17";
"PWR_1A_5":   PN = "CM20"  !CDS_PN = "CM20";
"PWR_1D":   PN = "BV17"  !CDS_PN = "BV17";
"PWR_2A_1":   PN = "AC17"  !CDS_PN = "AC17";
"PWR_2A_2":   PN = "AC20"  !CDS_PN = "AC20";
"PWR_2A_3":   PN = "AK17"  !CDS_PN = "AK17";
"PWR_2A_4":   PN = "AK20"  !CDS_PN = "AK20";
"PWR_2A_5":   PN = "AU17"  !CDS_PN = "AU17";
"PWR_2A_6":   PN = "AU20"  !CDS_PN = "AU20";
"PWR_2A_7":   PN = "BD17"  !CDS_PN = "BD17";
"PWR_2A_8":   PN = "BD20"  !CDS_PN = "BD20";
"PWR_2A_9":   PN = "DF17"  !CDS_PN = "DF17";
"PWR_2A_10":   PN = "DF20"  !CDS_PN = "DF20";
"PWR_2A_11":   PN = "DN17"  !CDS_PN = "DN17";
"PWR_2A_12":   PN = "DN20"  !CDS_PN = "DN20";
"PWR_2A_13":   PN = "DY17"  !CDS_PN = "DY17";
"PWR_2A_14":   PN = "DY20"  !CDS_PN = "DY20";
"PWR_2A_15":   PN = "EG17"  !CDS_PN = "EG17";
"PWR_2A_16":   PN = "EG20"  !CDS_PN = "EG20";
"PWR_2A_17":   PN = "EP17"  !CDS_PN = "EP17";
"PWR_2A_18":   PN = "EP20"  !CDS_PN = "EP20";
"PWR_2A_19":   PN = "T17"  !CDS_PN = "T17";
"PWR_2A_20":   PN = "T20"  !CDS_PN = "T20";
"PWR_2D_1":   PN = "BL17"  !CDS_PN = "BL17";
"PWR_2D_2":   PN = "BL20"  !CDS_PN = "BL20";
"PWR_2D_3":   PN = "CW17"  !CDS_PN = "CW17";
"PWR_2D_4":   PN = "CW20"  !CDS_PN = "CW20";
"VQPS":   PN = "G1"  !CDS_PN = "G1";
BODY = "Q_RES","I13": #LOCATION = "R1042" !CDS_LOCATION = "R1042" &SEC = "1" #&CDS_SEC = "1";
"A":   PN = "1"  !CDS_PN = "1";
"B":   PN = "2"  !CDS_PN = "2";
BODY = "Q_RES","I15": #LOCATION = "R1043" !CDS_LOCATION = "R1043" &SEC = "1" #&CDS_SEC = "1";
"A":   PN = "1"  !CDS_PN = "1";
"B":   PN = "2"  !CDS_PN = "2";
BODY = "PT5161LRS","I17": #LOCATION = "U6011" !CDS_LOCATION = "U6011" &SEC = "5" #&CDS_SEC = "5";
"GND1":   PN = "AC13"  !CDS_PN = "AC13";
"GND2":   PN = "AC22"  !CDS_PN = "AC22";
"GND3":   PN = "AC32"  !CDS_PN = "AC32";
"GND4":   PN = "AC4"  !CDS_PN = "AC4";
"GND5":   PN = "AD2"  !CDS_PN = "AD2";
"GND6":   PN = "AD34"  !CDS_PN = "AD34";
"GND7":   PN = "AE1"  !CDS_PN = "AE1";
"GND8":   PN = "AE35"  !CDS_PN = "AE35";
"GND9":   PN = "AK13"  !CDS_PN = "AK13";
"GND10":   PN = "AK22"  !CDS_PN = "AK22";
"GND11":   PN = "AK32"  !CDS_PN = "AK32";
"GND12":   PN = "AK4"  !CDS_PN = "AK4";
"GND13":   PN = "AL2"  !CDS_PN = "AL2";
"GND14":   PN = "AL34"  !CDS_PN = "AL34";
"GND15":   PN = "AM1"  !CDS_PN = "AM1";
"GND16":   PN = "AM35"  !CDS_PN = "AM35";
"GND17":   PN = "AU13"  !CDS_PN = "AU13";
"GND18":   PN = "AU22"  !CDS_PN = "AU22";
"GND19":   PN = "AU32"  !CDS_PN = "AU32";
"GND20":   PN = "AU4"  !CDS_PN = "AU4";
"GND21":   PN = "AV2"  !CDS_PN = "AV2";
"GND22":   PN = "AV34"  !CDS_PN = "AV34";
"GND23":   PN = "AW1"  !CDS_PN = "AW1";
"GND24":   PN = "AW35"  !CDS_PN = "AW35";
"GND25":   PN = "B19"  !CDS_PN = "B19";
"GND26":   PN = "BD13"  !CDS_PN = "BD13";
"GND27":   PN = "BD22"  !CDS_PN = "BD22";
"GND28":   PN = "BD32"  !CDS_PN = "BD32";
"GND29":   PN = "BD4"  !CDS_PN = "BD4";
"GND30":   PN = "BE2"  !CDS_PN = "BE2";
"GND31":   PN = "BE34"  !CDS_PN = "BE34";
"GND32":   PN = "BF1"  !CDS_PN = "BF1";
"GND33":   PN = "BF35"  !CDS_PN = "BF35";
"GND34":   PN = "BL13"  !CDS_PN = "BL13";
"GND35":   PN = "BL22"  !CDS_PN = "BL22";
"GND36":   PN = "BL32"  !CDS_PN = "BL32";
"GND37":   PN = "BL4"  !CDS_PN = "BL4";
"GND38":   PN = "BM2"  !CDS_PN = "BM2";
"GND39":   PN = "BM34"  !CDS_PN = "BM34";
"GND40":   PN = "BN1"  !CDS_PN = "BN1";
"GND41":   PN = "BN35"  !CDS_PN = "BN35";
"GND42":   PN = "BV13"  !CDS_PN = "BV13";
"GND43":   PN = "BV22"  !CDS_PN = "BV22";
"GND44":   PN = "BV32"  !CDS_PN = "BV32";
"GND45":   PN = "BV4"  !CDS_PN = "BV4";
"GND46":   PN = "BW2"  !CDS_PN = "BW2";
"GND47":   PN = "BW34"  !CDS_PN = "BW34";
"GND48":   PN = "BY1"  !CDS_PN = "BY1";
"GND49":   PN = "BY35"  !CDS_PN = "BY35";
"GND50":   PN = "CE13"  !CDS_PN = "CE13";
"GND51":   PN = "CE22"  !CDS_PN = "CE22";
"GND52":   PN = "CE32"  !CDS_PN = "CE32";
"GND53":   PN = "CE4"  !CDS_PN = "CE4";
"GND54":   PN = "CF2"  !CDS_PN = "CF2";
"GND55":   PN = "CF34"  !CDS_PN = "CF34";
"GND56":   PN = "CG1"  !CDS_PN = "CG1";
"GND57":   PN = "CG35"  !CDS_PN = "CG35";
"GND58":   PN = "CM13"  !CDS_PN = "CM13";
"GND59":   PN = "CM22"  !CDS_PN = "CM22";
"GND60":   PN = "CM32"  !CDS_PN = "CM32";
"GND61":   PN = "CM4"  !CDS_PN = "CM4";
"GND62":   PN = "CN2"  !CDS_PN = "CN2";
"GND63":   PN = "CN34"  !CDS_PN = "CN34";
"GND64":   PN = "CP1"  !CDS_PN = "CP1";
"GND65":   PN = "CP35"  !CDS_PN = "CP35";
"GND66":   PN = "CW13"  !CDS_PN = "CW13";
"GND67":   PN = "CW22"  !CDS_PN = "CW22";
"GND68":   PN = "CW32"  !CDS_PN = "CW32";
"GND69":   PN = "CW4"  !CDS_PN = "CW4";
"GND70":   PN = "CY2"  !CDS_PN = "CY2";
"GND71":   PN = "CY34"  !CDS_PN = "CY34";
"GND72":   PN = "DA1"  !CDS_PN = "DA1";
"GND73":   PN = "DA35"  !CDS_PN = "DA35";
"GND74":   PN = "DF13"  !CDS_PN = "DF13";
"GND75":   PN = "DF22"  !CDS_PN = "DF22";
"GND76":   PN = "DF32"  !CDS_PN = "DF32";
"GND77":   PN = "DF4"  !CDS_PN = "DF4";
"GND78":   PN = "DG2"  !CDS_PN = "DG2";
"GND79":   PN = "DG34"  !CDS_PN = "DG34";
"GND80":   PN = "DH1"  !CDS_PN = "DH1";
"GND81":   PN = "DH35"  !CDS_PN = "DH35";
"GND82":   PN = "DN13"  !CDS_PN = "DN13";
"GND83":   PN = "DN22"  !CDS_PN = "DN22";
"GND84":   PN = "DN32"  !CDS_PN = "DN32";
"GND85":   PN = "DN4"  !CDS_PN = "DN4";
"GND86":   PN = "DP2"  !CDS_PN = "DP2";
"GND87":   PN = "DP34"  !CDS_PN = "DP34";
"GND88":   PN = "DR1"  !CDS_PN = "DR1";
"GND89":   PN = "DR35"  !CDS_PN = "DR35";
"GND90":   PN = "DY13"  !CDS_PN = "DY13";
"GND91":   PN = "DY22"  !CDS_PN = "DY22";
"GND92":   PN = "DY32"  !CDS_PN = "DY32";
"GND93":   PN = "DY4"  !CDS_PN = "DY4";
"GND94":   PN = "E14"  !CDS_PN = "E14";
"GND95":   PN = "E27"  !CDS_PN = "E27";
"GND96":   PN = "E33"  !CDS_PN = "E33";
"GND97":   PN = "EA2"  !CDS_PN = "EA2";
"GND98":   PN = "EA34"  !CDS_PN = "EA34";
"GND99":   PN = "EB1"  !CDS_PN = "EB1";
"GND100":   PN = "EB35"  !CDS_PN = "EB35";
"GND101":   PN = "EG13"  !CDS_PN = "EG13";
"GND102":   PN = "EG22"  !CDS_PN = "EG22";
"GND103":   PN = "EG32"  !CDS_PN = "EG32";
"GND104":   PN = "EG4"  !CDS_PN = "EG4";
"GND105":   PN = "EH2"  !CDS_PN = "EH2";
"GND106":   PN = "EH34"  !CDS_PN = "EH34";
"GND107":   PN = "EJ1"  !CDS_PN = "EJ1";
"GND108":   PN = "EJ35"  !CDS_PN = "EJ35";
"GND109":   PN = "EP13"  !CDS_PN = "EP13";
"GND110":   PN = "EP22"  !CDS_PN = "EP22";
"GND111":   PN = "EP32"  !CDS_PN = "EP32";
"GND112":   PN = "EP4"  !CDS_PN = "EP4";
"GND113":   PN = "ER2"  !CDS_PN = "ER2";
"GND114":   PN = "ER34"  !CDS_PN = "ER34";
"GND115":   PN = "ET1"  !CDS_PN = "ET1";
"GND116":   PN = "ET35"  !CDS_PN = "ET35";
"GND117":   PN = "FA15"  !CDS_PN = "FA15";
"GND118":   PN = "FA32"  !CDS_PN = "FA32";
"GND119":   PN = "FB2"  !CDS_PN = "FB2";
"GND120":   PN = "FB34"  !CDS_PN = "FB34";
"GND121":   PN = "FC19"  !CDS_PN = "FC19";
"GND122":   PN = "FC23"  !CDS_PN = "FC23";
"GND123":   PN = "FC25"  !CDS_PN = "FC25";
"GND124":   PN = "FC28"  !CDS_PN = "FC28";
"GND125":   PN = "FC3"  !CDS_PN = "FC3";
"GND126":   PN = "FC6"  !CDS_PN = "FC6";
"GND127":   PN = "FC9"  !CDS_PN = "FC9";
"GND128":   PN = "FD1"  !CDS_PN = "FD1";
"GND129":   PN = "FD35"  !CDS_PN = "FD35";
"GND130":   PN = "FF14"  !CDS_PN = "FF14";
"GND131":   PN = "FF21"  !CDS_PN = "FF21";
"GND132":   PN = "FJ12"  !CDS_PN = "FJ12";
"GND133":   PN = "FJ19"  !CDS_PN = "FJ19";
"GND134":   PN = "H12"  !CDS_PN = "H12";
"GND135":   PN = "H16"  !CDS_PN = "H16";
"GND136":   PN = "H19"  !CDS_PN = "H19";
"GND137":   PN = "H31"  !CDS_PN = "H31";
"GND138":   PN = "J22"  !CDS_PN = "J22";
"GND139":   PN = "J4"  !CDS_PN = "J4";
"GND140":   PN = "K2"  !CDS_PN = "K2";
"GND141":   PN = "K34"  !CDS_PN = "K34";
"GND142":   PN = "L1"  !CDS_PN = "L1";
"GND143":   PN = "L35"  !CDS_PN = "L35";
"GND144":   PN = "T13"  !CDS_PN = "T13";
"GND145":   PN = "T22"  !CDS_PN = "T22";
"GND146":   PN = "T32"  !CDS_PN = "T32";
"GND147":   PN = "T4"  !CDS_PN = "T4";
"GND148":   PN = "U2"  !CDS_PN = "U2";
"GND149":   PN = "U34"  !CDS_PN = "U34";
"GND150":   PN = "V1"  !CDS_PN = "V1";
"GND151":   PN = "V35"  !CDS_PN = "V35";
"NCF_GND1":   PN = "A1"  !CDS_PN = "A1";
"NCF_GND2":   PN = "A35"  !CDS_PN = "A35";
"NCF_GND3":   PN = "C2"  !CDS_PN = "C2";
"NCF_GND4":   PN = "C34"  !CDS_PN = "C34";
"NCF_GND5":   PN = "D1"  !CDS_PN = "D1";
"NCF_GND6":   PN = "D35"  !CDS_PN = "D35";
"NCF_GND7":   PN = "FE2"  !CDS_PN = "FE2";
"NCF_GND8":   PN = "FE34"  !CDS_PN = "FE34";
"NCF_GND9":   PN = "FG1"  !CDS_PN = "FG1";
"NCF_GND10":   PN = "FG35"  !CDS_PN = "FG35";
"NCF_GND11":   PN = "FH2"  !CDS_PN = "FH2";
"NCF_GND12":   PN = "FH34"  !CDS_PN = "FH34";
BODY = "Q_RES","I18": #LOCATION = "R1041" !CDS_LOCATION = "R1041" &SEC = "1" #&CDS_SEC = "1";
"A":   PN = "1"  !CDS_PN = "1";
"B":   PN = "2"  !CDS_PN = "2";
BODY = "Q_RES","I19": #LOCATION = "R1040" !CDS_LOCATION = "R1040" &SEC = "1" #&CDS_SEC = "1";
"A":   PN = "1"  !CDS_PN = "1";
"B":   PN = "2"  !CDS_PN = "2";
DRAWING = "@t6g_mb_lib.t6g(sch_1):page411";
BODY = "Q_RES","I2": #LOCATION = "R1003" !CDS_LOCATION = "R1003" #SEC = "1" !CDS_SEC = "1";
"A":   PN = "1"  !CDS_PN = "1";
"B":   PN = "2"  !CDS_PN = "2";
BODY = "Q_RES","I4": #LOCATION = "R1002" !CDS_LOCATION = "R1002" #SEC = "1" !CDS_SEC = "1";
"A":   PN = "1"  !CDS_PN = "1";
"B":   PN = "2"  !CDS_PN = "2";
BODY = "Q_CAP","I5": #LOCATION = "C598" !CDS_LOCATION = "C598" &SEC = "1" #&CDS_SEC = "1";
"A":   PN = "1"  !CDS_PN = "1";
"B":   PN = "2"  !CDS_PN = "2";
BODY = "Q_CAP","I7": #LOCATION = "C601" !CDS_LOCATION = "C601" &SEC = "1" #&CDS_SEC = "1";
"A":   PN = "1"  !CDS_PN = "1";
"B":   PN = "2"  !CDS_PN = "2";
BODY = "Q_RES","I10": #LOCATION = "R1010" !CDS_LOCATION = "R1010" &SEC = "1" #&CDS_SEC = "1";
"A":   PN = "1"  !CDS_PN = "1";
"B":   PN = "2"  !CDS_PN = "2";
BODY = "Q_INDUCTOR","I11": #LOCATION = "L13" !CDS_LOCATION = "L13" &SEC = "1" #&CDS_SEC = "1";
"1":   PN = "1"  !CDS_PN = "1";
"2":   PN = "2"  !CDS_PN = "2";
BODY = "Q_CAP","I12": #LOCATION = "C588" !CDS_LOCATION = "C588" &SEC = "1" #&CDS_SEC = "1";
"A":   PN = "1"  !CDS_PN = "1";
"B":   PN = "2"  !CDS_PN = "2";
BODY = "Q_CAP","I15": #LOCATION = "C590" !CDS_LOCATION = "C590" &SEC = "1" #&CDS_SEC = "1";
"A":   PN = "1"  !CDS_PN = "1";
"B":   PN = "2"  !CDS_PN = "2";
BODY = "Q_CAP","I16": #LOCATION = "C595" !CDS_LOCATION = "C595" &SEC = "1" #&CDS_SEC = "1";
"A":   PN = "1"  !CDS_PN = "1";
"B":   PN = "2"  !CDS_PN = "2";
BODY = "Q_CAP","I17": #LOCATION = "C587" !CDS_LOCATION = "C587" &SEC = "1" #&CDS_SEC = "1";
"A":   PN = "1"  !CDS_PN = "1";
"B":   PN = "2"  !CDS_PN = "2";
BODY = "Q_CAP","I18": #LOCATION = "C589" !CDS_LOCATION = "C589" &SEC = "1" #&CDS_SEC = "1";
"A":   PN = "1"  !CDS_PN = "1";
"B":   PN = "2"  !CDS_PN = "2";
BODY = "Q_CAP","I19": #LOCATION = "C594" !CDS_LOCATION = "C594" &SEC = "1" #&CDS_SEC = "1";
"A":   PN = "1"  !CDS_PN = "1";
"B":   PN = "2"  !CDS_PN = "2";
BODY = "Q_CAP","I20": #LOCATION = "C597" !CDS_LOCATION = "C597" &SEC = "1" #&CDS_SEC = "1";
"A":   PN = "1"  !CDS_PN = "1";
"B":   PN = "2"  !CDS_PN = "2";
BODY = "Q_CAP","I21": #LOCATION = "C599" !CDS_LOCATION = "C599" &SEC = "1" #&CDS_SEC = "1";
"A":   PN = "1"  !CDS_PN = "1";
"B":   PN = "2"  !CDS_PN = "2";
BODY = "Q_CAP","I22": #LOCATION = "C591" !CDS_LOCATION = "C591" &SEC = "1" #&CDS_SEC = "1";
"A":   PN = "1"  !CDS_PN = "1";
"B":   PN = "2"  !CDS_PN = "2";
BODY = "Q_CAP","I24": #LOCATION = "C596" !CDS_LOCATION = "C596" &SEC = "1" #&CDS_SEC = "1";
"A":   PN = "1"  !CDS_PN = "1";
"B":   PN = "2"  !CDS_PN = "2";
BODY = "Q_CAP","I25": #LOCATION = "C600" !CDS_LOCATION = "C600" &SEC = "1" #&CDS_SEC = "1";
"A":   PN = "1"  !CDS_PN = "1";
"B":   PN = "2"  !CDS_PN = "2";
BODY = "Q_CAP","I26": #LOCATION = "C602" !CDS_LOCATION = "C602" &SEC = "1" #&CDS_SEC = "1";
"A":   PN = "1"  !CDS_PN = "1";
"B":   PN = "2"  !CDS_PN = "2";
BODY = "Q_CAP","I27": #LOCATION = "C603" !CDS_LOCATION = "C603" &SEC = "1" #&CDS_SEC = "1";
"A":   PN = "1"  !CDS_PN = "1";
"B":   PN = "2"  !CDS_PN = "2";
BODY = "Q_CAP","I28": #LOCATION = "C606" !CDS_LOCATION = "C606" &SEC = "1" #&CDS_SEC = "1";
"A":   PN = "1"  !CDS_PN = "1";
"B":   PN = "2"  !CDS_PN = "2";
BODY = "Q_CAP","I32": #LOCATION = "C617" !CDS_LOCATION = "C617" &SEC = "1" #&CDS_SEC = "1";
"A":   PN = "1"  !CDS_PN = "1";
"B":   PN = "2"  !CDS_PN = "2";
BODY = "Q_CAP","I34": #LOCATION = "C623" !CDS_LOCATION = "C623" &SEC = "1" #&CDS_SEC = "1";
"A":   PN = "1"  !CDS_PN = "1";
"B":   PN = "2"  !CDS_PN = "2";
BODY = "Q_RES","I36": #LOCATION = "R1011" !CDS_LOCATION = "R1011" &SEC = "1" #&CDS_SEC = "1";
"A":   PN = "1"  !CDS_PN = "1";
"B":   PN = "2"  !CDS_PN = "2";
BODY = "Q_CAP","I37": #LOCATION = "C662" !CDS_LOCATION = "C662" &SEC = "1" #&CDS_SEC = "1";
"A":   PN = "1"  !CDS_PN = "1";
"B":   PN = "2"  !CDS_PN = "2";
BODY = "Q_CAP","I38": #LOCATION = "C609" !CDS_LOCATION = "C609" &SEC = "1" #&CDS_SEC = "1";
"A":   PN = "1"  !CDS_PN = "1";
"B":   PN = "2"  !CDS_PN = "2";
BODY = "Q_CAP","I39": #LOCATION = "C618" !CDS_LOCATION = "C618" &SEC = "1" #&CDS_SEC = "1";
"A":   PN = "1"  !CDS_PN = "1";
"B":   PN = "2"  !CDS_PN = "2";
BODY = "Q_CAP","I40": #LOCATION = "C626" !CDS_LOCATION = "C626" &SEC = "1" #&CDS_SEC = "1";
"A":   PN = "1"  !CDS_PN = "1";
"B":   PN = "2"  !CDS_PN = "2";
BODY = "Q_CAP","I41": #LOCATION = "C645" !CDS_LOCATION = "C645" &SEC = "1" #&CDS_SEC = "1";
"A":   PN = "1"  !CDS_PN = "1";
"B":   PN = "2"  !CDS_PN = "2";
BODY = "Q_CAP","I42": #LOCATION = "C616" !CDS_LOCATION = "C616" &SEC = "1" #&CDS_SEC = "1";
"A":   PN = "1"  !CDS_PN = "1";
"B":   PN = "2"  !CDS_PN = "2";
BODY = "Q_CAP","I43": #LOCATION = "C657" !CDS_LOCATION = "C657" &SEC = "1" #&CDS_SEC = "1";
"A":   PN = "1"  !CDS_PN = "1";
"B":   PN = "2"  !CDS_PN = "2";
BODY = "Q_CAP","I44": #LOCATION = "C607" !CDS_LOCATION = "C607" &SEC = "1" #&CDS_SEC = "1";
"A":   PN = "1"  !CDS_PN = "1";
"B":   PN = "2"  !CDS_PN = "2";
BODY = "Q_CAP","I45": #LOCATION = "C643" !CDS_LOCATION = "C643" &SEC = "1" #&CDS_SEC = "1";
"A":   PN = "1"  !CDS_PN = "1";
"B":   PN = "2"  !CDS_PN = "2";
BODY = "Q_CAP","I46": #LOCATION = "C635" !CDS_LOCATION = "C635" &SEC = "1" #&CDS_SEC = "1";
"A":   PN = "1"  !CDS_PN = "1";
"B":   PN = "2"  !CDS_PN = "2";
BODY = "Q_CAP","I47": #LOCATION = "C627" !CDS_LOCATION = "C627" &SEC = "1" #&CDS_SEC = "1";
"A":   PN = "1"  !CDS_PN = "1";
"B":   PN = "2"  !CDS_PN = "2";
BODY = "Q_CAP","I48": #LOCATION = "C647" !CDS_LOCATION = "C647" &SEC = "1" #&CDS_SEC = "1";
"A":   PN = "1"  !CDS_PN = "1";
"B":   PN = "2"  !CDS_PN = "2";
BODY = "Q_CAP","I49": #LOCATION = "C654" !CDS_LOCATION = "C654" &SEC = "1" #&CDS_SEC = "1";
"A":   PN = "1"  !CDS_PN = "1";
"B":   PN = "2"  !CDS_PN = "2";
BODY = "Q_CAP","I50": #LOCATION = "C644" !CDS_LOCATION = "C644" &SEC = "1" #&CDS_SEC = "1";
"A":   PN = "1"  !CDS_PN = "1";
"B":   PN = "2"  !CDS_PN = "2";
BODY = "Q_CAP","I51": #LOCATION = "C638" !CDS_LOCATION = "C638" &SEC = "1" #&CDS_SEC = "1";
"A":   PN = "1"  !CDS_PN = "1";
"B":   PN = "2"  !CDS_PN = "2";
BODY = "Q_CAP","I52": #LOCATION = "C649" !CDS_LOCATION = "C649" &SEC = "1" #&CDS_SEC = "1";
"A":   PN = "1"  !CDS_PN = "1";
"B":   PN = "2"  !CDS_PN = "2";
BODY = "Q_CAP","I53": #LOCATION = "C653" !CDS_LOCATION = "C653" &SEC = "1" #&CDS_SEC = "1";
"A":   PN = "1"  !CDS_PN = "1";
"B":   PN = "2"  !CDS_PN = "2";
BODY = "Q_CAP","I55": #LOCATION = "C631" !CDS_LOCATION = "C631" &SEC = "1" #&CDS_SEC = "1";
"A":   PN = "1"  !CDS_PN = "1";
"B":   PN = "2"  !CDS_PN = "2";
BODY = "Q_CAP","I58": #LOCATION = "C650" !CDS_LOCATION = "C650" &SEC = "1" #&CDS_SEC = "1";
"A":   PN = "1"  !CDS_PN = "1";
"B":   PN = "2"  !CDS_PN = "2";
BODY = "Q_CAP","I59": #LOCATION = "C620" !CDS_LOCATION = "C620" &SEC = "1" #&CDS_SEC = "1";
"A":   PN = "1"  !CDS_PN = "1";
"B":   PN = "2"  !CDS_PN = "2";
BODY = "Q_CAP","I61": #LOCATION = "C613" !CDS_LOCATION = "C613" &SEC = "1" #&CDS_SEC = "1";
"A":   PN = "1"  !CDS_PN = "1";
"B":   PN = "2"  !CDS_PN = "2";
BODY = "Q_INDUCTOR","I63": #LOCATION = "L14" !CDS_LOCATION = "L14" &SEC = "1" #&CDS_SEC = "1";
"1":   PN = "1"  !CDS_PN = "1";
"2":   PN = "2"  !CDS_PN = "2";
BODY = "Q_CAP","I64": #LOCATION = "C625" !CDS_LOCATION = "C625" &SEC = "1" #&CDS_SEC = "1";
"A":   PN = "1"  !CDS_PN = "1";
"B":   PN = "2"  !CDS_PN = "2";
BODY = "Q_CAP","I65": #LOCATION = "C628" !CDS_LOCATION = "C628" &SEC = "1" #&CDS_SEC = "1";
"A":   PN = "1"  !CDS_PN = "1";
"B":   PN = "2"  !CDS_PN = "2";
BODY = "Q_CAP","I67": #LOCATION = "C632" !CDS_LOCATION = "C632" &SEC = "1" #&CDS_SEC = "1";
"A":   PN = "1"  !CDS_PN = "1";
"B":   PN = "2"  !CDS_PN = "2";
BODY = "Q_CAP","I68": #LOCATION = "C636" !CDS_LOCATION = "C636" &SEC = "1" #&CDS_SEC = "1";
"A":   PN = "1"  !CDS_PN = "1";
"B":   PN = "2"  !CDS_PN = "2";
BODY = "Q_CAP","I69": #LOCATION = "C633" !CDS_LOCATION = "C633" &SEC = "1" #&CDS_SEC = "1";
"A":   PN = "1"  !CDS_PN = "1";
"B":   PN = "2"  !CDS_PN = "2";
BODY = "Q_CAP","I70": #LOCATION = "C637" !CDS_LOCATION = "C637" &SEC = "1" #&CDS_SEC = "1";
"A":   PN = "1"  !CDS_PN = "1";
"B":   PN = "2"  !CDS_PN = "2";
BODY = "Q_CAP","I71": #LOCATION = "C634" !CDS_LOCATION = "C634" &SEC = "1" #&CDS_SEC = "1";
"A":   PN = "1"  !CDS_PN = "1";
"B":   PN = "2"  !CDS_PN = "2";
BODY = "Q_CAP","I72": #LOCATION = "C663" !CDS_LOCATION = "C663" &SEC = "1" #&CDS_SEC = "1";
"A":   PN = "1"  !CDS_PN = "1";
"B":   PN = "2"  !CDS_PN = "2";
BODY = "Q_CAP","I73": #LOCATION = "C630" !CDS_LOCATION = "C630" &SEC = "1" #&CDS_SEC = "1";
"A":   PN = "1"  !CDS_PN = "1";
"B":   PN = "2"  !CDS_PN = "2";
BODY = "Q_CAP","I74": #LOCATION = "C646" !CDS_LOCATION = "C646" &SEC = "1" #&CDS_SEC = "1";
"A":   PN = "1"  !CDS_PN = "1";
"B":   PN = "2"  !CDS_PN = "2";
BODY = "Q_CAP","I75": #LOCATION = "C651" !CDS_LOCATION = "C651" &SEC = "1" #&CDS_SEC = "1";
"A":   PN = "1"  !CDS_PN = "1";
"B":   PN = "2"  !CDS_PN = "2";
BODY = "Q_CAP","I76": #LOCATION = "C655" !CDS_LOCATION = "C655" &SEC = "1" #&CDS_SEC = "1";
"A":   PN = "1"  !CDS_PN = "1";
"B":   PN = "2"  !CDS_PN = "2";
BODY = "Q_CAP","I77": #LOCATION = "C656" !CDS_LOCATION = "C656" &SEC = "1" #&CDS_SEC = "1";
"A":   PN = "1"  !CDS_PN = "1";
"B":   PN = "2"  !CDS_PN = "2";
BODY = "Q_CAP","I78": #LOCATION = "C661" !CDS_LOCATION = "C661" &SEC = "1" #&CDS_SEC = "1";
"A":   PN = "1"  !CDS_PN = "1";
"B":   PN = "2"  !CDS_PN = "2";
BODY = "Q_CAP","I79": #LOCATION = "C648" !CDS_LOCATION = "C648" &SEC = "1" #&CDS_SEC = "1";
"A":   PN = "1"  !CDS_PN = "1";
"B":   PN = "2"  !CDS_PN = "2";
BODY = "Q_CAP","I81": #LOCATION = "C608" !CDS_LOCATION = "C608" &SEC = "1" #&CDS_SEC = "1";
"A":   PN = "1"  !CDS_PN = "1";
"B":   PN = "2"  !CDS_PN = "2";
BODY = "Q_CAP","I82": #LOCATION = "C610" !CDS_LOCATION = "C610" &SEC = "1" #&CDS_SEC = "1";
"A":   PN = "1"  !CDS_PN = "1";
"B":   PN = "2"  !CDS_PN = "2";
BODY = "Q_CAP","I83": #LOCATION = "C615" !CDS_LOCATION = "C615" &SEC = "1" #&CDS_SEC = "1";
"A":   PN = "1"  !CDS_PN = "1";
"B":   PN = "2"  !CDS_PN = "2";
BODY = "Q_CAP","I84": #LOCATION = "C619" !CDS_LOCATION = "C619" &SEC = "1" #&CDS_SEC = "1";
"A":   PN = "1"  !CDS_PN = "1";
"B":   PN = "2"  !CDS_PN = "2";
BODY = "Q_CAP","I85": #LOCATION = "C614" !CDS_LOCATION = "C614" &SEC = "1" #&CDS_SEC = "1";
"A":   PN = "1"  !CDS_PN = "1";
"B":   PN = "2"  !CDS_PN = "2";
BODY = "Q_CAP","I86": #LOCATION = "C622" !CDS_LOCATION = "C622" &SEC = "1" #&CDS_SEC = "1";
"A":   PN = "1"  !CDS_PN = "1";
"B":   PN = "2"  !CDS_PN = "2";
BODY = "Q_CAP","I87": #LOCATION = "C652" !CDS_LOCATION = "C652" &SEC = "1" #&CDS_SEC = "1";
"A":   PN = "1"  !CDS_PN = "1";
"B":   PN = "2"  !CDS_PN = "2";
BODY = "Q_INDUCTOR","I88": #LOCATION = "L28" !CDS_LOCATION = "L28" &SEC = "1" #&CDS_SEC = "1";
"1":   PN = "1"  !CDS_PN = "1";
"2":   PN = "2"  !CDS_PN = "2";
BODY = "Q_RES","I89": #LOCATION = "R1008" !CDS_LOCATION = "R1008" &SEC = "1" #&CDS_SEC = "1";
"A":   PN = "1"  !CDS_PN = "1";
"B":   PN = "2"  !CDS_PN = "2";
BODY = "Q_CAP","I90": #LOCATION = "C621" !CDS_LOCATION = "C621" &SEC = "1" #&CDS_SEC = "1";
"A":   PN = "1"  !CDS_PN = "1";
"B":   PN = "2"  !CDS_PN = "2";
BODY = "Q_CAP","I91": #LOCATION = "C624" !CDS_LOCATION = "C624" &SEC = "1" #&CDS_SEC = "1";
"A":   PN = "1"  !CDS_PN = "1";
"B":   PN = "2"  !CDS_PN = "2";
BODY = "Q_CAP","I92": #LOCATION = "C658" !CDS_LOCATION = "C658" &SEC = "1" #&CDS_SEC = "1";
"A":   PN = "1"  !CDS_PN = "1";
"B":   PN = "2"  !CDS_PN = "2";
BODY = "Q_CAP","I93": #LOCATION = "C659" !CDS_LOCATION = "C659" &SEC = "1" #&CDS_SEC = "1";
"A":   PN = "1"  !CDS_PN = "1";
"B":   PN = "2"  !CDS_PN = "2";
BODY = "Q_CAP","I94": #LOCATION = "C660" !CDS_LOCATION = "C660" &SEC = "1" #&CDS_SEC = "1";
"A":   PN = "1"  !CDS_PN = "1";
"B":   PN = "2"  !CDS_PN = "2";
BODY = "Q_CAPP","I95": #LOCATION = "C7011" !CDS_LOCATION = "C7011" &SEC = "1" #&CDS_SEC = "1";
"A":   PN = "1"  !CDS_PN = "1";
"B":   PN = "2"  !CDS_PN = "2";
BODY = "Q_CAPP","I96": #LOCATION = "C7012" !CDS_LOCATION = "C7012" &SEC = "1" #&CDS_SEC = "1";
"A":   PN = "1"  !CDS_PN = "1";
"B":   PN = "2"  !CDS_PN = "2";
BODY = "Q_CAP","I97": #LOCATION = "C7013" !CDS_LOCATION = "C7013" &SEC = "1" #&CDS_SEC = "1";
"A":   PN = "1"  !CDS_PN = "1";
"B":   PN = "2"  !CDS_PN = "2";
DRAWING = "@t6g_mb_lib.t6g(sch_1):page420";
BODY = "PT5161LRS","I6": #LOCATION = "U6012" !CDS_LOCATION = "U6012" &SEC = "4" #&CDS_SEC = "4";
"PWR_1A_1":   PN = "BV20"  !CDS_PN = "BV20";
"PWR_1A_2":   PN = "CE17"  !CDS_PN = "CE17";
"PWR_1A_3":   PN = "CE20"  !CDS_PN = "CE20";
"PWR_1A_4":   PN = "CM17"  !CDS_PN = "CM17";
"PWR_1A_5":   PN = "CM20"  !CDS_PN = "CM20";
"PWR_1D":   PN = "BV17"  !CDS_PN = "BV17";
"PWR_2A_1":   PN = "AC17"  !CDS_PN = "AC17";
"PWR_2A_2":   PN = "AC20"  !CDS_PN = "AC20";
"PWR_2A_3":   PN = "AK17"  !CDS_PN = "AK17";
"PWR_2A_4":   PN = "AK20"  !CDS_PN = "AK20";
"PWR_2A_5":   PN = "AU17"  !CDS_PN = "AU17";
"PWR_2A_6":   PN = "AU20"  !CDS_PN = "AU20";
"PWR_2A_7":   PN = "BD17"  !CDS_PN = "BD17";
"PWR_2A_8":   PN = "BD20"  !CDS_PN = "BD20";
"PWR_2A_9":   PN = "DF17"  !CDS_PN = "DF17";
"PWR_2A_10":   PN = "DF20"  !CDS_PN = "DF20";
"PWR_2A_11":   PN = "DN17"  !CDS_PN = "DN17";
"PWR_2A_12":   PN = "DN20"  !CDS_PN = "DN20";
"PWR_2A_13":   PN = "DY17"  !CDS_PN = "DY17";
"PWR_2A_14":   PN = "DY20"  !CDS_PN = "DY20";
"PWR_2A_15":   PN = "EG17"  !CDS_PN = "EG17";
"PWR_2A_16":   PN = "EG20"  !CDS_PN = "EG20";
"PWR_2A_17":   PN = "EP17"  !CDS_PN = "EP17";
"PWR_2A_18":   PN = "EP20"  !CDS_PN = "EP20";
"PWR_2A_19":   PN = "T17"  !CDS_PN = "T17";
"PWR_2A_20":   PN = "T20"  !CDS_PN = "T20";
"PWR_2D_1":   PN = "BL17"  !CDS_PN = "BL17";
"PWR_2D_2":   PN = "BL20"  !CDS_PN = "BL20";
"PWR_2D_3":   PN = "CW17"  !CDS_PN = "CW17";
"PWR_2D_4":   PN = "CW20"  !CDS_PN = "CW20";
"VQPS":   PN = "G1"  !CDS_PN = "G1";
BODY = "Q_RES","I13": #LOCATION = "R1083" !CDS_LOCATION = "R1083" &SEC = "1" #&CDS_SEC = "1";
"A":   PN = "1"  !CDS_PN = "1";
"B":   PN = "2"  !CDS_PN = "2";
BODY = "Q_RES","I14": #LOCATION = "R1084" !CDS_LOCATION = "R1084" &SEC = "1" #&CDS_SEC = "1";
"A":   PN = "1"  !CDS_PN = "1";
"B":   PN = "2"  !CDS_PN = "2";
BODY = "PT5161LRS","I17": #LOCATION = "U6012" !CDS_LOCATION = "U6012" &SEC = "5" #&CDS_SEC = "5";
"GND1":   PN = "AC13"  !CDS_PN = "AC13";
"GND2":   PN = "AC22"  !CDS_PN = "AC22";
"GND3":   PN = "AC32"  !CDS_PN = "AC32";
"GND4":   PN = "AC4"  !CDS_PN = "AC4";
"GND5":   PN = "AD2"  !CDS_PN = "AD2";
"GND6":   PN = "AD34"  !CDS_PN = "AD34";
"GND7":   PN = "AE1"  !CDS_PN = "AE1";
"GND8":   PN = "AE35"  !CDS_PN = "AE35";
"GND9":   PN = "AK13"  !CDS_PN = "AK13";
"GND10":   PN = "AK22"  !CDS_PN = "AK22";
"GND11":   PN = "AK32"  !CDS_PN = "AK32";
"GND12":   PN = "AK4"  !CDS_PN = "AK4";
"GND13":   PN = "AL2"  !CDS_PN = "AL2";
"GND14":   PN = "AL34"  !CDS_PN = "AL34";
"GND15":   PN = "AM1"  !CDS_PN = "AM1";
"GND16":   PN = "AM35"  !CDS_PN = "AM35";
"GND17":   PN = "AU13"  !CDS_PN = "AU13";
"GND18":   PN = "AU22"  !CDS_PN = "AU22";
"GND19":   PN = "AU32"  !CDS_PN = "AU32";
"GND20":   PN = "AU4"  !CDS_PN = "AU4";
"GND21":   PN = "AV2"  !CDS_PN = "AV2";
"GND22":   PN = "AV34"  !CDS_PN = "AV34";
"GND23":   PN = "AW1"  !CDS_PN = "AW1";
"GND24":   PN = "AW35"  !CDS_PN = "AW35";
"GND25":   PN = "B19"  !CDS_PN = "B19";
"GND26":   PN = "BD13"  !CDS_PN = "BD13";
"GND27":   PN = "BD22"  !CDS_PN = "BD22";
"GND28":   PN = "BD32"  !CDS_PN = "BD32";
"GND29":   PN = "BD4"  !CDS_PN = "BD4";
"GND30":   PN = "BE2"  !CDS_PN = "BE2";
"GND31":   PN = "BE34"  !CDS_PN = "BE34";
"GND32":   PN = "BF1"  !CDS_PN = "BF1";
"GND33":   PN = "BF35"  !CDS_PN = "BF35";
"GND34":   PN = "BL13"  !CDS_PN = "BL13";
"GND35":   PN = "BL22"  !CDS_PN = "BL22";
"GND36":   PN = "BL32"  !CDS_PN = "BL32";
"GND37":   PN = "BL4"  !CDS_PN = "BL4";
"GND38":   PN = "BM2"  !CDS_PN = "BM2";
"GND39":   PN = "BM34"  !CDS_PN = "BM34";
"GND40":   PN = "BN1"  !CDS_PN = "BN1";
"GND41":   PN = "BN35"  !CDS_PN = "BN35";
"GND42":   PN = "BV13"  !CDS_PN = "BV13";
"GND43":   PN = "BV22"  !CDS_PN = "BV22";
"GND44":   PN = "BV32"  !CDS_PN = "BV32";
"GND45":   PN = "BV4"  !CDS_PN = "BV4";
"GND46":   PN = "BW2"  !CDS_PN = "BW2";
"GND47":   PN = "BW34"  !CDS_PN = "BW34";
"GND48":   PN = "BY1"  !CDS_PN = "BY1";
"GND49":   PN = "BY35"  !CDS_PN = "BY35";
"GND50":   PN = "CE13"  !CDS_PN = "CE13";
"GND51":   PN = "CE22"  !CDS_PN = "CE22";
"GND52":   PN = "CE32"  !CDS_PN = "CE32";
"GND53":   PN = "CE4"  !CDS_PN = "CE4";
"GND54":   PN = "CF2"  !CDS_PN = "CF2";
"GND55":   PN = "CF34"  !CDS_PN = "CF34";
"GND56":   PN = "CG1"  !CDS_PN = "CG1";
"GND57":   PN = "CG35"  !CDS_PN = "CG35";
"GND58":   PN = "CM13"  !CDS_PN = "CM13";
"GND59":   PN = "CM22"  !CDS_PN = "CM22";
"GND60":   PN = "CM32"  !CDS_PN = "CM32";
"GND61":   PN = "CM4"  !CDS_PN = "CM4";
"GND62":   PN = "CN2"  !CDS_PN = "CN2";
"GND63":   PN = "CN34"  !CDS_PN = "CN34";
"GND64":   PN = "CP1"  !CDS_PN = "CP1";
"GND65":   PN = "CP35"  !CDS_PN = "CP35";
"GND66":   PN = "CW13"  !CDS_PN = "CW13";
"GND67":   PN = "CW22"  !CDS_PN = "CW22";
"GND68":   PN = "CW32"  !CDS_PN = "CW32";
"GND69":   PN = "CW4"  !CDS_PN = "CW4";
"GND70":   PN = "CY2"  !CDS_PN = "CY2";
"GND71":   PN = "CY34"  !CDS_PN = "CY34";
"GND72":   PN = "DA1"  !CDS_PN = "DA1";
"GND73":   PN = "DA35"  !CDS_PN = "DA35";
"GND74":   PN = "DF13"  !CDS_PN = "DF13";
"GND75":   PN = "DF22"  !CDS_PN = "DF22";
"GND76":   PN = "DF32"  !CDS_PN = "DF32";
"GND77":   PN = "DF4"  !CDS_PN = "DF4";
"GND78":   PN = "DG2"  !CDS_PN = "DG2";
"GND79":   PN = "DG34"  !CDS_PN = "DG34";
"GND80":   PN = "DH1"  !CDS_PN = "DH1";
"GND81":   PN = "DH35"  !CDS_PN = "DH35";
"GND82":   PN = "DN13"  !CDS_PN = "DN13";
"GND83":   PN = "DN22"  !CDS_PN = "DN22";
"GND84":   PN = "DN32"  !CDS_PN = "DN32";
"GND85":   PN = "DN4"  !CDS_PN = "DN4";
"GND86":   PN = "DP2"  !CDS_PN = "DP2";
"GND87":   PN = "DP34"  !CDS_PN = "DP34";
"GND88":   PN = "DR1"  !CDS_PN = "DR1";
"GND89":   PN = "DR35"  !CDS_PN = "DR35";
"GND90":   PN = "DY13"  !CDS_PN = "DY13";
"GND91":   PN = "DY22"  !CDS_PN = "DY22";
"GND92":   PN = "DY32"  !CDS_PN = "DY32";
"GND93":   PN = "DY4"  !CDS_PN = "DY4";
"GND94":   PN = "E14"  !CDS_PN = "E14";
"GND95":   PN = "E27"  !CDS_PN = "E27";
"GND96":   PN = "E33"  !CDS_PN = "E33";
"GND97":   PN = "EA2"  !CDS_PN = "EA2";
"GND98":   PN = "EA34"  !CDS_PN = "EA34";
"GND99":   PN = "EB1"  !CDS_PN = "EB1";
"GND100":   PN = "EB35"  !CDS_PN = "EB35";
"GND101":   PN = "EG13"  !CDS_PN = "EG13";
"GND102":   PN = "EG22"  !CDS_PN = "EG22";
"GND103":   PN = "EG32"  !CDS_PN = "EG32";
"GND104":   PN = "EG4"  !CDS_PN = "EG4";
"GND105":   PN = "EH2"  !CDS_PN = "EH2";
"GND106":   PN = "EH34"  !CDS_PN = "EH34";
"GND107":   PN = "EJ1"  !CDS_PN = "EJ1";
"GND108":   PN = "EJ35"  !CDS_PN = "EJ35";
"GND109":   PN = "EP13"  !CDS_PN = "EP13";
"GND110":   PN = "EP22"  !CDS_PN = "EP22";
"GND111":   PN = "EP32"  !CDS_PN = "EP32";
"GND112":   PN = "EP4"  !CDS_PN = "EP4";
"GND113":   PN = "ER2"  !CDS_PN = "ER2";
"GND114":   PN = "ER34"  !CDS_PN = "ER34";
"GND115":   PN = "ET1"  !CDS_PN = "ET1";
"GND116":   PN = "ET35"  !CDS_PN = "ET35";
"GND117":   PN = "FA15"  !CDS_PN = "FA15";
"GND118":   PN = "FA32"  !CDS_PN = "FA32";
"GND119":   PN = "FB2"  !CDS_PN = "FB2";
"GND120":   PN = "FB34"  !CDS_PN = "FB34";
"GND121":   PN = "FC19"  !CDS_PN = "FC19";
"GND122":   PN = "FC23"  !CDS_PN = "FC23";
"GND123":   PN = "FC25"  !CDS_PN = "FC25";
"GND124":   PN = "FC28"  !CDS_PN = "FC28";
"GND125":   PN = "FC3"  !CDS_PN = "FC3";
"GND126":   PN = "FC6"  !CDS_PN = "FC6";
"GND127":   PN = "FC9"  !CDS_PN = "FC9";
"GND128":   PN = "FD1"  !CDS_PN = "FD1";
"GND129":   PN = "FD35"  !CDS_PN = "FD35";
"GND130":   PN = "FF14"  !CDS_PN = "FF14";
"GND131":   PN = "FF21"  !CDS_PN = "FF21";
"GND132":   PN = "FJ12"  !CDS_PN = "FJ12";
"GND133":   PN = "FJ19"  !CDS_PN = "FJ19";
"GND134":   PN = "H12"  !CDS_PN = "H12";
"GND135":   PN = "H16"  !CDS_PN = "H16";
"GND136":   PN = "H19"  !CDS_PN = "H19";
"GND137":   PN = "H31"  !CDS_PN = "H31";
"GND138":   PN = "J22"  !CDS_PN = "J22";
"GND139":   PN = "J4"  !CDS_PN = "J4";
"GND140":   PN = "K2"  !CDS_PN = "K2";
"GND141":   PN = "K34"  !CDS_PN = "K34";
"GND142":   PN = "L1"  !CDS_PN = "L1";
"GND143":   PN = "L35"  !CDS_PN = "L35";
"GND144":   PN = "T13"  !CDS_PN = "T13";
"GND145":   PN = "T22"  !CDS_PN = "T22";
"GND146":   PN = "T32"  !CDS_PN = "T32";
"GND147":   PN = "T4"  !CDS_PN = "T4";
"GND148":   PN = "U2"  !CDS_PN = "U2";
"GND149":   PN = "U34"  !CDS_PN = "U34";
"GND150":   PN = "V1"  !CDS_PN = "V1";
"GND151":   PN = "V35"  !CDS_PN = "V35";
"NCF_GND1":   PN = "A1"  !CDS_PN = "A1";
"NCF_GND2":   PN = "A35"  !CDS_PN = "A35";
"NCF_GND3":   PN = "C2"  !CDS_PN = "C2";
"NCF_GND4":   PN = "C34"  !CDS_PN = "C34";
"NCF_GND5":   PN = "D1"  !CDS_PN = "D1";
"NCF_GND6":   PN = "D35"  !CDS_PN = "D35";
"NCF_GND7":   PN = "FE2"  !CDS_PN = "FE2";
"NCF_GND8":   PN = "FE34"  !CDS_PN = "FE34";
"NCF_GND9":   PN = "FG1"  !CDS_PN = "FG1";
"NCF_GND10":   PN = "FG35"  !CDS_PN = "FG35";
"NCF_GND11":   PN = "FH2"  !CDS_PN = "FH2";
"NCF_GND12":   PN = "FH34"  !CDS_PN = "FH34";
BODY = "Q_RES","I18": #LOCATION = "R1082" !CDS_LOCATION = "R1082" &SEC = "1" #&CDS_SEC = "1";
"A":   PN = "1"  !CDS_PN = "1";
"B":   PN = "2"  !CDS_PN = "2";
BODY = "Q_RES","I19": #LOCATION = "R1081" !CDS_LOCATION = "R1081" &SEC = "1" #&CDS_SEC = "1";
"A":   PN = "1"  !CDS_PN = "1";
"B":   PN = "2"  !CDS_PN = "2";
DRAWING = "@t6g_mb_lib.t6g(sch_1):page422";
BODY = "Q_RES","I4": #LOCATION = "R1046" !CDS_LOCATION = "R1046" #SEC = "1" !CDS_SEC = "1";
"A":   PN = "1"  !CDS_PN = "1";
"B":   PN = "2"  !CDS_PN = "2";
BODY = "Q_RES","I5": #LOCATION = "R1045" !CDS_LOCATION = "R1045" #SEC = "1" !CDS_SEC = "1";
"A":   PN = "1"  !CDS_PN = "1";
"B":   PN = "2"  !CDS_PN = "2";
BODY = "Q_CAP","I6": #LOCATION = "C666" !CDS_LOCATION = "C666" &SEC = "1" #&CDS_SEC = "1";
"A":   PN = "1"  !CDS_PN = "1";
"B":   PN = "2"  !CDS_PN = "2";
BODY = "Q_CAP","I7": #LOCATION = "C668" !CDS_LOCATION = "C668" &SEC = "1" #&CDS_SEC = "1";
"A":   PN = "1"  !CDS_PN = "1";
"B":   PN = "2"  !CDS_PN = "2";
BODY = "Q_CAP","I9": #LOCATION = "C676" !CDS_LOCATION = "C676" &SEC = "1" #&CDS_SEC = "1";
"A":   PN = "1"  !CDS_PN = "1";
"B":   PN = "2"  !CDS_PN = "2";
BODY = "Q_CAP","I10": #LOCATION = "C775" !CDS_LOCATION = "C775" &SEC = "1" #&CDS_SEC = "1";
"A":   PN = "1"  !CDS_PN = "1";
"B":   PN = "2"  !CDS_PN = "2";
BODY = "Q_CAP","I12": #LOCATION = "C671" !CDS_LOCATION = "C671" &SEC = "1" #&CDS_SEC = "1";
"A":   PN = "1"  !CDS_PN = "1";
"B":   PN = "2"  !CDS_PN = "2";
BODY = "Q_CAP","I13": #LOCATION = "C670" !CDS_LOCATION = "C670" &SEC = "1" #&CDS_SEC = "1";
"A":   PN = "1"  !CDS_PN = "1";
"B":   PN = "2"  !CDS_PN = "2";
BODY = "Q_CAP","I15": #LOCATION = "C673" !CDS_LOCATION = "C673" &SEC = "1" #&CDS_SEC = "1";
"A":   PN = "1"  !CDS_PN = "1";
"B":   PN = "2"  !CDS_PN = "2";
BODY = "Q_CAP","I16": #LOCATION = "C677" !CDS_LOCATION = "C677" &SEC = "1" #&CDS_SEC = "1";
"A":   PN = "1"  !CDS_PN = "1";
"B":   PN = "2"  !CDS_PN = "2";
BODY = "Q_CAP","I17": #LOCATION = "C774" !CDS_LOCATION = "C774" &SEC = "1" #&CDS_SEC = "1";
"A":   PN = "1"  !CDS_PN = "1";
"B":   PN = "2"  !CDS_PN = "2";
BODY = "Q_CAP","I18": #LOCATION = "C776" !CDS_LOCATION = "C776" &SEC = "1" #&CDS_SEC = "1";
"A":   PN = "1"  !CDS_PN = "1";
"B":   PN = "2"  !CDS_PN = "2";
BODY = "Q_CAP","I19": #LOCATION = "C777" !CDS_LOCATION = "C777" &SEC = "1" #&CDS_SEC = "1";
"A":   PN = "1"  !CDS_PN = "1";
"B":   PN = "2"  !CDS_PN = "2";
BODY = "Q_CAP","I20": #LOCATION = "C778" !CDS_LOCATION = "C778" &SEC = "1" #&CDS_SEC = "1";
"A":   PN = "1"  !CDS_PN = "1";
"B":   PN = "2"  !CDS_PN = "2";
BODY = "Q_RES","I21": #LOCATION = "R1051" !CDS_LOCATION = "R1051" &SEC = "1" #&CDS_SEC = "1";
"A":   PN = "1"  !CDS_PN = "1";
"B":   PN = "2"  !CDS_PN = "2";
BODY = "Q_RES","I22": #LOCATION = "R1053" !CDS_LOCATION = "R1053" &SEC = "1" #&CDS_SEC = "1";
"A":   PN = "1"  !CDS_PN = "1";
"B":   PN = "2"  !CDS_PN = "2";
BODY = "Q_INDUCTOR","I23": #LOCATION = "L18" !CDS_LOCATION = "L18" &SEC = "1" #&CDS_SEC = "1";
"1":   PN = "1"  !CDS_PN = "1";
"2":   PN = "2"  !CDS_PN = "2";
BODY = "Q_CAP","I25": #LOCATION = "C665" !CDS_LOCATION = "C665" &SEC = "1" #&CDS_SEC = "1";
"A":   PN = "1"  !CDS_PN = "1";
"B":   PN = "2"  !CDS_PN = "2";
BODY = "Q_CAP","I26": #LOCATION = "C669" !CDS_LOCATION = "C669" &SEC = "1" #&CDS_SEC = "1";
"A":   PN = "1"  !CDS_PN = "1";
"B":   PN = "2"  !CDS_PN = "2";
BODY = "Q_CAP","I27": #LOCATION = "C667" !CDS_LOCATION = "C667" &SEC = "1" #&CDS_SEC = "1";
"A":   PN = "1"  !CDS_PN = "1";
"B":   PN = "2"  !CDS_PN = "2";
BODY = "Q_CAP","I29": #LOCATION = "C672" !CDS_LOCATION = "C672" &SEC = "1" #&CDS_SEC = "1";
"A":   PN = "1"  !CDS_PN = "1";
"B":   PN = "2"  !CDS_PN = "2";
BODY = "Q_INDUCTOR","I30": #LOCATION = "L21" !CDS_LOCATION = "L21" &SEC = "1" #&CDS_SEC = "1";
"1":   PN = "1"  !CDS_PN = "1";
"2":   PN = "2"  !CDS_PN = "2";
BODY = "Q_CAP","I34": #LOCATION = "C982" !CDS_LOCATION = "C982" &SEC = "1" #&CDS_SEC = "1";
"A":   PN = "1"  !CDS_PN = "1";
"B":   PN = "2"  !CDS_PN = "2";
BODY = "Q_CAP","I35": #LOCATION = "C984" !CDS_LOCATION = "C984" &SEC = "1" #&CDS_SEC = "1";
"A":   PN = "1"  !CDS_PN = "1";
"B":   PN = "2"  !CDS_PN = "2";
BODY = "Q_CAP","I36": #LOCATION = "C791" !CDS_LOCATION = "C791" &SEC = "1" #&CDS_SEC = "1";
"A":   PN = "1"  !CDS_PN = "1";
"B":   PN = "2"  !CDS_PN = "2";
BODY = "Q_CAP","I39": #LOCATION = "C794" !CDS_LOCATION = "C794" &SEC = "1" #&CDS_SEC = "1";
"A":   PN = "1"  !CDS_PN = "1";
"B":   PN = "2"  !CDS_PN = "2";
BODY = "Q_CAP","I40": #LOCATION = "C790" !CDS_LOCATION = "C790" &SEC = "1" #&CDS_SEC = "1";
"A":   PN = "1"  !CDS_PN = "1";
"B":   PN = "2"  !CDS_PN = "2";
BODY = "Q_CAP","I41": #LOCATION = "C987" !CDS_LOCATION = "C987" &SEC = "1" #&CDS_SEC = "1";
"A":   PN = "1"  !CDS_PN = "1";
"B":   PN = "2"  !CDS_PN = "2";
BODY = "Q_CAP","I42": #LOCATION = "C800" !CDS_LOCATION = "C800" &SEC = "1" #&CDS_SEC = "1";
"A":   PN = "1"  !CDS_PN = "1";
"B":   PN = "2"  !CDS_PN = "2";
BODY = "Q_CAP","I43": #LOCATION = "C784" !CDS_LOCATION = "C784" &SEC = "1" #&CDS_SEC = "1";
"A":   PN = "1"  !CDS_PN = "1";
"B":   PN = "2"  !CDS_PN = "2";
BODY = "Q_CAP","I44": #LOCATION = "C797" !CDS_LOCATION = "C797" &SEC = "1" #&CDS_SEC = "1";
"A":   PN = "1"  !CDS_PN = "1";
"B":   PN = "2"  !CDS_PN = "2";
BODY = "Q_CAP","I45": #LOCATION = "C781" !CDS_LOCATION = "C781" &SEC = "1" #&CDS_SEC = "1";
"A":   PN = "1"  !CDS_PN = "1";
"B":   PN = "2"  !CDS_PN = "2";
BODY = "Q_CAP","I46": #LOCATION = "C788" !CDS_LOCATION = "C788" &SEC = "1" #&CDS_SEC = "1";
"A":   PN = "1"  !CDS_PN = "1";
"B":   PN = "2"  !CDS_PN = "2";
BODY = "Q_CAP","I47": #LOCATION = "C796" !CDS_LOCATION = "C796" &SEC = "1" #&CDS_SEC = "1";
"A":   PN = "1"  !CDS_PN = "1";
"B":   PN = "2"  !CDS_PN = "2";
BODY = "Q_CAP","I48": #LOCATION = "C795" !CDS_LOCATION = "C795" &SEC = "1" #&CDS_SEC = "1";
"A":   PN = "1"  !CDS_PN = "1";
"B":   PN = "2"  !CDS_PN = "2";
BODY = "Q_CAP","I49": #LOCATION = "C981" !CDS_LOCATION = "C981" &SEC = "1" #&CDS_SEC = "1";
"A":   PN = "1"  !CDS_PN = "1";
"B":   PN = "2"  !CDS_PN = "2";
BODY = "Q_CAP","I50": #LOCATION = "C798" !CDS_LOCATION = "C798" &SEC = "1" #&CDS_SEC = "1";
"A":   PN = "1"  !CDS_PN = "1";
"B":   PN = "2"  !CDS_PN = "2";
BODY = "Q_CAP","I51": #LOCATION = "C802" !CDS_LOCATION = "C802" &SEC = "1" #&CDS_SEC = "1";
"A":   PN = "1"  !CDS_PN = "1";
"B":   PN = "2"  !CDS_PN = "2";
BODY = "Q_CAP","I52": #LOCATION = "C792" !CDS_LOCATION = "C792" &SEC = "1" #&CDS_SEC = "1";
"A":   PN = "1"  !CDS_PN = "1";
"B":   PN = "2"  !CDS_PN = "2";
BODY = "Q_CAP","I54": #LOCATION = "C975" !CDS_LOCATION = "C975" &SEC = "1" #&CDS_SEC = "1";
"A":   PN = "1"  !CDS_PN = "1";
"B":   PN = "2"  !CDS_PN = "2";
BODY = "Q_CAP","I55": #LOCATION = "C979" !CDS_LOCATION = "C979" &SEC = "1" #&CDS_SEC = "1";
"A":   PN = "1"  !CDS_PN = "1";
"B":   PN = "2"  !CDS_PN = "2";
BODY = "Q_CAP","I56": #LOCATION = "C967" !CDS_LOCATION = "C967" &SEC = "1" #&CDS_SEC = "1";
"A":   PN = "1"  !CDS_PN = "1";
"B":   PN = "2"  !CDS_PN = "2";
BODY = "Q_CAP","I57": #LOCATION = "C970" !CDS_LOCATION = "C970" &SEC = "1" #&CDS_SEC = "1";
"A":   PN = "1"  !CDS_PN = "1";
"B":   PN = "2"  !CDS_PN = "2";
BODY = "Q_CAP","I58": #LOCATION = "C966" !CDS_LOCATION = "C966" &SEC = "1" #&CDS_SEC = "1";
"A":   PN = "1"  !CDS_PN = "1";
"B":   PN = "2"  !CDS_PN = "2";
BODY = "Q_CAP","I59": #LOCATION = "C969" !CDS_LOCATION = "C969" &SEC = "1" #&CDS_SEC = "1";
"A":   PN = "1"  !CDS_PN = "1";
"B":   PN = "2"  !CDS_PN = "2";
BODY = "Q_CAP","I60": #LOCATION = "C977" !CDS_LOCATION = "C977" &SEC = "1" #&CDS_SEC = "1";
"A":   PN = "1"  !CDS_PN = "1";
"B":   PN = "2"  !CDS_PN = "2";
BODY = "Q_CAP","I61": #LOCATION = "C978" !CDS_LOCATION = "C978" &SEC = "1" #&CDS_SEC = "1";
"A":   PN = "1"  !CDS_PN = "1";
"B":   PN = "2"  !CDS_PN = "2";
BODY = "Q_CAP","I62": #LOCATION = "C783" !CDS_LOCATION = "C783" &SEC = "1" #&CDS_SEC = "1";
"A":   PN = "1"  !CDS_PN = "1";
"B":   PN = "2"  !CDS_PN = "2";
BODY = "Q_CAP","I63": #LOCATION = "C988" !CDS_LOCATION = "C988" &SEC = "1" #&CDS_SEC = "1";
"A":   PN = "1"  !CDS_PN = "1";
"B":   PN = "2"  !CDS_PN = "2";
BODY = "Q_CAP","I64": #LOCATION = "C974" !CDS_LOCATION = "C974" &SEC = "1" #&CDS_SEC = "1";
"A":   PN = "1"  !CDS_PN = "1";
"B":   PN = "2"  !CDS_PN = "2";
BODY = "Q_CAP","I65": #LOCATION = "C799" !CDS_LOCATION = "C799" &SEC = "1" #&CDS_SEC = "1";
"A":   PN = "1"  !CDS_PN = "1";
"B":   PN = "2"  !CDS_PN = "2";
BODY = "Q_CAP","I66": #LOCATION = "C983" !CDS_LOCATION = "C983" &SEC = "1" #&CDS_SEC = "1";
"A":   PN = "1"  !CDS_PN = "1";
"B":   PN = "2"  !CDS_PN = "2";
BODY = "Q_CAP","I68": #LOCATION = "C804" !CDS_LOCATION = "C804" &SEC = "1" #&CDS_SEC = "1";
"A":   PN = "1"  !CDS_PN = "1";
"B":   PN = "2"  !CDS_PN = "2";
BODY = "Q_CAP","I69": #LOCATION = "C968" !CDS_LOCATION = "C968" &SEC = "1" #&CDS_SEC = "1";
"A":   PN = "1"  !CDS_PN = "1";
"B":   PN = "2"  !CDS_PN = "2";
BODY = "Q_CAP","I72": #LOCATION = "C786" !CDS_LOCATION = "C786" &SEC = "1" #&CDS_SEC = "1";
"A":   PN = "1"  !CDS_PN = "1";
"B":   PN = "2"  !CDS_PN = "2";
BODY = "Q_CAP","I73": #LOCATION = "C779" !CDS_LOCATION = "C779" &SEC = "1" #&CDS_SEC = "1";
"A":   PN = "1"  !CDS_PN = "1";
"B":   PN = "2"  !CDS_PN = "2";
BODY = "Q_CAP","I74": #LOCATION = "C986" !CDS_LOCATION = "C986" &SEC = "1" #&CDS_SEC = "1";
"A":   PN = "1"  !CDS_PN = "1";
"B":   PN = "2"  !CDS_PN = "2";
BODY = "Q_CAP","I75": #LOCATION = "C973" !CDS_LOCATION = "C973" &SEC = "1" #&CDS_SEC = "1";
"A":   PN = "1"  !CDS_PN = "1";
"B":   PN = "2"  !CDS_PN = "2";
BODY = "Q_CAP","I77": #LOCATION = "C801" !CDS_LOCATION = "C801" &SEC = "1" #&CDS_SEC = "1";
"A":   PN = "1"  !CDS_PN = "1";
"B":   PN = "2"  !CDS_PN = "2";
BODY = "Q_CAP","I78": #LOCATION = "C805" !CDS_LOCATION = "C805" &SEC = "1" #&CDS_SEC = "1";
"A":   PN = "1"  !CDS_PN = "1";
"B":   PN = "2"  !CDS_PN = "2";
BODY = "Q_CAP","I79": #LOCATION = "C971" !CDS_LOCATION = "C971" &SEC = "1" #&CDS_SEC = "1";
"A":   PN = "1"  !CDS_PN = "1";
"B":   PN = "2"  !CDS_PN = "2";
BODY = "Q_CAP","I80": #LOCATION = "C976" !CDS_LOCATION = "C976" &SEC = "1" #&CDS_SEC = "1";
"A":   PN = "1"  !CDS_PN = "1";
"B":   PN = "2"  !CDS_PN = "2";
BODY = "Q_CAP","I81": #LOCATION = "C980" !CDS_LOCATION = "C980" &SEC = "1" #&CDS_SEC = "1";
"A":   PN = "1"  !CDS_PN = "1";
"B":   PN = "2"  !CDS_PN = "2";
BODY = "Q_CAP","I82": #LOCATION = "C780" !CDS_LOCATION = "C780" &SEC = "1" #&CDS_SEC = "1";
"A":   PN = "1"  !CDS_PN = "1";
"B":   PN = "2"  !CDS_PN = "2";
BODY = "Q_CAP","I83": #LOCATION = "C782" !CDS_LOCATION = "C782" &SEC = "1" #&CDS_SEC = "1";
"A":   PN = "1"  !CDS_PN = "1";
"B":   PN = "2"  !CDS_PN = "2";
BODY = "Q_CAP","I84": #LOCATION = "C785" !CDS_LOCATION = "C785" &SEC = "1" #&CDS_SEC = "1";
"A":   PN = "1"  !CDS_PN = "1";
"B":   PN = "2"  !CDS_PN = "2";
BODY = "Q_CAP","I86": #LOCATION = "C789" !CDS_LOCATION = "C789" &SEC = "1" #&CDS_SEC = "1";
"A":   PN = "1"  !CDS_PN = "1";
"B":   PN = "2"  !CDS_PN = "2";
BODY = "Q_CAP","I87": #LOCATION = "C803" !CDS_LOCATION = "C803" &SEC = "1" #&CDS_SEC = "1";
"A":   PN = "1"  !CDS_PN = "1";
"B":   PN = "2"  !CDS_PN = "2";
BODY = "Q_INDUCTOR","I88": #LOCATION = "L29" !CDS_LOCATION = "L29" &SEC = "1" #&CDS_SEC = "1";
"1":   PN = "1"  !CDS_PN = "1";
"2":   PN = "2"  !CDS_PN = "2";
BODY = "Q_RES","I89": #LOCATION = "R1050" !CDS_LOCATION = "R1050" &SEC = "1" #&CDS_SEC = "1";
"A":   PN = "1"  !CDS_PN = "1";
"B":   PN = "2"  !CDS_PN = "2";
BODY = "Q_CAP","I90": #LOCATION = "C787" !CDS_LOCATION = "C787" &SEC = "1" #&CDS_SEC = "1";
"A":   PN = "1"  !CDS_PN = "1";
"B":   PN = "2"  !CDS_PN = "2";
BODY = "Q_CAP","I91": #LOCATION = "C793" !CDS_LOCATION = "C793" &SEC = "1" #&CDS_SEC = "1";
"A":   PN = "1"  !CDS_PN = "1";
"B":   PN = "2"  !CDS_PN = "2";
BODY = "Q_CAP","I92": #LOCATION = "C972" !CDS_LOCATION = "C972" &SEC = "1" #&CDS_SEC = "1";
"A":   PN = "1"  !CDS_PN = "1";
"B":   PN = "2"  !CDS_PN = "2";
BODY = "Q_CAP","I93": #LOCATION = "C985" !CDS_LOCATION = "C985" &SEC = "1" #&CDS_SEC = "1";
"A":   PN = "1"  !CDS_PN = "1";
"B":   PN = "2"  !CDS_PN = "2";
BODY = "Q_CAPP","I94": #LOCATION = "C7014" !CDS_LOCATION = "C7014" &SEC = "1" #&CDS_SEC = "1";
"A":   PN = "1"  !CDS_PN = "1";
"B":   PN = "2"  !CDS_PN = "2";
BODY = "Q_CAPP","I95": #LOCATION = "C7015" !CDS_LOCATION = "C7015" &SEC = "1" #&CDS_SEC = "1";
"A":   PN = "1"  !CDS_PN = "1";
"B":   PN = "2"  !CDS_PN = "2";
BODY = "Q_CAP","I96": #LOCATION = "C7016" !CDS_LOCATION = "C7016" &SEC = "1" #&CDS_SEC = "1";
"A":   PN = "1"  !CDS_PN = "1";
"B":   PN = "2"  !CDS_PN = "2";
DRAWING = "@t6g_mb_lib.t6g(sch_1):page431";
BODY = "PT5161LRS","I6": #LOCATION = "U6013" !CDS_LOCATION = "U6013" &SEC = "4" #&CDS_SEC = "4";
"PWR_1A_1":   PN = "BV20"  !CDS_PN = "BV20";
"PWR_1A_2":   PN = "CE17"  !CDS_PN = "CE17";
"PWR_1A_3":   PN = "CE20"  !CDS_PN = "CE20";
"PWR_1A_4":   PN = "CM17"  !CDS_PN = "CM17";
"PWR_1A_5":   PN = "CM20"  !CDS_PN = "CM20";
"PWR_1D":   PN = "BV17"  !CDS_PN = "BV17";
"PWR_2A_1":   PN = "AC17"  !CDS_PN = "AC17";
"PWR_2A_2":   PN = "AC20"  !CDS_PN = "AC20";
"PWR_2A_3":   PN = "AK17"  !CDS_PN = "AK17";
"PWR_2A_4":   PN = "AK20"  !CDS_PN = "AK20";
"PWR_2A_5":   PN = "AU17"  !CDS_PN = "AU17";
"PWR_2A_6":   PN = "AU20"  !CDS_PN = "AU20";
"PWR_2A_7":   PN = "BD17"  !CDS_PN = "BD17";
"PWR_2A_8":   PN = "BD20"  !CDS_PN = "BD20";
"PWR_2A_9":   PN = "DF17"  !CDS_PN = "DF17";
"PWR_2A_10":   PN = "DF20"  !CDS_PN = "DF20";
"PWR_2A_11":   PN = "DN17"  !CDS_PN = "DN17";
"PWR_2A_12":   PN = "DN20"  !CDS_PN = "DN20";
"PWR_2A_13":   PN = "DY17"  !CDS_PN = "DY17";
"PWR_2A_14":   PN = "DY20"  !CDS_PN = "DY20";
"PWR_2A_15":   PN = "EG17"  !CDS_PN = "EG17";
"PWR_2A_16":   PN = "EG20"  !CDS_PN = "EG20";
"PWR_2A_17":   PN = "EP17"  !CDS_PN = "EP17";
"PWR_2A_18":   PN = "EP20"  !CDS_PN = "EP20";
"PWR_2A_19":   PN = "T17"  !CDS_PN = "T17";
"PWR_2A_20":   PN = "T20"  !CDS_PN = "T20";
"PWR_2D_1":   PN = "BL17"  !CDS_PN = "BL17";
"PWR_2D_2":   PN = "BL20"  !CDS_PN = "BL20";
"PWR_2D_3":   PN = "CW17"  !CDS_PN = "CW17";
"PWR_2D_4":   PN = "CW20"  !CDS_PN = "CW20";
"VQPS":   PN = "G1"  !CDS_PN = "G1";
BODY = "Q_RES","I13": #LOCATION = "R1125" !CDS_LOCATION = "R1125" &SEC = "1" #&CDS_SEC = "1";
"A":   PN = "1"  !CDS_PN = "1";
"B":   PN = "2"  !CDS_PN = "2";
BODY = "Q_RES","I14": #LOCATION = "R1126" !CDS_LOCATION = "R1126" &SEC = "1" #&CDS_SEC = "1";
"A":   PN = "1"  !CDS_PN = "1";
"B":   PN = "2"  !CDS_PN = "2";
BODY = "PT5161LRS","I17": #LOCATION = "U6013" !CDS_LOCATION = "U6013" &SEC = "5" #&CDS_SEC = "5";
"GND1":   PN = "AC13"  !CDS_PN = "AC13";
"GND2":   PN = "AC22"  !CDS_PN = "AC22";
"GND3":   PN = "AC32"  !CDS_PN = "AC32";
"GND4":   PN = "AC4"  !CDS_PN = "AC4";
"GND5":   PN = "AD2"  !CDS_PN = "AD2";
"GND6":   PN = "AD34"  !CDS_PN = "AD34";
"GND7":   PN = "AE1"  !CDS_PN = "AE1";
"GND8":   PN = "AE35"  !CDS_PN = "AE35";
"GND9":   PN = "AK13"  !CDS_PN = "AK13";
"GND10":   PN = "AK22"  !CDS_PN = "AK22";
"GND11":   PN = "AK32"  !CDS_PN = "AK32";
"GND12":   PN = "AK4"  !CDS_PN = "AK4";
"GND13":   PN = "AL2"  !CDS_PN = "AL2";
"GND14":   PN = "AL34"  !CDS_PN = "AL34";
"GND15":   PN = "AM1"  !CDS_PN = "AM1";
"GND16":   PN = "AM35"  !CDS_PN = "AM35";
"GND17":   PN = "AU13"  !CDS_PN = "AU13";
"GND18":   PN = "AU22"  !CDS_PN = "AU22";
"GND19":   PN = "AU32"  !CDS_PN = "AU32";
"GND20":   PN = "AU4"  !CDS_PN = "AU4";
"GND21":   PN = "AV2"  !CDS_PN = "AV2";
"GND22":   PN = "AV34"  !CDS_PN = "AV34";
"GND23":   PN = "AW1"  !CDS_PN = "AW1";
"GND24":   PN = "AW35"  !CDS_PN = "AW35";
"GND25":   PN = "B19"  !CDS_PN = "B19";
"GND26":   PN = "BD13"  !CDS_PN = "BD13";
"GND27":   PN = "BD22"  !CDS_PN = "BD22";
"GND28":   PN = "BD32"  !CDS_PN = "BD32";
"GND29":   PN = "BD4"  !CDS_PN = "BD4";
"GND30":   PN = "BE2"  !CDS_PN = "BE2";
"GND31":   PN = "BE34"  !CDS_PN = "BE34";
"GND32":   PN = "BF1"  !CDS_PN = "BF1";
"GND33":   PN = "BF35"  !CDS_PN = "BF35";
"GND34":   PN = "BL13"  !CDS_PN = "BL13";
"GND35":   PN = "BL22"  !CDS_PN = "BL22";
"GND36":   PN = "BL32"  !CDS_PN = "BL32";
"GND37":   PN = "BL4"  !CDS_PN = "BL4";
"GND38":   PN = "BM2"  !CDS_PN = "BM2";
"GND39":   PN = "BM34"  !CDS_PN = "BM34";
"GND40":   PN = "BN1"  !CDS_PN = "BN1";
"GND41":   PN = "BN35"  !CDS_PN = "BN35";
"GND42":   PN = "BV13"  !CDS_PN = "BV13";
"GND43":   PN = "BV22"  !CDS_PN = "BV22";
"GND44":   PN = "BV32"  !CDS_PN = "BV32";
"GND45":   PN = "BV4"  !CDS_PN = "BV4";
"GND46":   PN = "BW2"  !CDS_PN = "BW2";
"GND47":   PN = "BW34"  !CDS_PN = "BW34";
"GND48":   PN = "BY1"  !CDS_PN = "BY1";
"GND49":   PN = "BY35"  !CDS_PN = "BY35";
"GND50":   PN = "CE13"  !CDS_PN = "CE13";
"GND51":   PN = "CE22"  !CDS_PN = "CE22";
"GND52":   PN = "CE32"  !CDS_PN = "CE32";
"GND53":   PN = "CE4"  !CDS_PN = "CE4";
"GND54":   PN = "CF2"  !CDS_PN = "CF2";
"GND55":   PN = "CF34"  !CDS_PN = "CF34";
"GND56":   PN = "CG1"  !CDS_PN = "CG1";
"GND57":   PN = "CG35"  !CDS_PN = "CG35";
"GND58":   PN = "CM13"  !CDS_PN = "CM13";
"GND59":   PN = "CM22"  !CDS_PN = "CM22";
"GND60":   PN = "CM32"  !CDS_PN = "CM32";
"GND61":   PN = "CM4"  !CDS_PN = "CM4";
"GND62":   PN = "CN2"  !CDS_PN = "CN2";
"GND63":   PN = "CN34"  !CDS_PN = "CN34";
"GND64":   PN = "CP1"  !CDS_PN = "CP1";
"GND65":   PN = "CP35"  !CDS_PN = "CP35";
"GND66":   PN = "CW13"  !CDS_PN = "CW13";
"GND67":   PN = "CW22"  !CDS_PN = "CW22";
"GND68":   PN = "CW32"  !CDS_PN = "CW32";
"GND69":   PN = "CW4"  !CDS_PN = "CW4";
"GND70":   PN = "CY2"  !CDS_PN = "CY2";
"GND71":   PN = "CY34"  !CDS_PN = "CY34";
"GND72":   PN = "DA1"  !CDS_PN = "DA1";
"GND73":   PN = "DA35"  !CDS_PN = "DA35";
"GND74":   PN = "DF13"  !CDS_PN = "DF13";
"GND75":   PN = "DF22"  !CDS_PN = "DF22";
"GND76":   PN = "DF32"  !CDS_PN = "DF32";
"GND77":   PN = "DF4"  !CDS_PN = "DF4";
"GND78":   PN = "DG2"  !CDS_PN = "DG2";
"GND79":   PN = "DG34"  !CDS_PN = "DG34";
"GND80":   PN = "DH1"  !CDS_PN = "DH1";
"GND81":   PN = "DH35"  !CDS_PN = "DH35";
"GND82":   PN = "DN13"  !CDS_PN = "DN13";
"GND83":   PN = "DN22"  !CDS_PN = "DN22";
"GND84":   PN = "DN32"  !CDS_PN = "DN32";
"GND85":   PN = "DN4"  !CDS_PN = "DN4";
"GND86":   PN = "DP2"  !CDS_PN = "DP2";
"GND87":   PN = "DP34"  !CDS_PN = "DP34";
"GND88":   PN = "DR1"  !CDS_PN = "DR1";
"GND89":   PN = "DR35"  !CDS_PN = "DR35";
"GND90":   PN = "DY13"  !CDS_PN = "DY13";
"GND91":   PN = "DY22"  !CDS_PN = "DY22";
"GND92":   PN = "DY32"  !CDS_PN = "DY32";
"GND93":   PN = "DY4"  !CDS_PN = "DY4";
"GND94":   PN = "E14"  !CDS_PN = "E14";
"GND95":   PN = "E27"  !CDS_PN = "E27";
"GND96":   PN = "E33"  !CDS_PN = "E33";
"GND97":   PN = "EA2"  !CDS_PN = "EA2";
"GND98":   PN = "EA34"  !CDS_PN = "EA34";
"GND99":   PN = "EB1"  !CDS_PN = "EB1";
"GND100":   PN = "EB35"  !CDS_PN = "EB35";
"GND101":   PN = "EG13"  !CDS_PN = "EG13";
"GND102":   PN = "EG22"  !CDS_PN = "EG22";
"GND103":   PN = "EG32"  !CDS_PN = "EG32";
"GND104":   PN = "EG4"  !CDS_PN = "EG4";
"GND105":   PN = "EH2"  !CDS_PN = "EH2";
"GND106":   PN = "EH34"  !CDS_PN = "EH34";
"GND107":   PN = "EJ1"  !CDS_PN = "EJ1";
"GND108":   PN = "EJ35"  !CDS_PN = "EJ35";
"GND109":   PN = "EP13"  !CDS_PN = "EP13";
"GND110":   PN = "EP22"  !CDS_PN = "EP22";
"GND111":   PN = "EP32"  !CDS_PN = "EP32";
"GND112":   PN = "EP4"  !CDS_PN = "EP4";
"GND113":   PN = "ER2"  !CDS_PN = "ER2";
"GND114":   PN = "ER34"  !CDS_PN = "ER34";
"GND115":   PN = "ET1"  !CDS_PN = "ET1";
"GND116":   PN = "ET35"  !CDS_PN = "ET35";
"GND117":   PN = "FA15"  !CDS_PN = "FA15";
"GND118":   PN = "FA32"  !CDS_PN = "FA32";
"GND119":   PN = "FB2"  !CDS_PN = "FB2";
"GND120":   PN = "FB34"  !CDS_PN = "FB34";
"GND121":   PN = "FC19"  !CDS_PN = "FC19";
"GND122":   PN = "FC23"  !CDS_PN = "FC23";
"GND123":   PN = "FC25"  !CDS_PN = "FC25";
"GND124":   PN = "FC28"  !CDS_PN = "FC28";
"GND125":   PN = "FC3"  !CDS_PN = "FC3";
"GND126":   PN = "FC6"  !CDS_PN = "FC6";
"GND127":   PN = "FC9"  !CDS_PN = "FC9";
"GND128":   PN = "FD1"  !CDS_PN = "FD1";
"GND129":   PN = "FD35"  !CDS_PN = "FD35";
"GND130":   PN = "FF14"  !CDS_PN = "FF14";
"GND131":   PN = "FF21"  !CDS_PN = "FF21";
"GND132":   PN = "FJ12"  !CDS_PN = "FJ12";
"GND133":   PN = "FJ19"  !CDS_PN = "FJ19";
"GND134":   PN = "H12"  !CDS_PN = "H12";
"GND135":   PN = "H16"  !CDS_PN = "H16";
"GND136":   PN = "H19"  !CDS_PN = "H19";
"GND137":   PN = "H31"  !CDS_PN = "H31";
"GND138":   PN = "J22"  !CDS_PN = "J22";
"GND139":   PN = "J4"  !CDS_PN = "J4";
"GND140":   PN = "K2"  !CDS_PN = "K2";
"GND141":   PN = "K34"  !CDS_PN = "K34";
"GND142":   PN = "L1"  !CDS_PN = "L1";
"GND143":   PN = "L35"  !CDS_PN = "L35";
"GND144":   PN = "T13"  !CDS_PN = "T13";
"GND145":   PN = "T22"  !CDS_PN = "T22";
"GND146":   PN = "T32"  !CDS_PN = "T32";
"GND147":   PN = "T4"  !CDS_PN = "T4";
"GND148":   PN = "U2"  !CDS_PN = "U2";
"GND149":   PN = "U34"  !CDS_PN = "U34";
"GND150":   PN = "V1"  !CDS_PN = "V1";
"GND151":   PN = "V35"  !CDS_PN = "V35";
"NCF_GND1":   PN = "A1"  !CDS_PN = "A1";
"NCF_GND2":   PN = "A35"  !CDS_PN = "A35";
"NCF_GND3":   PN = "C2"  !CDS_PN = "C2";
"NCF_GND4":   PN = "C34"  !CDS_PN = "C34";
"NCF_GND5":   PN = "D1"  !CDS_PN = "D1";
"NCF_GND6":   PN = "D35"  !CDS_PN = "D35";
"NCF_GND7":   PN = "FE2"  !CDS_PN = "FE2";
"NCF_GND8":   PN = "FE34"  !CDS_PN = "FE34";
"NCF_GND9":   PN = "FG1"  !CDS_PN = "FG1";
"NCF_GND10":   PN = "FG35"  !CDS_PN = "FG35";
"NCF_GND11":   PN = "FH2"  !CDS_PN = "FH2";
"NCF_GND12":   PN = "FH34"  !CDS_PN = "FH34";
BODY = "Q_RES","I18": #LOCATION = "R1124" !CDS_LOCATION = "R1124" &SEC = "1" #&CDS_SEC = "1";
"A":   PN = "1"  !CDS_PN = "1";
"B":   PN = "2"  !CDS_PN = "2";
BODY = "Q_RES","I19": #LOCATION = "R1123" !CDS_LOCATION = "R1123" &SEC = "1" #&CDS_SEC = "1";
"A":   PN = "1"  !CDS_PN = "1";
"B":   PN = "2"  !CDS_PN = "2";
DRAWING = "@t6g_mb_lib.t6g(sch_1):page433";
BODY = "Q_RES","I1": #LOCATION = "R1087" !CDS_LOCATION = "R1087" #SEC = "1" !CDS_SEC = "1";
"A":   PN = "1"  !CDS_PN = "1";
"B":   PN = "2"  !CDS_PN = "2";
BODY = "Q_RES","I2": #LOCATION = "R1086" !CDS_LOCATION = "R1086" #SEC = "1" !CDS_SEC = "1";
"A":   PN = "1"  !CDS_PN = "1";
"B":   PN = "2"  !CDS_PN = "2";
BODY = "Q_CAP","I5": #LOCATION = "C999" !CDS_LOCATION = "C999" &SEC = "1" #&CDS_SEC = "1";
"A":   PN = "1"  !CDS_PN = "1";
"B":   PN = "2"  !CDS_PN = "2";
BODY = "Q_CAP","I6": #LOCATION = "C1002" !CDS_LOCATION = "C1002" &SEC = "1" #&CDS_SEC = "1";
"A":   PN = "1"  !CDS_PN = "1";
"B":   PN = "2"  !CDS_PN = "2";
BODY = "Q_RES","I7": #LOCATION = "R1094" !CDS_LOCATION = "R1094" &SEC = "1" #&CDS_SEC = "1";
"A":   PN = "1"  !CDS_PN = "1";
"B":   PN = "2"  !CDS_PN = "2";
BODY = "Q_INDUCTOR","I10": #LOCATION = "L22" !CDS_LOCATION = "L22" &SEC = "1" #&CDS_SEC = "1";
"1":   PN = "1"  !CDS_PN = "1";
"2":   PN = "2"  !CDS_PN = "2";
BODY = "Q_CAP","I12": #LOCATION = "C991" !CDS_LOCATION = "C991" &SEC = "1" #&CDS_SEC = "1";
"A":   PN = "1"  !CDS_PN = "1";
"B":   PN = "2"  !CDS_PN = "2";
BODY = "Q_CAP","I13": #LOCATION = "C993" !CDS_LOCATION = "C993" &SEC = "1" #&CDS_SEC = "1";
"A":   PN = "1"  !CDS_PN = "1";
"B":   PN = "2"  !CDS_PN = "2";
BODY = "Q_CAP","I15": #LOCATION = "C995" !CDS_LOCATION = "C995" &SEC = "1" #&CDS_SEC = "1";
"A":   PN = "1"  !CDS_PN = "1";
"B":   PN = "2"  !CDS_PN = "2";
BODY = "Q_CAP","I16": #LOCATION = "C996" !CDS_LOCATION = "C996" &SEC = "1" #&CDS_SEC = "1";
"A":   PN = "1"  !CDS_PN = "1";
"B":   PN = "2"  !CDS_PN = "2";
BODY = "Q_CAP","I17": #LOCATION = "C998" !CDS_LOCATION = "C998" &SEC = "1" #&CDS_SEC = "1";
"A":   PN = "1"  !CDS_PN = "1";
"B":   PN = "2"  !CDS_PN = "2";
BODY = "Q_CAP","I19": #LOCATION = "C990" !CDS_LOCATION = "C990" &SEC = "1" #&CDS_SEC = "1";
"A":   PN = "1"  !CDS_PN = "1";
"B":   PN = "2"  !CDS_PN = "2";
BODY = "Q_CAP","I20": #LOCATION = "C992" !CDS_LOCATION = "C992" &SEC = "1" #&CDS_SEC = "1";
"A":   PN = "1"  !CDS_PN = "1";
"B":   PN = "2"  !CDS_PN = "2";
BODY = "Q_CAP","I21": #LOCATION = "C994" !CDS_LOCATION = "C994" &SEC = "1" #&CDS_SEC = "1";
"A":   PN = "1"  !CDS_PN = "1";
"B":   PN = "2"  !CDS_PN = "2";
BODY = "Q_CAP","I22": #LOCATION = "C997" !CDS_LOCATION = "C997" &SEC = "1" #&CDS_SEC = "1";
"A":   PN = "1"  !CDS_PN = "1";
"B":   PN = "2"  !CDS_PN = "2";
BODY = "Q_CAP","I24": #LOCATION = "C1000" !CDS_LOCATION = "C1000" &SEC = "1" #&CDS_SEC = "1";
"A":   PN = "1"  !CDS_PN = "1";
"B":   PN = "2"  !CDS_PN = "2";
BODY = "Q_CAP","I25": #LOCATION = "C1001" !CDS_LOCATION = "C1001" &SEC = "1" #&CDS_SEC = "1";
"A":   PN = "1"  !CDS_PN = "1";
"B":   PN = "2"  !CDS_PN = "2";
BODY = "Q_CAP","I26": #LOCATION = "C1003" !CDS_LOCATION = "C1003" &SEC = "1" #&CDS_SEC = "1";
"A":   PN = "1"  !CDS_PN = "1";
"B":   PN = "2"  !CDS_PN = "2";
BODY = "Q_CAP","I27": #LOCATION = "C1004" !CDS_LOCATION = "C1004" &SEC = "1" #&CDS_SEC = "1";
"A":   PN = "1"  !CDS_PN = "1";
"B":   PN = "2"  !CDS_PN = "2";
BODY = "Q_CAP","I28": #LOCATION = "C1005" !CDS_LOCATION = "C1005" &SEC = "1" #&CDS_SEC = "1";
"A":   PN = "1"  !CDS_PN = "1";
"B":   PN = "2"  !CDS_PN = "2";
BODY = "Q_CAP","I30": #LOCATION = "C1014" !CDS_LOCATION = "C1014" &SEC = "1" #&CDS_SEC = "1";
"A":   PN = "1"  !CDS_PN = "1";
"B":   PN = "2"  !CDS_PN = "2";
BODY = "Q_CAP","I35": #LOCATION = "C1021" !CDS_LOCATION = "C1021" &SEC = "1" #&CDS_SEC = "1";
"A":   PN = "1"  !CDS_PN = "1";
"B":   PN = "2"  !CDS_PN = "2";
BODY = "Q_RES","I36": #LOCATION = "R1095" !CDS_LOCATION = "R1095" &SEC = "1" #&CDS_SEC = "1";
"A":   PN = "1"  !CDS_PN = "1";
"B":   PN = "2"  !CDS_PN = "2";
BODY = "Q_CAP","I37": #LOCATION = "C1024" !CDS_LOCATION = "C1024" &SEC = "1" #&CDS_SEC = "1";
"A":   PN = "1"  !CDS_PN = "1";
"B":   PN = "2"  !CDS_PN = "2";
BODY = "Q_CAP","I38": #LOCATION = "C1027" !CDS_LOCATION = "C1027" &SEC = "1" #&CDS_SEC = "1";
"A":   PN = "1"  !CDS_PN = "1";
"B":   PN = "2"  !CDS_PN = "2";
BODY = "Q_CAP","I39": #LOCATION = "C1023" !CDS_LOCATION = "C1023" &SEC = "1" #&CDS_SEC = "1";
"A":   PN = "1"  !CDS_PN = "1";
"B":   PN = "2"  !CDS_PN = "2";
BODY = "Q_CAP","I40": #LOCATION = "C1036" !CDS_LOCATION = "C1036" &SEC = "1" #&CDS_SEC = "1";
"A":   PN = "1"  !CDS_PN = "1";
"B":   PN = "2"  !CDS_PN = "2";
BODY = "Q_CAP","I41": #LOCATION = "C1010" !CDS_LOCATION = "C1010" &SEC = "1" #&CDS_SEC = "1";
"A":   PN = "1"  !CDS_PN = "1";
"B":   PN = "2"  !CDS_PN = "2";
BODY = "Q_CAP","I42": #LOCATION = "C1052" !CDS_LOCATION = "C1052" &SEC = "1" #&CDS_SEC = "1";
"A":   PN = "1"  !CDS_PN = "1";
"B":   PN = "2"  !CDS_PN = "2";
BODY = "Q_CAP","I43": #LOCATION = "C1055" !CDS_LOCATION = "C1055" &SEC = "1" #&CDS_SEC = "1";
"A":   PN = "1"  !CDS_PN = "1";
"B":   PN = "2"  !CDS_PN = "2";
BODY = "Q_CAP","I44": #LOCATION = "C1035" !CDS_LOCATION = "C1035" &SEC = "1" #&CDS_SEC = "1";
"A":   PN = "1"  !CDS_PN = "1";
"B":   PN = "2"  !CDS_PN = "2";
BODY = "Q_CAP","I45": #LOCATION = "C1031" !CDS_LOCATION = "C1031" &SEC = "1" #&CDS_SEC = "1";
"A":   PN = "1"  !CDS_PN = "1";
"B":   PN = "2"  !CDS_PN = "2";
BODY = "Q_CAP","I46": #LOCATION = "C1006" !CDS_LOCATION = "C1006" &SEC = "1" #&CDS_SEC = "1";
"A":   PN = "1"  !CDS_PN = "1";
"B":   PN = "2"  !CDS_PN = "2";
BODY = "Q_CAP","I47": #LOCATION = "C1034" !CDS_LOCATION = "C1034" &SEC = "1" #&CDS_SEC = "1";
"A":   PN = "1"  !CDS_PN = "1";
"B":   PN = "2"  !CDS_PN = "2";
BODY = "Q_CAP","I48": #LOCATION = "C1039" !CDS_LOCATION = "C1039" &SEC = "1" #&CDS_SEC = "1";
"A":   PN = "1"  !CDS_PN = "1";
"B":   PN = "2"  !CDS_PN = "2";
BODY = "Q_CAP","I49": #LOCATION = "C1015" !CDS_LOCATION = "C1015" &SEC = "1" #&CDS_SEC = "1";
"A":   PN = "1"  !CDS_PN = "1";
"B":   PN = "2"  !CDS_PN = "2";
BODY = "Q_CAP","I50": #LOCATION = "C1054" !CDS_LOCATION = "C1054" &SEC = "1" #&CDS_SEC = "1";
"A":   PN = "1"  !CDS_PN = "1";
"B":   PN = "2"  !CDS_PN = "2";
BODY = "Q_CAP","I51": #LOCATION = "C1056" !CDS_LOCATION = "C1056" &SEC = "1" #&CDS_SEC = "1";
"A":   PN = "1"  !CDS_PN = "1";
"B":   PN = "2"  !CDS_PN = "2";
BODY = "Q_CAP","I52": #LOCATION = "C1008" !CDS_LOCATION = "C1008" &SEC = "1" #&CDS_SEC = "1";
"A":   PN = "1"  !CDS_PN = "1";
"B":   PN = "2"  !CDS_PN = "2";
BODY = "Q_CAP","I53": #LOCATION = "C1011" !CDS_LOCATION = "C1011" &SEC = "1" #&CDS_SEC = "1";
"A":   PN = "1"  !CDS_PN = "1";
"B":   PN = "2"  !CDS_PN = "2";
BODY = "Q_CAP","I54": #LOCATION = "C1043" !CDS_LOCATION = "C1043" &SEC = "1" #&CDS_SEC = "1";
"A":   PN = "1"  !CDS_PN = "1";
"B":   PN = "2"  !CDS_PN = "2";
BODY = "Q_CAP","I56": #LOCATION = "C1047" !CDS_LOCATION = "C1047" &SEC = "1" #&CDS_SEC = "1";
"A":   PN = "1"  !CDS_PN = "1";
"B":   PN = "2"  !CDS_PN = "2";
BODY = "Q_CAP","I57": #LOCATION = "C1019" !CDS_LOCATION = "C1019" &SEC = "1" #&CDS_SEC = "1";
"A":   PN = "1"  !CDS_PN = "1";
"B":   PN = "2"  !CDS_PN = "2";
BODY = "Q_CAP","I59": #LOCATION = "C1046" !CDS_LOCATION = "C1046" &SEC = "1" #&CDS_SEC = "1";
"A":   PN = "1"  !CDS_PN = "1";
"B":   PN = "2"  !CDS_PN = "2";
BODY = "Q_CAP","I60": #LOCATION = "C1050" !CDS_LOCATION = "C1050" &SEC = "1" #&CDS_SEC = "1";
"A":   PN = "1"  !CDS_PN = "1";
"B":   PN = "2"  !CDS_PN = "2";
BODY = "Q_CAP","I62": #LOCATION = "C1013" !CDS_LOCATION = "C1013" &SEC = "1" #&CDS_SEC = "1";
"A":   PN = "1"  !CDS_PN = "1";
"B":   PN = "2"  !CDS_PN = "2";
BODY = "Q_CAP","I63": #LOCATION = "C1017" !CDS_LOCATION = "C1017" &SEC = "1" #&CDS_SEC = "1";
"A":   PN = "1"  !CDS_PN = "1";
"B":   PN = "2"  !CDS_PN = "2";
BODY = "Q_INDUCTOR","I65": #LOCATION = "L23" !CDS_LOCATION = "L23" &SEC = "1" #&CDS_SEC = "1";
"1":   PN = "1"  !CDS_PN = "1";
"2":   PN = "2"  !CDS_PN = "2";
BODY = "Q_CAP","I66": #LOCATION = "C1022" !CDS_LOCATION = "C1022" &SEC = "1" #&CDS_SEC = "1";
"A":   PN = "1"  !CDS_PN = "1";
"B":   PN = "2"  !CDS_PN = "2";
BODY = "Q_CAP","I67": #LOCATION = "C1025" !CDS_LOCATION = "C1025" &SEC = "1" #&CDS_SEC = "1";
"A":   PN = "1"  !CDS_PN = "1";
"B":   PN = "2"  !CDS_PN = "2";
BODY = "Q_CAP","I69": #LOCATION = "C1028" !CDS_LOCATION = "C1028" &SEC = "1" #&CDS_SEC = "1";
"A":   PN = "1"  !CDS_PN = "1";
"B":   PN = "2"  !CDS_PN = "2";
BODY = "Q_CAP","I70": #LOCATION = "C1029" !CDS_LOCATION = "C1029" &SEC = "1" #&CDS_SEC = "1";
"A":   PN = "1"  !CDS_PN = "1";
"B":   PN = "2"  !CDS_PN = "2";
BODY = "Q_CAP","I71": #LOCATION = "C1033" !CDS_LOCATION = "C1033" &SEC = "1" #&CDS_SEC = "1";
"A":   PN = "1"  !CDS_PN = "1";
"B":   PN = "2"  !CDS_PN = "2";
BODY = "Q_CAP","I72": #LOCATION = "C1026" !CDS_LOCATION = "C1026" &SEC = "1" #&CDS_SEC = "1";
"A":   PN = "1"  !CDS_PN = "1";
"B":   PN = "2"  !CDS_PN = "2";
BODY = "Q_CAP","I73": #LOCATION = "C1044" !CDS_LOCATION = "C1044" &SEC = "1" #&CDS_SEC = "1";
"A":   PN = "1"  !CDS_PN = "1";
"B":   PN = "2"  !CDS_PN = "2";
BODY = "Q_CAP","I74": #LOCATION = "C1032" !CDS_LOCATION = "C1032" &SEC = "1" #&CDS_SEC = "1";
"A":   PN = "1"  !CDS_PN = "1";
"B":   PN = "2"  !CDS_PN = "2";
BODY = "Q_CAP","I75": #LOCATION = "C1038" !CDS_LOCATION = "C1038" &SEC = "1" #&CDS_SEC = "1";
"A":   PN = "1"  !CDS_PN = "1";
"B":   PN = "2"  !CDS_PN = "2";
BODY = "Q_CAP","I76": #LOCATION = "C1016" !CDS_LOCATION = "C1016" &SEC = "1" #&CDS_SEC = "1";
"A":   PN = "1"  !CDS_PN = "1";
"B":   PN = "2"  !CDS_PN = "2";
BODY = "Q_CAP","I77": #LOCATION = "C1030" !CDS_LOCATION = "C1030" &SEC = "1" #&CDS_SEC = "1";
"A":   PN = "1"  !CDS_PN = "1";
"B":   PN = "2"  !CDS_PN = "2";
BODY = "Q_CAP","I78": #LOCATION = "C1041" !CDS_LOCATION = "C1041" &SEC = "1" #&CDS_SEC = "1";
"A":   PN = "1"  !CDS_PN = "1";
"B":   PN = "2"  !CDS_PN = "2";
BODY = "Q_CAP","I79": #LOCATION = "C1037" !CDS_LOCATION = "C1037" &SEC = "1" #&CDS_SEC = "1";
"A":   PN = "1"  !CDS_PN = "1";
"B":   PN = "2"  !CDS_PN = "2";
BODY = "Q_CAP","I80": #LOCATION = "C1049" !CDS_LOCATION = "C1049" &SEC = "1" #&CDS_SEC = "1";
"A":   PN = "1"  !CDS_PN = "1";
"B":   PN = "2"  !CDS_PN = "2";
BODY = "Q_CAP","I81": #LOCATION = "C1007" !CDS_LOCATION = "C1007" &SEC = "1" #&CDS_SEC = "1";
"A":   PN = "1"  !CDS_PN = "1";
"B":   PN = "2"  !CDS_PN = "2";
BODY = "Q_CAP","I82": #LOCATION = "C1009" !CDS_LOCATION = "C1009" &SEC = "1" #&CDS_SEC = "1";
"A":   PN = "1"  !CDS_PN = "1";
"B":   PN = "2"  !CDS_PN = "2";
BODY = "Q_CAP","I84": #LOCATION = "C1012" !CDS_LOCATION = "C1012" &SEC = "1" #&CDS_SEC = "1";
"A":   PN = "1"  !CDS_PN = "1";
"B":   PN = "2"  !CDS_PN = "2";
BODY = "Q_CAP","I85": #LOCATION = "C1048" !CDS_LOCATION = "C1048" &SEC = "1" #&CDS_SEC = "1";
"A":   PN = "1"  !CDS_PN = "1";
"B":   PN = "2"  !CDS_PN = "2";
BODY = "Q_CAP","I86": #LOCATION = "C1040" !CDS_LOCATION = "C1040" &SEC = "1" #&CDS_SEC = "1";
"A":   PN = "1"  !CDS_PN = "1";
"B":   PN = "2"  !CDS_PN = "2";
BODY = "Q_CAP","I87": #LOCATION = "C1045" !CDS_LOCATION = "C1045" &SEC = "1" #&CDS_SEC = "1";
"A":   PN = "1"  !CDS_PN = "1";
"B":   PN = "2"  !CDS_PN = "2";
BODY = "Q_INDUCTOR","I88": #LOCATION = "L30" !CDS_LOCATION = "L30" &SEC = "1" #&CDS_SEC = "1";
"1":   PN = "1"  !CDS_PN = "1";
"2":   PN = "2"  !CDS_PN = "2";
BODY = "Q_RES","I89": #LOCATION = "R1093" !CDS_LOCATION = "R1093" &SEC = "1" #&CDS_SEC = "1";
"A":   PN = "1"  !CDS_PN = "1";
"B":   PN = "2"  !CDS_PN = "2";
BODY = "Q_CAP","I90": #LOCATION = "C1018" !CDS_LOCATION = "C1018" &SEC = "1" #&CDS_SEC = "1";
"A":   PN = "1"  !CDS_PN = "1";
"B":   PN = "2"  !CDS_PN = "2";
BODY = "Q_CAP","I91": #LOCATION = "C1020" !CDS_LOCATION = "C1020" &SEC = "1" #&CDS_SEC = "1";
"A":   PN = "1"  !CDS_PN = "1";
"B":   PN = "2"  !CDS_PN = "2";
BODY = "Q_CAP","I92": #LOCATION = "C1051" !CDS_LOCATION = "C1051" &SEC = "1" #&CDS_SEC = "1";
"A":   PN = "1"  !CDS_PN = "1";
"B":   PN = "2"  !CDS_PN = "2";
BODY = "Q_CAP","I93": #LOCATION = "C1053" !CDS_LOCATION = "C1053" &SEC = "1" #&CDS_SEC = "1";
"A":   PN = "1"  !CDS_PN = "1";
"B":   PN = "2"  !CDS_PN = "2";
BODY = "Q_CAPP","I94": #LOCATION = "C7017" !CDS_LOCATION = "C7017" &SEC = "1" #&CDS_SEC = "1";
"A":   PN = "1"  !CDS_PN = "1";
"B":   PN = "2"  !CDS_PN = "2";
BODY = "Q_CAPP","I95": #LOCATION = "C7018" !CDS_LOCATION = "C7018" &SEC = "1" #&CDS_SEC = "1";
"A":   PN = "1"  !CDS_PN = "1";
"B":   PN = "2"  !CDS_PN = "2";
BODY = "Q_CAP","I96": #LOCATION = "C7019" !CDS_LOCATION = "C7019" &SEC = "1" #&CDS_SEC = "1";
"A":   PN = "1"  !CDS_PN = "1";
"B":   PN = "2"  !CDS_PN = "2";
DRAWING = "@t6g_mb_lib.t6g(sch_1):page340";
BODY = "Q_RES","I2": #LOCATION = "R9032" !CDS_LOCATION = "R9032" &SEC = "1" #&CDS_SEC = "1";
"A":   PN = "1"  !CDS_PN = "1";
"B":   PN = "2"  !CDS_PN = "2";
BODY = "Q_RES","I3": #LOCATION = "R9034" !CDS_LOCATION = "R9034" &SEC = "1" #&CDS_SEC = "1";
"A":   PN = "1"  !CDS_PN = "1";
"B":   PN = "2"  !CDS_PN = "2";
BODY = "Q_RES","I13": #LOCATION = "R9022" !CDS_LOCATION = "R9022" &SEC = "1" #&CDS_SEC = "1";
"A":   PN = "1"  !CDS_PN = "1";
"B":   PN = "2"  !CDS_PN = "2";
BODY = "Q_RES","I14": #LOCATION = "R9023" !CDS_LOCATION = "R9023" &SEC = "1" #&CDS_SEC = "1";
"A":   PN = "1"  !CDS_PN = "1";
"B":   PN = "2"  !CDS_PN = "2";
BODY = "Q_RES","I15": #LOCATION = "R9030" !CDS_LOCATION = "R9030" &SEC = "1" #&CDS_SEC = "1";
"A":   PN = "1"  !CDS_PN = "1";
"B":   PN = "2"  !CDS_PN = "2";
BODY = "Q_RES","I18": #LOCATION = "R9029" !CDS_LOCATION = "R9029" &SEC = "1" #&CDS_SEC = "1";
"A":   PN = "1"  !CDS_PN = "1";
"B":   PN = "2"  !CDS_PN = "2";
BODY = "Q_RES","I22": #LOCATION = "R9031" !CDS_LOCATION = "R9031" &SEC = "1" #&CDS_SEC = "1";
"A":   PN = "1"  !CDS_PN = "1";
"B":   PN = "2"  !CDS_PN = "2";
BODY = "74LVC1G08W57","I25": #LOCATION = "U9001" !CDS_LOCATION = "U9001" &SEC = "1" #&CDS_SEC = "1";
"A":   PN = "1"  !CDS_PN = "1";
"B":   PN = "2"  !CDS_PN = "2";
"GND":   PN = "3"  !CDS_PN = "3";
"VCC":   PN = "5"  !CDS_PN = "5";
"Y":   PN = "4"  !CDS_PN = "4";
BODY = "Q_CAP","I27": #LOCATION = "C9007" !CDS_LOCATION = "C9007" &SEC = "1" #&CDS_SEC = "1";
"A":   PN = "1"  !CDS_PN = "1";
"B":   PN = "2"  !CDS_PN = "2";
BODY = "Q_RES","I29": #LOCATION = "R9033" !CDS_LOCATION = "R9033" &SEC = "1" #&CDS_SEC = "1";
"A":   PN = "1"  !CDS_PN = "1";
"B":   PN = "2"  !CDS_PN = "2";
BODY = "MOSFET_N","I31": #LOCATION = "U24" !CDS_LOCATION = "U24" &SEC = "1" #&CDS_SEC = "1";
"DRAIN":   PN = "D"  !CDS_PN = "D";
"GATE":   PN = "G"  !CDS_PN = "G";
"SOURCE":   PN = "S"  !CDS_PN = "S";
BODY = "Q_RES","I34": #LOCATION = "R1128" !CDS_LOCATION = "R1128" &SEC = "1" #&CDS_SEC = "1";
"A":   PN = "1"  !CDS_PN = "1";
"B":   PN = "2"  !CDS_PN = "2";
BODY = "74LVC1G08W57","I36": #LOCATION = "U23" !CDS_LOCATION = "U23" #SEC = "1" !CDS_SEC = "1";
"A":   PN = "1"  !CDS_PN = "1";
"B":   PN = "2"  !CDS_PN = "2";
"GND":   PN = "3"  !CDS_PN = "3";
"VCC":   PN = "5"  !CDS_PN = "5";
"Y":   PN = "4"  !CDS_PN = "4";
BODY = "Q_CAP","I40": #LOCATION = "C1059" !CDS_LOCATION = "C1059" &SEC = "1" #&CDS_SEC = "1";
"A":   PN = "1"  !CDS_PN = "1";
"B":   PN = "2"  !CDS_PN = "2";
BODY = "Q_RES","I44": #LOCATION = "R1131" !CDS_LOCATION = "R1131" &SEC = "1" #&CDS_SEC = "1";
"A":   PN = "1"  !CDS_PN = "1";
"B":   PN = "2"  !CDS_PN = "2";
BODY = "Q_RES","I47": #LOCATION = "R1134" !CDS_LOCATION = "R1134" &SEC = "1" #&CDS_SEC = "1";
"A":   PN = "1"  !CDS_PN = "1";
"B":   PN = "2"  !CDS_PN = "2";
BODY = "Q_RES","I49": #LOCATION = "R1130" !CDS_LOCATION = "R1130" &SEC = "1" #&CDS_SEC = "1";
"A":   PN = "1"  !CDS_PN = "1";
"B":   PN = "2"  !CDS_PN = "2";
BODY = "SN74LVC1G07DBVR","I51": #LOCATION = "U28" !CDS_LOCATION = "U28" &SEC = "1" #&CDS_SEC = "1";
"A":   PN = "2"  !CDS_PN = "2";
"GND":   PN = "3"  !CDS_PN = "3";
"NC":   PN = "1"  !CDS_PN = "1";
"VCC":   PN = "5"  !CDS_PN = "5";
"Y":   PN = "4"  !CDS_PN = "4";
BODY = "Q_CAP","I53": #LOCATION = "C1058" !CDS_LOCATION = "C1058" &SEC = "1" #&CDS_SEC = "1";
"A":   PN = "1"  !CDS_PN = "1";
"B":   PN = "2"  !CDS_PN = "2";
BODY = "Q_RES","I57": #LOCATION = "R1129" !CDS_LOCATION = "R1129" &SEC = "1" #&CDS_SEC = "1";
"A":   PN = "1"  !CDS_PN = "1";
"B":   PN = "2"  !CDS_PN = "2";
BODY = "Q_RES","I58": #LOCATION = "R1132" !CDS_LOCATION = "R1132" &SEC = "1" #&CDS_SEC = "1";
"A":   PN = "1"  !CDS_PN = "1";
"B":   PN = "2"  !CDS_PN = "2";
BODY = "Q_RES","I61": #LOCATION = "R1133" !CDS_LOCATION = "R1133" &SEC = "1" #&CDS_SEC = "1";
"A":   PN = "1"  !CDS_PN = "1";
"B":   PN = "2"  !CDS_PN = "2";
BODY = "Q_RES","I64": #LOCATION = "R1144" !CDS_LOCATION = "R1144" &SEC = "1" #&CDS_SEC = "1";
"A":   PN = "1"  !CDS_PN = "1";
"B":   PN = "2"  !CDS_PN = "2";
BODY = "Q_RES","I65": #LOCATION = "R1143" !CDS_LOCATION = "R1143" &SEC = "1" #&CDS_SEC = "1";
"A":   PN = "1"  !CDS_PN = "1";
"B":   PN = "2"  !CDS_PN = "2";
BODY = "SN74LVC1G07DBVR","I66": #LOCATION = "U30" !CDS_LOCATION = "U30" &SEC = "1" #&CDS_SEC = "1";
"A":   PN = "2"  !CDS_PN = "2";
"GND":   PN = "3"  !CDS_PN = "3";
"NC":   PN = "1"  !CDS_PN = "1";
"VCC":   PN = "5"  !CDS_PN = "5";
"Y":   PN = "4"  !CDS_PN = "4";
BODY = "Q_CAP","I69": #LOCATION = "C1060" !CDS_LOCATION = "C1060" &SEC = "1" #&CDS_SEC = "1";
"A":   PN = "1"  !CDS_PN = "1";
"B":   PN = "2"  !CDS_PN = "2";
BODY = "Q_RES","I71": #LOCATION = "R1142" !CDS_LOCATION = "R1142" &SEC = "1" #&CDS_SEC = "1";
"A":   PN = "1"  !CDS_PN = "1";
"B":   PN = "2"  !CDS_PN = "2";
BODY = "74LVC1G32GW","I74": #LOCATION = "U9002" !CDS_LOCATION = "U9002" &SEC = "1" #&CDS_SEC = "1";
"GND":   PN = "3"  !CDS_PN = "3";
"I0":   PN = "1"  !CDS_PN = "1";
"I1":   PN = "2"  !CDS_PN = "2";
"O":   PN = "4"  !CDS_PN = "4";
"VCC":   PN = "5"  !CDS_PN = "5";
BODY = "Q_CAP","I75": #LOCATION = "C9008" !CDS_LOCATION = "C9008" &SEC = "1" #&CDS_SEC = "1";
"A":   PN = "1"  !CDS_PN = "1";
"B":   PN = "2"  !CDS_PN = "2";
BODY = "Q_RES","I76": #LOCATION = "R1145" !CDS_LOCATION = "R1145" &SEC = "1" #&CDS_SEC = "1";
"A":   PN = "1"  !CDS_PN = "1";
"B":   PN = "2"  !CDS_PN = "2";
BODY = "Q_CAP","I79": #LOCATION = "C8008" !CDS_LOCATION = "C8008" &SEC = "1" #&CDS_SEC = "1";
"A":   PN = "1"  !CDS_PN = "1";
"B":   PN = "2"  !CDS_PN = "2";
BODY = "APX80929SAG7","I80": #LOCATION = "U8001" !CDS_LOCATION = "U8001" #SEC = "1" !CDS_SEC = "1";
"GND":   PN = "1"  !CDS_PN = "1";
"RESET_L":   PN = "2"  !CDS_PN = "2";
"VCC":   PN = "3"  !CDS_PN = "3";
BODY = "Q_RES","I84": #LOCATION = "R8093" !CDS_LOCATION = "R8093" &SEC = "1" #&CDS_SEC = "1";
"A":   PN = "1"  !CDS_PN = "1";
"B":   PN = "2"  !CDS_PN = "2";
BODY = "Q_RES","I85": #LOCATION = "R8094" !CDS_LOCATION = "R8094" #SEC = "1" !CDS_SEC = "1";
"A":   PN = "1"  !CDS_PN = "1";
"B":   PN = "2"  !CDS_PN = "2";
BODY = "Q_RES","I90": #LOCATION = "R8092" !CDS_LOCATION = "R8092" &SEC = "1" #&CDS_SEC = "1";
"A":   PN = "1"  !CDS_PN = "1";
"B":   PN = "2"  !CDS_PN = "2";
BODY = "74LVC1G08W57","I91": #LOCATION = "U9050" !CDS_LOCATION = "U9050" &SEC = "1" #&CDS_SEC = "1";
"A":   PN = "1"  !CDS_PN = "1";
"B":   PN = "2"  !CDS_PN = "2";
"GND":   PN = "3"  !CDS_PN = "3";
"VCC":   PN = "5"  !CDS_PN = "5";
"Y":   PN = "4"  !CDS_PN = "4";
BODY = "Q_CAP","I94": #LOCATION = "C9050" !CDS_LOCATION = "C9050" &SEC = "1" #&CDS_SEC = "1";
"A":   PN = "1"  !CDS_PN = "1";
"B":   PN = "2"  !CDS_PN = "2";
BODY = "Q_RES","I96": #LOCATION = "R1509" !CDS_LOCATION = "R1509" &SEC = "1" #&CDS_SEC = "1";
"A":   PN = "1"  !CDS_PN = "1";
"B":   PN = "2"  !CDS_PN = "2";
BODY = "Q_RES","I101": #LOCATION = "R1519" !CDS_LOCATION = "R1519" &SEC = "1" #&CDS_SEC = "1";
"A":   PN = "1"  !CDS_PN = "1";
"B":   PN = "2"  !CDS_PN = "2";
BODY = "Q_RES","I102": #LOCATION = "R1518" !CDS_LOCATION = "R1518" &SEC = "1" #&CDS_SEC = "1";
"A":   PN = "1"  !CDS_PN = "1";
"B":   PN = "2"  !CDS_PN = "2";
DRAWING = "@t6g_mb_lib.t6g(sch_1):page257";
BODY = "Q_RES","I3": #LOCATION = "R1163" !CDS_LOCATION = "R1163" &SEC = "1" #&CDS_SEC = "1";
"A":   PN = "1"  !CDS_PN = "1";
"B":   PN = "2"  !CDS_PN = "2";
BODY = "Q_CAP","I5": #LOCATION = "C1061" !CDS_LOCATION = "C1061" &SEC = "1" #&CDS_SEC = "1";
"A":   PN = "1"  !CDS_PN = "1";
"B":   PN = "2"  !CDS_PN = "2";
BODY = "Q_RES","I10": #LOCATION = "R1176" !CDS_LOCATION = "R1176" &SEC = "1" #&CDS_SEC = "1";
"A":   PN = "1"  !CDS_PN = "1";
"B":   PN = "2"  !CDS_PN = "2";
BODY = "Q_RES","I12": #LOCATION = "R1178" !CDS_LOCATION = "R1178" &SEC = "1" #&CDS_SEC = "1";
"A":   PN = "1"  !CDS_PN = "1";
"B":   PN = "2"  !CDS_PN = "2";
BODY = "Q_CAP","I14": #LOCATION = "C1065" !CDS_LOCATION = "C1065" &SEC = "1" #&CDS_SEC = "1";
"A":   PN = "1"  !CDS_PN = "1";
"B":   PN = "2"  !CDS_PN = "2";
BODY = "Q_RES","I16": #LOCATION = "R1173" !CDS_LOCATION = "R1173" &SEC = "1" #&CDS_SEC = "1";
"A":   PN = "1"  !CDS_PN = "1";
"B":   PN = "2"  !CDS_PN = "2";
BODY = "Q_RES","I17": #LOCATION = "R1174" !CDS_LOCATION = "R1174" &SEC = "1" #&CDS_SEC = "1";
"A":   PN = "1"  !CDS_PN = "1";
"B":   PN = "2"  !CDS_PN = "2";
BODY = "Q_RES","I18": #LOCATION = "R1166" !CDS_LOCATION = "R1166" &SEC = "1" #&CDS_SEC = "1";
"A":   PN = "1"  !CDS_PN = "1";
"B":   PN = "2"  !CDS_PN = "2";
BODY = "Q_RES","I19": #LOCATION = "R1167" !CDS_LOCATION = "R1167" &SEC = "1" #&CDS_SEC = "1";
"A":   PN = "1"  !CDS_PN = "1";
"B":   PN = "2"  !CDS_PN = "2";
BODY = "MOSFET_N","I24": #LOCATION = "U32" !CDS_LOCATION = "U32" &SEC = "1" #&CDS_SEC = "1";
"DRAIN":   PN = "D"  !CDS_PN = "D";
"GATE":   PN = "G"  !CDS_PN = "G";
"SOURCE":   PN = "S"  !CDS_PN = "S";
BODY = "Q_RES","I25": #LOCATION = "R1149" !CDS_LOCATION = "R1149" &SEC = "1" #&CDS_SEC = "1";
"A":   PN = "1"  !CDS_PN = "1";
"B":   PN = "2"  !CDS_PN = "2";
BODY = "Q_RES","I28": #LOCATION = "R1164" !CDS_LOCATION = "R1164" &SEC = "1" #&CDS_SEC = "1";
"A":   PN = "1"  !CDS_PN = "1";
"B":   PN = "2"  !CDS_PN = "2";
BODY = "74LVC1G08W57","I31": #LOCATION = "U31" !CDS_LOCATION = "U31" #SEC = "1" !CDS_SEC = "1";
"A":   PN = "1"  !CDS_PN = "1";
"B":   PN = "2"  !CDS_PN = "2";
"GND":   PN = "3"  !CDS_PN = "3";
"VCC":   PN = "5"  !CDS_PN = "5";
"Y":   PN = "4"  !CDS_PN = "4";
BODY = "Q_RES","I32": #LOCATION = "R1165" !CDS_LOCATION = "R1165" &SEC = "1" #&CDS_SEC = "1";
"A":   PN = "1"  !CDS_PN = "1";
"B":   PN = "2"  !CDS_PN = "2";
BODY = "Q_RES","I34": #LOCATION = "R1169" !CDS_LOCATION = "R1169" &SEC = "1" #&CDS_SEC = "1";
"A":   PN = "1"  !CDS_PN = "1";
"B":   PN = "2"  !CDS_PN = "2";
BODY = "Q_CAP","I36": #LOCATION = "C1062" !CDS_LOCATION = "C1062" &SEC = "1" #&CDS_SEC = "1";
"A":   PN = "1"  !CDS_PN = "1";
"B":   PN = "2"  !CDS_PN = "2";
BODY = "Q_RES","I39": #LOCATION = "R1147" !CDS_LOCATION = "R1147" &SEC = "1" #&CDS_SEC = "1";
"A":   PN = "1"  !CDS_PN = "1";
"B":   PN = "2"  !CDS_PN = "2";
BODY = "74LVC1G32GW","I40": #LOCATION = "U37" !CDS_LOCATION = "U37" &SEC = "1" #&CDS_SEC = "1";
"GND":   PN = "3"  !CDS_PN = "3";
"I0":   PN = "1"  !CDS_PN = "1";
"I1":   PN = "2"  !CDS_PN = "2";
"O":   PN = "4"  !CDS_PN = "4";
"VCC":   PN = "5"  !CDS_PN = "5";
BODY = "Q_RES","I41": #LOCATION = "R1146" !CDS_LOCATION = "R1146" &SEC = "1" #&CDS_SEC = "1";
"A":   PN = "1"  !CDS_PN = "1";
"B":   PN = "2"  !CDS_PN = "2";
BODY = "Q_RES","I42": #LOCATION = "R1175" !CDS_LOCATION = "R1175" &SEC = "1" #&CDS_SEC = "1";
"A":   PN = "1"  !CDS_PN = "1";
"B":   PN = "2"  !CDS_PN = "2";
BODY = "SN74LVC1G07DBVR","I45": #LOCATION = "U34" !CDS_LOCATION = "U34" &SEC = "1" #&CDS_SEC = "1";
"A":   PN = "2"  !CDS_PN = "2";
"GND":   PN = "3"  !CDS_PN = "3";
"NC":   PN = "1"  !CDS_PN = "1";
"VCC":   PN = "5"  !CDS_PN = "5";
"Y":   PN = "4"  !CDS_PN = "4";
BODY = "Q_CAP","I46": #LOCATION = "C1064" !CDS_LOCATION = "C1064" &SEC = "1" #&CDS_SEC = "1";
"A":   PN = "1"  !CDS_PN = "1";
"B":   PN = "2"  !CDS_PN = "2";
BODY = "Q_RES","I49": #LOCATION = "R1177" !CDS_LOCATION = "R1177" &SEC = "1" #&CDS_SEC = "1";
"A":   PN = "1"  !CDS_PN = "1";
"B":   PN = "2"  !CDS_PN = "2";
BODY = "Q_RES","I51": #LOCATION = "R1172" !CDS_LOCATION = "R1172" &SEC = "1" #&CDS_SEC = "1";
"A":   PN = "1"  !CDS_PN = "1";
"B":   PN = "2"  !CDS_PN = "2";
BODY = "Q_CAP","I55": #LOCATION = "C1063" !CDS_LOCATION = "C1063" &SEC = "1" #&CDS_SEC = "1";
"A":   PN = "1"  !CDS_PN = "1";
"B":   PN = "2"  !CDS_PN = "2";
BODY = "Q_RES","I57": #LOCATION = "R1168" !CDS_LOCATION = "R1168" &SEC = "1" #&CDS_SEC = "1";
"A":   PN = "1"  !CDS_PN = "1";
"B":   PN = "2"  !CDS_PN = "2";
BODY = "Q_RES","I58": #LOCATION = "R1170" !CDS_LOCATION = "R1170" &SEC = "1" #&CDS_SEC = "1";
"A":   PN = "1"  !CDS_PN = "1";
"B":   PN = "2"  !CDS_PN = "2";
BODY = "Q_RES","I60": #LOCATION = "R1171" !CDS_LOCATION = "R1171" &SEC = "1" #&CDS_SEC = "1";
"A":   PN = "1"  !CDS_PN = "1";
"B":   PN = "2"  !CDS_PN = "2";
BODY = "74LVC1G08W57","I63": #LOCATION = "U35" !CDS_LOCATION = "U35" &SEC = "1" #&CDS_SEC = "1";
"A":   PN = "1"  !CDS_PN = "1";
"B":   PN = "2"  !CDS_PN = "2";
"GND":   PN = "3"  !CDS_PN = "3";
"VCC":   PN = "5"  !CDS_PN = "5";
"Y":   PN = "4"  !CDS_PN = "4";
BODY = "SN74LVC1G07DBVR","I64": #LOCATION = "U33" !CDS_LOCATION = "U33" &SEC = "1" #&CDS_SEC = "1";
"A":   PN = "2"  !CDS_PN = "2";
"GND":   PN = "3"  !CDS_PN = "3";
"NC":   PN = "1"  !CDS_PN = "1";
"VCC":   PN = "5"  !CDS_PN = "5";
"Y":   PN = "4"  !CDS_PN = "4";
BODY = "Q_CAP","I66": #LOCATION = "C8009" !CDS_LOCATION = "C8009" &SEC = "1" #&CDS_SEC = "1";
"A":   PN = "1"  !CDS_PN = "1";
"B":   PN = "2"  !CDS_PN = "2";
BODY = "APX80929SAG7","I67": #LOCATION = "U8002" !CDS_LOCATION = "U8002" #SEC = "1" !CDS_SEC = "1";
"GND":   PN = "1"  !CDS_PN = "1";
"RESET_L":   PN = "2"  !CDS_PN = "2";
"VCC":   PN = "3"  !CDS_PN = "3";
BODY = "Q_RES","I70": #LOCATION = "R8096" !CDS_LOCATION = "R8096" &SEC = "1" #&CDS_SEC = "1";
"A":   PN = "1"  !CDS_PN = "1";
"B":   PN = "2"  !CDS_PN = "2";
BODY = "Q_RES","I73": #LOCATION = "R8097" !CDS_LOCATION = "R8097" &SEC = "1" #&CDS_SEC = "1";
"A":   PN = "1"  !CDS_PN = "1";
"B":   PN = "2"  !CDS_PN = "2";
BODY = "Q_RES","I77": #LOCATION = "R8095" !CDS_LOCATION = "R8095" &SEC = "1" #&CDS_SEC = "1";
"A":   PN = "1"  !CDS_PN = "1";
"B":   PN = "2"  !CDS_PN = "2";
BODY = "74LVC1G08W57","I78": #LOCATION = "U9051" !CDS_LOCATION = "U9051" &SEC = "1" #&CDS_SEC = "1";
"A":   PN = "1"  !CDS_PN = "1";
"B":   PN = "2"  !CDS_PN = "2";
"GND":   PN = "3"  !CDS_PN = "3";
"VCC":   PN = "5"  !CDS_PN = "5";
"Y":   PN = "4"  !CDS_PN = "4";
BODY = "Q_CAP","I81": #LOCATION = "C9051" !CDS_LOCATION = "C9051" &SEC = "1" #&CDS_SEC = "1";
"A":   PN = "1"  !CDS_PN = "1";
"B":   PN = "2"  !CDS_PN = "2";
BODY = "Q_RES","I84": #LOCATION = "R1523" !CDS_LOCATION = "R1523" &SEC = "1" #&CDS_SEC = "1";
"A":   PN = "1"  !CDS_PN = "1";
"B":   PN = "2"  !CDS_PN = "2";
BODY = "Q_RES","I88": #LOCATION = "R1525" !CDS_LOCATION = "R1525" &SEC = "1" #&CDS_SEC = "1";
"A":   PN = "1"  !CDS_PN = "1";
"B":   PN = "2"  !CDS_PN = "2";
BODY = "Q_RES","I89": #LOCATION = "R1524" !CDS_LOCATION = "R1524" &SEC = "1" #&CDS_SEC = "1";
"A":   PN = "1"  !CDS_PN = "1";
"B":   PN = "2"  !CDS_PN = "2";
DRAWING = "@t6g_mb_lib.t6g(sch_1):page376";
BODY = "PI3CSW12ZUAEX","I22": #LOCATION = "U45" !CDS_LOCATION = "U45" &SEC = "1" #&CDS_SEC = "1";
"1D+":   PN = "1"  !CDS_PN = "1";
"1D-":   PN = "2"  !CDS_PN = "2";
"2D+":   PN = "3"  !CDS_PN = "3";
"2D-":   PN = "4"  !CDS_PN = "4";
"D+":   PN = "8"  !CDS_PN = "8";
"D-":   PN = "7"  !CDS_PN = "7";
"GND":   PN = "5"  !CDS_PN = "5";
"OE#":   PN = "6"  !CDS_PN = "6";
"S":   PN = "9"  !CDS_PN = "9";
"VDD":   PN = "10"  !CDS_PN = "10";
BODY = "Q_CAP","I24": #LOCATION = "C1069" !CDS_LOCATION = "C1069" &SEC = "1" #&CDS_SEC = "1";
"A":   PN = "1"  !CDS_PN = "1";
"B":   PN = "2"  !CDS_PN = "2";
BODY = "Q_RES","I28": #LOCATION = "R1215" !CDS_LOCATION = "R1215" &SEC = "1" #&CDS_SEC = "1";
"A":   PN = "1"  !CDS_PN = "1";
"B":   PN = "2"  !CDS_PN = "2";
BODY = "Q_RES","I30": #LOCATION = "R1201" !CDS_LOCATION = "R1201" &SEC = "1" #&CDS_SEC = "1";
"A":   PN = "1"  !CDS_PN = "1";
"B":   PN = "2"  !CDS_PN = "2";
BODY = "PI3CSW12ZUAEX","I31": #LOCATION = "U42" !CDS_LOCATION = "U42" &SEC = "1" #&CDS_SEC = "1";
"1D+":   PN = "1"  !CDS_PN = "1";
"1D-":   PN = "2"  !CDS_PN = "2";
"2D+":   PN = "3"  !CDS_PN = "3";
"2D-":   PN = "4"  !CDS_PN = "4";
"D+":   PN = "8"  !CDS_PN = "8";
"D-":   PN = "7"  !CDS_PN = "7";
"GND":   PN = "5"  !CDS_PN = "5";
"OE#":   PN = "6"  !CDS_PN = "6";
"S":   PN = "9"  !CDS_PN = "9";
"VDD":   PN = "10"  !CDS_PN = "10";
BODY = "Q_CAP","I37": #LOCATION = "C1067" !CDS_LOCATION = "C1067" &SEC = "1" #&CDS_SEC = "1";
"A":   PN = "1"  !CDS_PN = "1";
"B":   PN = "2"  !CDS_PN = "2";
BODY = "Q_RES","I40": #LOCATION = "R1199" !CDS_LOCATION = "R1199" &SEC = "1" #&CDS_SEC = "1";
"A":   PN = "1"  !CDS_PN = "1";
"B":   PN = "2"  !CDS_PN = "2";
BODY = "Q_RES","I41": #LOCATION = "R1213" !CDS_LOCATION = "R1213" &SEC = "1" #&CDS_SEC = "1";
"A":   PN = "1"  !CDS_PN = "1";
"B":   PN = "2"  !CDS_PN = "2";
BODY = "PI3CSW12ZUAEX","I46": #LOCATION = "U41" !CDS_LOCATION = "U41" &SEC = "1" #&CDS_SEC = "1";
"1D+":   PN = "1"  !CDS_PN = "1";
"1D-":   PN = "2"  !CDS_PN = "2";
"2D+":   PN = "3"  !CDS_PN = "3";
"2D-":   PN = "4"  !CDS_PN = "4";
"D+":   PN = "8"  !CDS_PN = "8";
"D-":   PN = "7"  !CDS_PN = "7";
"GND":   PN = "5"  !CDS_PN = "5";
"OE#":   PN = "6"  !CDS_PN = "6";
"S":   PN = "9"  !CDS_PN = "9";
"VDD":   PN = "10"  !CDS_PN = "10";
BODY = "Q_CAP","I48": #LOCATION = "C1066" !CDS_LOCATION = "C1066" &SEC = "1" #&CDS_SEC = "1";
"A":   PN = "1"  !CDS_PN = "1";
"B":   PN = "2"  !CDS_PN = "2";
BODY = "Q_RES","I53": #LOCATION = "R1198" !CDS_LOCATION = "R1198" &SEC = "1" #&CDS_SEC = "1";
"A":   PN = "1"  !CDS_PN = "1";
"B":   PN = "2"  !CDS_PN = "2";
BODY = "Q_RES","I54": #LOCATION = "R1212" !CDS_LOCATION = "R1212" &SEC = "1" #&CDS_SEC = "1";
"A":   PN = "1"  !CDS_PN = "1";
"B":   PN = "2"  !CDS_PN = "2";
BODY = "PI3CSW12ZUAEX","I61": #LOCATION = "U43" !CDS_LOCATION = "U43" &SEC = "1" #&CDS_SEC = "1";
"1D+":   PN = "1"  !CDS_PN = "1";
"1D-":   PN = "2"  !CDS_PN = "2";
"2D+":   PN = "3"  !CDS_PN = "3";
"2D-":   PN = "4"  !CDS_PN = "4";
"D+":   PN = "8"  !CDS_PN = "8";
"D-":   PN = "7"  !CDS_PN = "7";
"GND":   PN = "5"  !CDS_PN = "5";
"OE#":   PN = "6"  !CDS_PN = "6";
"S":   PN = "9"  !CDS_PN = "9";
"VDD":   PN = "10"  !CDS_PN = "10";
BODY = "Q_CAP","I65": #LOCATION = "C1068" !CDS_LOCATION = "C1068" &SEC = "1" #&CDS_SEC = "1";
"A":   PN = "1"  !CDS_PN = "1";
"B":   PN = "2"  !CDS_PN = "2";
BODY = "Q_RES","I68": #LOCATION = "R1200" !CDS_LOCATION = "R1200" &SEC = "1" #&CDS_SEC = "1";
"A":   PN = "1"  !CDS_PN = "1";
"B":   PN = "2"  !CDS_PN = "2";
BODY = "Q_RES","I69": #LOCATION = "R1214" !CDS_LOCATION = "R1214" &SEC = "1" #&CDS_SEC = "1";
"A":   PN = "1"  !CDS_PN = "1";
"B":   PN = "2"  !CDS_PN = "2";
BODY = "PI3CSW12ZUAEX","I76": #LOCATION = "U48" !CDS_LOCATION = "U48" &SEC = "1" #&CDS_SEC = "1";
"1D+":   PN = "1"  !CDS_PN = "1";
"1D-":   PN = "2"  !CDS_PN = "2";
"2D+":   PN = "3"  !CDS_PN = "3";
"2D-":   PN = "4"  !CDS_PN = "4";
"D+":   PN = "8"  !CDS_PN = "8";
"D-":   PN = "7"  !CDS_PN = "7";
"GND":   PN = "5"  !CDS_PN = "5";
"OE#":   PN = "6"  !CDS_PN = "6";
"S":   PN = "9"  !CDS_PN = "9";
"VDD":   PN = "10"  !CDS_PN = "10";
BODY = "Q_CAP","I80": #LOCATION = "C1073" !CDS_LOCATION = "C1073" &SEC = "1" #&CDS_SEC = "1";
"A":   PN = "1"  !CDS_PN = "1";
"B":   PN = "2"  !CDS_PN = "2";
BODY = "Q_CAP","I84": #LOCATION = "C1072" !CDS_LOCATION = "C1072" &SEC = "1" #&CDS_SEC = "1";
"A":   PN = "1"  !CDS_PN = "1";
"B":   PN = "2"  !CDS_PN = "2";
BODY = "PI3CSW12ZUAEX","I85": #LOCATION = "U49" !CDS_LOCATION = "U49" &SEC = "1" #&CDS_SEC = "1";
"1D+":   PN = "1"  !CDS_PN = "1";
"1D-":   PN = "2"  !CDS_PN = "2";
"2D+":   PN = "3"  !CDS_PN = "3";
"2D-":   PN = "4"  !CDS_PN = "4";
"D+":   PN = "8"  !CDS_PN = "8";
"D-":   PN = "7"  !CDS_PN = "7";
"GND":   PN = "5"  !CDS_PN = "5";
"OE#":   PN = "6"  !CDS_PN = "6";
"S":   PN = "9"  !CDS_PN = "9";
"VDD":   PN = "10"  !CDS_PN = "10";
BODY = "Q_RES","I86": #LOCATION = "R1211" !CDS_LOCATION = "R1211" &SEC = "1" #&CDS_SEC = "1";
"A":   PN = "1"  !CDS_PN = "1";
"B":   PN = "2"  !CDS_PN = "2";
BODY = "Q_RES","I87": #LOCATION = "R1219" !CDS_LOCATION = "R1219" &SEC = "1" #&CDS_SEC = "1";
"A":   PN = "1"  !CDS_PN = "1";
"B":   PN = "2"  !CDS_PN = "2";
BODY = "Q_CAP","I99": #LOCATION = "C1070" !CDS_LOCATION = "C1070" &SEC = "1" #&CDS_SEC = "1";
"A":   PN = "1"  !CDS_PN = "1";
"B":   PN = "2"  !CDS_PN = "2";
BODY = "Q_CAP","I105": #LOCATION = "C1071" !CDS_LOCATION = "C1071" &SEC = "1" #&CDS_SEC = "1";
"A":   PN = "1"  !CDS_PN = "1";
"B":   PN = "2"  !CDS_PN = "2";
BODY = "PI3CSW12ZUAEX","I108": #LOCATION = "U46" !CDS_LOCATION = "U46" &SEC = "1" #&CDS_SEC = "1";
"1D+":   PN = "1"  !CDS_PN = "1";
"1D-":   PN = "2"  !CDS_PN = "2";
"2D+":   PN = "3"  !CDS_PN = "3";
"2D-":   PN = "4"  !CDS_PN = "4";
"D+":   PN = "8"  !CDS_PN = "8";
"D-":   PN = "7"  !CDS_PN = "7";
"GND":   PN = "5"  !CDS_PN = "5";
"OE#":   PN = "6"  !CDS_PN = "6";
"S":   PN = "9"  !CDS_PN = "9";
"VDD":   PN = "10"  !CDS_PN = "10";
BODY = "Q_RES","I109": #LOCATION = "R1210" !CDS_LOCATION = "R1210" &SEC = "1" #&CDS_SEC = "1";
"A":   PN = "1"  !CDS_PN = "1";
"B":   PN = "2"  !CDS_PN = "2";
BODY = "Q_RES","I110": #LOCATION = "R1218" !CDS_LOCATION = "R1218" &SEC = "1" #&CDS_SEC = "1";
"A":   PN = "1"  !CDS_PN = "1";
"B":   PN = "2"  !CDS_PN = "2";
BODY = "Q_RES","I115": #LOCATION = "R1206" !CDS_LOCATION = "R1206" &SEC = "1" #&CDS_SEC = "1";
"A":   PN = "1"  !CDS_PN = "1";
"B":   PN = "2"  !CDS_PN = "2";
BODY = "Q_RES","I116": #LOCATION = "R1216" !CDS_LOCATION = "R1216" &SEC = "1" #&CDS_SEC = "1";
"A":   PN = "1"  !CDS_PN = "1";
"B":   PN = "2"  !CDS_PN = "2";
BODY = "PI3CSW12ZUAEX","I121": #LOCATION = "U47" !CDS_LOCATION = "U47" &SEC = "1" #&CDS_SEC = "1";
"1D+":   PN = "1"  !CDS_PN = "1";
"1D-":   PN = "2"  !CDS_PN = "2";
"2D+":   PN = "3"  !CDS_PN = "3";
"2D-":   PN = "4"  !CDS_PN = "4";
"D+":   PN = "8"  !CDS_PN = "8";
"D-":   PN = "7"  !CDS_PN = "7";
"GND":   PN = "5"  !CDS_PN = "5";
"OE#":   PN = "6"  !CDS_PN = "6";
"S":   PN = "9"  !CDS_PN = "9";
"VDD":   PN = "10"  !CDS_PN = "10";
BODY = "Q_RES","I122": #LOCATION = "R1217" !CDS_LOCATION = "R1217" &SEC = "1" #&CDS_SEC = "1";
"A":   PN = "1"  !CDS_PN = "1";
"B":   PN = "2"  !CDS_PN = "2";
BODY = "Q_RES","I123": #LOCATION = "R1209" !CDS_LOCATION = "R1209" &SEC = "1" #&CDS_SEC = "1";
"A":   PN = "1"  !CDS_PN = "1";
"B":   PN = "2"  !CDS_PN = "2";
DRAWING = "@t6g_mb_lib.t6g(sch_1):page263";
BODY = "Q_RES","I12": #LOCATION = "R1226" !CDS_LOCATION = "R1226" &SEC = "1" #&CDS_SEC = "1";
"A":   PN = "1"  !CDS_PN = "1";
"B":   PN = "2"  !CDS_PN = "2";
BODY = "Q_RES","I13": #LOCATION = "R1238" !CDS_LOCATION = "R1238" &SEC = "1" #&CDS_SEC = "1";
"A":   PN = "1"  !CDS_PN = "1";
"B":   PN = "2"  !CDS_PN = "2";
BODY = "Q_RES","I15": #LOCATION = "R1263" !CDS_LOCATION = "R1263" &SEC = "1" #&CDS_SEC = "1";
"A":   PN = "1"  !CDS_PN = "1";
"B":   PN = "2"  !CDS_PN = "2";
BODY = "Q_RES","I16": #LOCATION = "R1260" !CDS_LOCATION = "R1260" &SEC = "1" #&CDS_SEC = "1";
"A":   PN = "1"  !CDS_PN = "1";
"B":   PN = "2"  !CDS_PN = "2";
BODY = "Q_RES","I19": #LOCATION = "R1237" !CDS_LOCATION = "R1237" &SEC = "1" #&CDS_SEC = "1";
"A":   PN = "1"  !CDS_PN = "1";
"B":   PN = "2"  !CDS_PN = "2";
BODY = "Q_RES","I21": #LOCATION = "R1259" !CDS_LOCATION = "R1259" &SEC = "1" #&CDS_SEC = "1";
"A":   PN = "1"  !CDS_PN = "1";
"B":   PN = "2"  !CDS_PN = "2";
BODY = "Q_RES","I22": #LOCATION = "R1258" !CDS_LOCATION = "R1258" &SEC = "1" #&CDS_SEC = "1";
"A":   PN = "1"  !CDS_PN = "1";
"B":   PN = "2"  !CDS_PN = "2";
BODY = "Q_CAP","I43": #LOCATION = "C1093" !CDS_LOCATION = "C1093" &SEC = "1" #&CDS_SEC = "1";
"A":   PN = "1"  !CDS_PN = "1";
"B":   PN = "2"  !CDS_PN = "2";
BODY = "Q_CAP","I45": #LOCATION = "C1085" !CDS_LOCATION = "C1085" &SEC = "1" #&CDS_SEC = "1";
"A":   PN = "1"  !CDS_PN = "1";
"B":   PN = "2"  !CDS_PN = "2";
BODY = "Q_RES","I57": #LOCATION = "R1240" !CDS_LOCATION = "R1240" &SEC = "1" #&CDS_SEC = "1";
"A":   PN = "1"  !CDS_PN = "1";
"B":   PN = "2"  !CDS_PN = "2";
BODY = "Q_RES","I58": #LOCATION = "R1242" !CDS_LOCATION = "R1242" &SEC = "1" #&CDS_SEC = "1";
"A":   PN = "1"  !CDS_PN = "1";
"B":   PN = "2"  !CDS_PN = "2";
BODY = "Q_RES","I59": #LOCATION = "R1239" !CDS_LOCATION = "R1239" &SEC = "1" #&CDS_SEC = "1";
"A":   PN = "1"  !CDS_PN = "1";
"B":   PN = "2"  !CDS_PN = "2";
BODY = "Q_RES","I60": #LOCATION = "R1241" !CDS_LOCATION = "R1241" &SEC = "1" #&CDS_SEC = "1";
"A":   PN = "1"  !CDS_PN = "1";
"B":   PN = "2"  !CDS_PN = "2";
BODY = "Q_CAP","I68": #LOCATION = "C1094" !CDS_LOCATION = "C1094" &SEC = "1" #&CDS_SEC = "1";
"A":   PN = "1"  !CDS_PN = "1";
"B":   PN = "2"  !CDS_PN = "2";
BODY = "Q_INDUCTOR","I69": #LOCATION = "L25" !CDS_LOCATION = "L25" &SEC = "1" #&CDS_SEC = "1";
"1":   PN = "1"  !CDS_PN = "1";
"2":   PN = "2"  !CDS_PN = "2";
BODY = "Q_CAP","I76": #LOCATION = "C1092" !CDS_LOCATION = "C1092" &SEC = "1" #&CDS_SEC = "1";
"A":   PN = "1"  !CDS_PN = "1";
"B":   PN = "2"  !CDS_PN = "2";
BODY = "Q_CAP","I77": #LOCATION = "C1084" !CDS_LOCATION = "C1084" &SEC = "1" #&CDS_SEC = "1";
"A":   PN = "1"  !CDS_PN = "1";
"B":   PN = "2"  !CDS_PN = "2";
BODY = "Q_CAP","I115": #LOCATION = "C1074" !CDS_LOCATION = "C1074" &SEC = "1" #&CDS_SEC = "1";
"A":   PN = "1"  !CDS_PN = "1";
"B":   PN = "2"  !CDS_PN = "2";
BODY = "Q_RES","I119": #LOCATION = "R1268" !CDS_LOCATION = "R1268" &SEC = "1" #&CDS_SEC = "1";
"A":   PN = "1"  !CDS_PN = "1";
"B":   PN = "2"  !CDS_PN = "2";
BODY = "Q_CAP","I130": #LOCATION = "C1095" !CDS_LOCATION = "C1095" &SEC = "1" #&CDS_SEC = "1";
"A":   PN = "1"  !CDS_PN = "1";
"B":   PN = "2"  !CDS_PN = "2";
BODY = "Q_RES","I131": #LOCATION = "R1267" !CDS_LOCATION = "R1267" &SEC = "1" #&CDS_SEC = "1";
"A":   PN = "1"  !CDS_PN = "1";
"B":   PN = "2"  !CDS_PN = "2";
BODY = "Q_RES","I138": #LOCATION = "R1227" !CDS_LOCATION = "R1227" &SEC = "1" #&CDS_SEC = "1";
"A":   PN = "1"  !CDS_PN = "1";
"B":   PN = "2"  !CDS_PN = "2";
BODY = "Q_RES","I139": #LOCATION = "R1228" !CDS_LOCATION = "R1228" &SEC = "1" #&CDS_SEC = "1";
"A":   PN = "1"  !CDS_PN = "1";
"B":   PN = "2"  !CDS_PN = "2";
BODY = "Q_RES","I140": #LOCATION = "R1244" !CDS_LOCATION = "R1244" &SEC = "1" #&CDS_SEC = "1";
"A":   PN = "1"  !CDS_PN = "1";
"B":   PN = "2"  !CDS_PN = "2";
BODY = "Q_RES","I141": #LOCATION = "R1243" !CDS_LOCATION = "R1243" &SEC = "1" #&CDS_SEC = "1";
"A":   PN = "1"  !CDS_PN = "1";
"B":   PN = "2"  !CDS_PN = "2";
BODY = "ADC128D818CIMTXNOPB","I142": #LOCATION = "U51" !CDS_LOCATION = "U51" &SEC = "1" #&CDS_SEC = "1";
"A0":   PN = "7"  !CDS_PN = "7";
"A1":   PN = "8"  !CDS_PN = "8";
"GND":   PN = "4"  !CDS_PN = "4";
"IN0":   PN = "16"  !CDS_PN = "16";
"IN1":   PN = "15"  !CDS_PN = "15";
"IN2":   PN = "14"  !CDS_PN = "14";
"IN3":   PN = "13"  !CDS_PN = "13";
"IN4":   PN = "12"  !CDS_PN = "12";
"IN5":   PN = "11"  !CDS_PN = "11";
"IN6":   PN = "10"  !CDS_PN = "10";
"IN7":   PN = "9"  !CDS_PN = "9";
"INT#":   PN = "6"  !CDS_PN = "6";
"SCL":   PN = "3"  !CDS_PN = "3";
"SDA":   PN = "2"  !CDS_PN = "2";
"V+":   PN = "5"  !CDS_PN = "5";
"VREF":   PN = "1"  !CDS_PN = "1";
BODY = "Q_CAP","I152": #LOCATION = "C1076" !CDS_LOCATION = "C1076" &SEC = "1" #&CDS_SEC = "1";
"A":   PN = "1"  !CDS_PN = "1";
"B":   PN = "2"  !CDS_PN = "2";
BODY = "Q_RES","I154": #LOCATION = "R1230" !CDS_LOCATION = "R1230" &SEC = "1" #&CDS_SEC = "1";
"A":   PN = "1"  !CDS_PN = "1";
"B":   PN = "2"  !CDS_PN = "2";
BODY = "MAX11617EEET","I156": #LOCATION = "U50" !CDS_LOCATION = "U50" #SEC = "1" !CDS_SEC = "1";
"AIN0":   PN = "5"  !CDS_PN = "5";
"AIN1":   PN = "6"  !CDS_PN = "6";
"AIN2":   PN = "7"  !CDS_PN = "7";
"AIN3":   PN = "8"  !CDS_PN = "8";
"AIN4":   PN = "9"  !CDS_PN = "9";
"AIN5":   PN = "10"  !CDS_PN = "10";
"AIN6":   PN = "11"  !CDS_PN = "11";
"AIN7":   PN = "12"  !CDS_PN = "12";
"AIN8":   PN = "4"  !CDS_PN = "4";
"AIN9":   PN = "3"  !CDS_PN = "3";
"AIN10":   PN = "2"  !CDS_PN = "2";
"AIN11||REF":   PN = "1"  !CDS_PN = "1";
"GND":   PN = "15"  !CDS_PN = "15";
"SCL":   PN = "13"  !CDS_PN = "13";
"SDA":   PN = "14"  !CDS_PN = "14";
"VDD":   PN = "16"  !CDS_PN = "16";
BODY = "Q_CAP","I165": #LOCATION = "C1075" !CDS_LOCATION = "C1075" &SEC = "1" #&CDS_SEC = "1";
"A":   PN = "1"  !CDS_PN = "1";
"B":   PN = "2"  !CDS_PN = "2";
BODY = "Q_CAP","I166": #LOCATION = "C1077" !CDS_LOCATION = "C1077" &SEC = "1" #&CDS_SEC = "1";
"A":   PN = "1"  !CDS_PN = "1";
"B":   PN = "2"  !CDS_PN = "2";
BODY = "Q_INDUCTOR","I168": #LOCATION = "L24" !CDS_LOCATION = "L24" &SEC = "1" #&CDS_SEC = "1";
"1":   PN = "1"  !CDS_PN = "1";
"2":   PN = "2"  !CDS_PN = "2";
BODY = "Q_CAP","I173": #LOCATION = "C1078" !CDS_LOCATION = "C1078" &SEC = "1" #&CDS_SEC = "1";
"A":   PN = "1"  !CDS_PN = "1";
"B":   PN = "2"  !CDS_PN = "2";
BODY = "Q_CAP","I175": #LOCATION = "C1086" !CDS_LOCATION = "C1086" &SEC = "1" #&CDS_SEC = "1";
"A":   PN = "1"  !CDS_PN = "1";
"B":   PN = "2"  !CDS_PN = "2";
BODY = "Q_RES","I177": #LOCATION = "R1245" !CDS_LOCATION = "R1245" &SEC = "1" #&CDS_SEC = "1";
"A":   PN = "1"  !CDS_PN = "1";
"B":   PN = "2"  !CDS_PN = "2";
BODY = "Q_RES","I178": #LOCATION = "R1251" !CDS_LOCATION = "R1251" &SEC = "1" #&CDS_SEC = "1";
"A":   PN = "1"  !CDS_PN = "1";
"B":   PN = "2"  !CDS_PN = "2";
BODY = "Q_RES","I179": #LOCATION = "R1232" !CDS_LOCATION = "R1232" &SEC = "1" #&CDS_SEC = "1";
"A":   PN = "1"  !CDS_PN = "1";
"B":   PN = "2"  !CDS_PN = "2";
BODY = "Q_CAP","I185": #LOCATION = "C1079" !CDS_LOCATION = "C1079" &SEC = "1" #&CDS_SEC = "1";
"A":   PN = "1"  !CDS_PN = "1";
"B":   PN = "2"  !CDS_PN = "2";
BODY = "Q_CAP","I187": #LOCATION = "C1087" !CDS_LOCATION = "C1087" &SEC = "1" #&CDS_SEC = "1";
"A":   PN = "1"  !CDS_PN = "1";
"B":   PN = "2"  !CDS_PN = "2";
BODY = "Q_RES","I189": #LOCATION = "R1246" !CDS_LOCATION = "R1246" &SEC = "1" #&CDS_SEC = "1";
"A":   PN = "1"  !CDS_PN = "1";
"B":   PN = "2"  !CDS_PN = "2";
BODY = "Q_RES","I190": #LOCATION = "R1252" !CDS_LOCATION = "R1252" &SEC = "1" #&CDS_SEC = "1";
"A":   PN = "1"  !CDS_PN = "1";
"B":   PN = "2"  !CDS_PN = "2";
BODY = "Q_RES","I191": #LOCATION = "R1231" !CDS_LOCATION = "R1231" &SEC = "1" #&CDS_SEC = "1";
"A":   PN = "1"  !CDS_PN = "1";
"B":   PN = "2"  !CDS_PN = "2";
BODY = "Q_RES","I194": #LOCATION = "R1234" !CDS_LOCATION = "R1234" &SEC = "1" #&CDS_SEC = "1";
"A":   PN = "1"  !CDS_PN = "1";
"B":   PN = "2"  !CDS_PN = "2";
BODY = "Q_CAP","I198": #LOCATION = "C1083" !CDS_LOCATION = "C1083" &SEC = "1" #&CDS_SEC = "1";
"A":   PN = "1"  !CDS_PN = "1";
"B":   PN = "2"  !CDS_PN = "2";
BODY = "Q_CAP","I200": #LOCATION = "C1091" !CDS_LOCATION = "C1091" &SEC = "1" #&CDS_SEC = "1";
"A":   PN = "1"  !CDS_PN = "1";
"B":   PN = "2"  !CDS_PN = "2";
BODY = "Q_RES","I202": #LOCATION = "R1250" !CDS_LOCATION = "R1250" &SEC = "1" #&CDS_SEC = "1";
"A":   PN = "1"  !CDS_PN = "1";
"B":   PN = "2"  !CDS_PN = "2";
BODY = "Q_RES","I203": #LOCATION = "R1257" !CDS_LOCATION = "R1257" &SEC = "1" #&CDS_SEC = "1";
"A":   PN = "1"  !CDS_PN = "1";
"B":   PN = "2"  !CDS_PN = "2";
BODY = "Q_CAP","I209": #LOCATION = "C1082" !CDS_LOCATION = "C1082" &SEC = "1" #&CDS_SEC = "1";
"A":   PN = "1"  !CDS_PN = "1";
"B":   PN = "2"  !CDS_PN = "2";
BODY = "Q_CAP","I211": #LOCATION = "C1089" !CDS_LOCATION = "C1089" &SEC = "1" #&CDS_SEC = "1";
"A":   PN = "1"  !CDS_PN = "1";
"B":   PN = "2"  !CDS_PN = "2";
BODY = "Q_RES","I213": #LOCATION = "R1248" !CDS_LOCATION = "R1248" &SEC = "1" #&CDS_SEC = "1";
"A":   PN = "1"  !CDS_PN = "1";
"B":   PN = "2"  !CDS_PN = "2";
BODY = "Q_RES","I214": #LOCATION = "R1255" !CDS_LOCATION = "R1255" &SEC = "1" #&CDS_SEC = "1";
"A":   PN = "1"  !CDS_PN = "1";
"B":   PN = "2"  !CDS_PN = "2";
BODY = "Q_RES","I215": #LOCATION = "R1235" !CDS_LOCATION = "R1235" &SEC = "1" #&CDS_SEC = "1";
"A":   PN = "1"  !CDS_PN = "1";
"B":   PN = "2"  !CDS_PN = "2";
BODY = "Q_RES","I216": #LOCATION = "R1224" !CDS_LOCATION = "R1224" &SEC = "1" #&CDS_SEC = "1";
"A":   PN = "1"  !CDS_PN = "1";
"B":   PN = "2"  !CDS_PN = "2";
BODY = "Q_CAP","I221": #LOCATION = "C1080" !CDS_LOCATION = "C1080" &SEC = "1" #&CDS_SEC = "1";
"A":   PN = "1"  !CDS_PN = "1";
"B":   PN = "2"  !CDS_PN = "2";
BODY = "Q_CAP","I223": #LOCATION = "C1088" !CDS_LOCATION = "C1088" &SEC = "1" #&CDS_SEC = "1";
"A":   PN = "1"  !CDS_PN = "1";
"B":   PN = "2"  !CDS_PN = "2";
BODY = "Q_RES","I225": #LOCATION = "R1247" !CDS_LOCATION = "R1247" &SEC = "1" #&CDS_SEC = "1";
"A":   PN = "1"  !CDS_PN = "1";
"B":   PN = "2"  !CDS_PN = "2";
BODY = "Q_RES","I226": #LOCATION = "R1254" !CDS_LOCATION = "R1254" &SEC = "1" #&CDS_SEC = "1";
"A":   PN = "1"  !CDS_PN = "1";
"B":   PN = "2"  !CDS_PN = "2";
BODY = "Q_RES","I227": #LOCATION = "R1233" !CDS_LOCATION = "R1233" &SEC = "1" #&CDS_SEC = "1";
"A":   PN = "1"  !CDS_PN = "1";
"B":   PN = "2"  !CDS_PN = "2";
BODY = "Q_RES","I230": #LOCATION = "R1236" !CDS_LOCATION = "R1236" &SEC = "1" #&CDS_SEC = "1";
"A":   PN = "1"  !CDS_PN = "1";
"B":   PN = "2"  !CDS_PN = "2";
BODY = "Q_RES","I231": #LOCATION = "R1249" !CDS_LOCATION = "R1249" &SEC = "1" #&CDS_SEC = "1";
"A":   PN = "1"  !CDS_PN = "1";
"B":   PN = "2"  !CDS_PN = "2";
BODY = "Q_CAP","I232": #LOCATION = "C1081" !CDS_LOCATION = "C1081" &SEC = "1" #&CDS_SEC = "1";
"A":   PN = "1"  !CDS_PN = "1";
"B":   PN = "2"  !CDS_PN = "2";
BODY = "Q_CAP","I237": #LOCATION = "C1090" !CDS_LOCATION = "C1090" &SEC = "1" #&CDS_SEC = "1";
"A":   PN = "1"  !CDS_PN = "1";
"B":   PN = "2"  !CDS_PN = "2";
BODY = "Q_RES","I239": #LOCATION = "R1256" !CDS_LOCATION = "R1256" &SEC = "1" #&CDS_SEC = "1";
"A":   PN = "1"  !CDS_PN = "1";
"B":   PN = "2"  !CDS_PN = "2";
BODY = "Q_RES","I242": #LOCATION = "R1229" !CDS_LOCATION = "R1229" &SEC = "1" #&CDS_SEC = "1";
"A":   PN = "1"  !CDS_PN = "1";
"B":   PN = "2"  !CDS_PN = "2";
BODY = "Q_RES","I243": #LOCATION = "R1221" !CDS_LOCATION = "R1221" &SEC = "1" #&CDS_SEC = "1";
"A":   PN = "1"  !CDS_PN = "1";
"B":   PN = "2"  !CDS_PN = "2";
BODY = "Q_RES","I244": #LOCATION = "R1220" !CDS_LOCATION = "R1220" &SEC = "1" #&CDS_SEC = "1";
"A":   PN = "1"  !CDS_PN = "1";
"B":   PN = "2"  !CDS_PN = "2";
BODY = "Q_RES","I245": #LOCATION = "R1223" !CDS_LOCATION = "R1223" &SEC = "1" #&CDS_SEC = "1";
"A":   PN = "1"  !CDS_PN = "1";
"B":   PN = "2"  !CDS_PN = "2";
BODY = "Q_RES","I246": #LOCATION = "R1222" !CDS_LOCATION = "R1222" &SEC = "1" #&CDS_SEC = "1";
"A":   PN = "1"  !CDS_PN = "1";
"B":   PN = "2"  !CDS_PN = "2";
BODY = "Q_RES","I247": #LOCATION = "R1225" !CDS_LOCATION = "R1225" &SEC = "1" #&CDS_SEC = "1";
"A":   PN = "1"  !CDS_PN = "1";
"B":   PN = "2"  !CDS_PN = "2";
DRAWING = "@t6g_mb_lib.t6g(sch_1):page466";
BODY = "Q_RES","I2": #LOCATION = "R1324" !CDS_LOCATION = "R1324" &SEC = "1" #&CDS_SEC = "1";
"A":   PN = "1"  !CDS_PN = "1";
"B":   PN = "2"  !CDS_PN = "2";
BODY = "Q_CAP","I5": #LOCATION = "C1108" !CDS_LOCATION = "C1108" &SEC = "1" #&CDS_SEC = "1";
"A":   PN = "1"  !CDS_PN = "1";
"B":   PN = "2"  !CDS_PN = "2";
BODY = "Q_RES","I10": #LOCATION = "R1284" !CDS_LOCATION = "R1284" &SEC = "1" #&CDS_SEC = "1";
"A":   PN = "1"  !CDS_PN = "1";
"B":   PN = "2"  !CDS_PN = "2";
BODY = "Q_RES","I11": #LOCATION = "R1301" !CDS_LOCATION = "R1301" &SEC = "1" #&CDS_SEC = "1";
"A":   PN = "1"  !CDS_PN = "1";
"B":   PN = "2"  !CDS_PN = "2";
BODY = "Q_RES","I12": #LOCATION = "R1306" !CDS_LOCATION = "R1306" &SEC = "1" #&CDS_SEC = "1";
"A":   PN = "1"  !CDS_PN = "1";
"B":   PN = "2"  !CDS_PN = "2";
BODY = "Q_RES","I13": #LOCATION = "R1309" !CDS_LOCATION = "R1309" &SEC = "1" #&CDS_SEC = "1";
"A":   PN = "1"  !CDS_PN = "1";
"B":   PN = "2"  !CDS_PN = "2";
BODY = "Q_RES","I14": #LOCATION = "R1276" !CDS_LOCATION = "R1276" &SEC = "1" #&CDS_SEC = "1";
"A":   PN = "1"  !CDS_PN = "1";
"B":   PN = "2"  !CDS_PN = "2";
BODY = "Q_CAP","I15": #LOCATION = "C1111" !CDS_LOCATION = "C1111" &SEC = "1" #&CDS_SEC = "1";
"A":   PN = "1"  !CDS_PN = "1";
"B":   PN = "2"  !CDS_PN = "2";
BODY = "Q_RES","I17": #LOCATION = "R1320" !CDS_LOCATION = "R1320" &SEC = "1" #&CDS_SEC = "1";
"A":   PN = "1"  !CDS_PN = "1";
"B":   PN = "2"  !CDS_PN = "2";
BODY = "Q_CAP","I19": #LOCATION = "C1097" !CDS_LOCATION = "C1097" &SEC = "1" #&CDS_SEC = "1";
"A":   PN = "1"  !CDS_PN = "1";
"B":   PN = "2"  !CDS_PN = "2";
BODY = "Q_RES","I23": #LOCATION = "R1270" !CDS_LOCATION = "R1270" &SEC = "1" #&CDS_SEC = "1";
"A":   PN = "1"  !CDS_PN = "1";
"B":   PN = "2"  !CDS_PN = "2";
BODY = "Q_RES","I27": #LOCATION = "R1273" !CDS_LOCATION = "R1273" &SEC = "1" #&CDS_SEC = "1";
"A":   PN = "1"  !CDS_PN = "1";
"B":   PN = "2"  !CDS_PN = "2";
BODY = "ISL28022FRZT","I28": #LOCATION = "U55" !CDS_LOCATION = "U55" #SEC = "1" !CDS_SEC = "1";
"A0":   PN = "2"  !CDS_PN = "2";
"A1":   PN = "1"  !CDS_PN = "1";
"EXT_CLK||INT":   PN = "3"  !CDS_PN = "3";
"GND":   PN = "10"  !CDS_PN = "10";
"NC0":   PN = "6"  !CDS_PN = "6";
"NC1":   PN = "7"  !CDS_PN = "7";
"NC2":   PN = "8"  !CDS_PN = "8";
"NC3":   PN = "14"  !CDS_PN = "14";
"NC4":   PN = "15"  !CDS_PN = "15";
"NC5":   PN = "16"  !CDS_PN = "16";
"SCL|||SMBCLK":   PN = "5"  !CDS_PN = "5";
"SDA||SMBDAT":   PN = "4"  !CDS_PN = "4";
"TH_GND":   PN = "TH"  !CDS_PN = "TH";
"VBUS":   PN = "11"  !CDS_PN = "11";
"VCC":   PN = "9"  !CDS_PN = "9";
"VINM":   PN = "12"  !CDS_PN = "12";
"VINP":   PN = "13"  !CDS_PN = "13";
BODY = "ISL28022FRZT","I29": #LOCATION = "U56" !CDS_LOCATION = "U56" #SEC = "1" !CDS_SEC = "1";
"A0":   PN = "2"  !CDS_PN = "2";
"A1":   PN = "1"  !CDS_PN = "1";
"EXT_CLK||INT":   PN = "3"  !CDS_PN = "3";
"GND":   PN = "10"  !CDS_PN = "10";
"NC0":   PN = "6"  !CDS_PN = "6";
"NC1":   PN = "7"  !CDS_PN = "7";
"NC2":   PN = "8"  !CDS_PN = "8";
"NC3":   PN = "14"  !CDS_PN = "14";
"NC4":   PN = "15"  !CDS_PN = "15";
"NC5":   PN = "16"  !CDS_PN = "16";
"SCL|||SMBCLK":   PN = "5"  !CDS_PN = "5";
"SDA||SMBDAT":   PN = "4"  !CDS_PN = "4";
"TH_GND":   PN = "TH"  !CDS_PN = "TH";
"VBUS":   PN = "11"  !CDS_PN = "11";
"VCC":   PN = "9"  !CDS_PN = "9";
"VINM":   PN = "12"  !CDS_PN = "12";
"VINP":   PN = "13"  !CDS_PN = "13";
BODY = "Q_RES","I33": #LOCATION = "R1271" !CDS_LOCATION = "R1271" &SEC = "1" #&CDS_SEC = "1";
"A":   PN = "1"  !CDS_PN = "1";
"B":   PN = "2"  !CDS_PN = "2";
BODY = "Q_CAP","I36": #LOCATION = "C1106" !CDS_LOCATION = "C1106" &SEC = "1" #&CDS_SEC = "1";
"A":   PN = "1"  !CDS_PN = "1";
"B":   PN = "2"  !CDS_PN = "2";
BODY = "Q_RES","I39": #LOCATION = "R1322" !CDS_LOCATION = "R1322" &SEC = "1" #&CDS_SEC = "1";
"A":   PN = "1"  !CDS_PN = "1";
"B":   PN = "2"  !CDS_PN = "2";
BODY = "Q_RES","I41": #LOCATION = "R1277" !CDS_LOCATION = "R1277" &SEC = "1" #&CDS_SEC = "1";
"A":   PN = "1"  !CDS_PN = "1";
"B":   PN = "2"  !CDS_PN = "2";
BODY = "Q_RES","I42": #LOCATION = "R1274" !CDS_LOCATION = "R1274" &SEC = "1" #&CDS_SEC = "1";
"A":   PN = "1"  !CDS_PN = "1";
"B":   PN = "2"  !CDS_PN = "2";
BODY = "Q_RES","I43": #LOCATION = "R1291" !CDS_LOCATION = "R1291" &SEC = "1" #&CDS_SEC = "1";
"A":   PN = "1"  !CDS_PN = "1";
"B":   PN = "2"  !CDS_PN = "2";
BODY = "Q_RES","I44": #LOCATION = "R1307" !CDS_LOCATION = "R1307" &SEC = "1" #&CDS_SEC = "1";
"A":   PN = "1"  !CDS_PN = "1";
"B":   PN = "2"  !CDS_PN = "2";
BODY = "Q_RES","I45": #LOCATION = "R1310" !CDS_LOCATION = "R1310" &SEC = "1" #&CDS_SEC = "1";
"A":   PN = "1"  !CDS_PN = "1";
"B":   PN = "2"  !CDS_PN = "2";
BODY = "Q_CAP","I51": #LOCATION = "C1109" !CDS_LOCATION = "C1109" &SEC = "1" #&CDS_SEC = "1";
"A":   PN = "1"  !CDS_PN = "1";
"B":   PN = "2"  !CDS_PN = "2";
BODY = "Q_RES","I53": #LOCATION = "R1325" !CDS_LOCATION = "R1325" &SEC = "1" #&CDS_SEC = "1";
"A":   PN = "1"  !CDS_PN = "1";
"B":   PN = "2"  !CDS_PN = "2";
BODY = "Q_CAP","I54": #LOCATION = "C1112" !CDS_LOCATION = "C1112" &SEC = "1" #&CDS_SEC = "1";
"A":   PN = "1"  !CDS_PN = "1";
"B":   PN = "2"  !CDS_PN = "2";
BODY = "Q_RES","I55": #LOCATION = "R1302" !CDS_LOCATION = "R1302" &SEC = "1" #&CDS_SEC = "1";
"A":   PN = "1"  !CDS_PN = "1";
"B":   PN = "2"  !CDS_PN = "2";
BODY = "ISL28022FRZT","I57": #LOCATION = "U52" !CDS_LOCATION = "U52" #SEC = "1" !CDS_SEC = "1";
"A0":   PN = "2"  !CDS_PN = "2";
"A1":   PN = "1"  !CDS_PN = "1";
"EXT_CLK||INT":   PN = "3"  !CDS_PN = "3";
"GND":   PN = "10"  !CDS_PN = "10";
"NC0":   PN = "6"  !CDS_PN = "6";
"NC1":   PN = "7"  !CDS_PN = "7";
"NC2":   PN = "8"  !CDS_PN = "8";
"NC3":   PN = "14"  !CDS_PN = "14";
"NC4":   PN = "15"  !CDS_PN = "15";
"NC5":   PN = "16"  !CDS_PN = "16";
"SCL|||SMBCLK":   PN = "5"  !CDS_PN = "5";
"SDA||SMBDAT":   PN = "4"  !CDS_PN = "4";
"TH_GND":   PN = "TH"  !CDS_PN = "TH";
"VBUS":   PN = "11"  !CDS_PN = "11";
"VCC":   PN = "9"  !CDS_PN = "9";
"VINM":   PN = "12"  !CDS_PN = "12";
"VINP":   PN = "13"  !CDS_PN = "13";
BODY = "Q_RES","I62": #LOCATION = "R1269" !CDS_LOCATION = "R1269" &SEC = "1" #&CDS_SEC = "1";
"A":   PN = "1"  !CDS_PN = "1";
"B":   PN = "2"  !CDS_PN = "2";
BODY = "Q_CAP","I66": #LOCATION = "C1096" !CDS_LOCATION = "C1096" &SEC = "1" #&CDS_SEC = "1";
"A":   PN = "1"  !CDS_PN = "1";
"B":   PN = "2"  !CDS_PN = "2";
BODY = "Q_CAP","I68": #LOCATION = "C1110" !CDS_LOCATION = "C1110" &SEC = "1" #&CDS_SEC = "1";
"A":   PN = "1"  !CDS_PN = "1";
"B":   PN = "2"  !CDS_PN = "2";
BODY = "Q_RES","I70": #LOCATION = "R1275" !CDS_LOCATION = "R1275" &SEC = "1" #&CDS_SEC = "1";
"A":   PN = "1"  !CDS_PN = "1";
"B":   PN = "2"  !CDS_PN = "2";
BODY = "Q_RES","I71": #LOCATION = "R1272" !CDS_LOCATION = "R1272" &SEC = "1" #&CDS_SEC = "1";
"A":   PN = "1"  !CDS_PN = "1";
"B":   PN = "2"  !CDS_PN = "2";
BODY = "Q_RES","I72": #LOCATION = "R1305" !CDS_LOCATION = "R1305" &SEC = "1" #&CDS_SEC = "1";
"A":   PN = "1"  !CDS_PN = "1";
"B":   PN = "2"  !CDS_PN = "2";
BODY = "Q_RES","I74": #LOCATION = "R1283" !CDS_LOCATION = "R1283" &SEC = "1" #&CDS_SEC = "1";
"A":   PN = "1"  !CDS_PN = "1";
"B":   PN = "2"  !CDS_PN = "2";
BODY = "Q_RES","I75": #LOCATION = "R1292" !CDS_LOCATION = "R1292" &SEC = "1" #&CDS_SEC = "1";
"A":   PN = "1"  !CDS_PN = "1";
"B":   PN = "2"  !CDS_PN = "2";
BODY = "Q_CAP","I81": #LOCATION = "C1107" !CDS_LOCATION = "C1107" &SEC = "1" #&CDS_SEC = "1";
"A":   PN = "1"  !CDS_PN = "1";
"B":   PN = "2"  !CDS_PN = "2";
BODY = "Q_RES","I84": #LOCATION = "R1323" !CDS_LOCATION = "R1323" &SEC = "1" #&CDS_SEC = "1";
"A":   PN = "1"  !CDS_PN = "1";
"B":   PN = "2"  !CDS_PN = "2";
BODY = "Q_RES","I85": #LOCATION = "R1327" !CDS_LOCATION = "R1327" &SEC = "1" #&CDS_SEC = "1";
"A":   PN = "1"  !CDS_PN = "1";
"B":   PN = "2"  !CDS_PN = "2";
BODY = "Q_RES","I87": #LOCATION = "R1328" !CDS_LOCATION = "R1328" &SEC = "1" #&CDS_SEC = "1";
"A":   PN = "1"  !CDS_PN = "1";
"B":   PN = "2"  !CDS_PN = "2";
BODY = "Q_RES","I90": #LOCATION = "R1326" !CDS_LOCATION = "R1326" &SEC = "1" #&CDS_SEC = "1";
"A":   PN = "1"  !CDS_PN = "1";
"B":   PN = "2"  !CDS_PN = "2";
BODY = "Q_RES","I92": #LOCATION = "R1355" !CDS_LOCATION = "R1355" &SEC = "1" #&CDS_SEC = "1";
"A":   PN = "1"  !CDS_PN = "1";
"B":   PN = "2"  !CDS_PN = "2";
BODY = "Q_RES","I93": #LOCATION = "R1360" !CDS_LOCATION = "R1360" &SEC = "1" #&CDS_SEC = "1";
"A":   PN = "1"  !CDS_PN = "1";
"B":   PN = "2"  !CDS_PN = "2";
BODY = "Q_RES","I94": #LOCATION = "R1350" !CDS_LOCATION = "R1350" &SEC = "1" #&CDS_SEC = "1";
"A":   PN = "1"  !CDS_PN = "1";
"B":   PN = "2"  !CDS_PN = "2";
BODY = "Q_RES","I95": #LOCATION = "R1317" !CDS_LOCATION = "R1317" &SEC = "1" #&CDS_SEC = "1";
"A":   PN = "1"  !CDS_PN = "1";
"B":   PN = "2"  !CDS_PN = "2";
BODY = "Q_RES","I96": #LOCATION = "R1308" !CDS_LOCATION = "R1308" &SEC = "1" #&CDS_SEC = "1";
"A":   PN = "1"  !CDS_PN = "1";
"B":   PN = "2"  !CDS_PN = "2";
DRAWING = "@t6g_mb_lib.t6g(sch_1):page211";
BODY = "PICOPROBE_BXA","I65": #LOCATION = "J63" !CDS_LOCATION = "J63" #SEC = "1" !CDS_SEC = "1";
"1_P":   PN = "1"  !CDS_PN = "1";
"2_N":   PN = "2"  !CDS_PN = "2";
"3_G":   PN = "3"  !CDS_PN = "3";
BODY = "PICOPROBE_BXA","I66": #LOCATION = "J8069" !CDS_LOCATION = "J8069" #SEC = "1" !CDS_SEC = "1";
"1_P":   PN = "1"  !CDS_PN = "1";
"2_N":   PN = "2"  !CDS_PN = "2";
"3_G":   PN = "3"  !CDS_PN = "3";
BODY = "PICOPROBE_BXA","I67": #LOCATION = "J64" !CDS_LOCATION = "J64" #SEC = "1" !CDS_SEC = "1";
"1_P":   PN = "1"  !CDS_PN = "1";
"2_N":   PN = "2"  !CDS_PN = "2";
"3_G":   PN = "3"  !CDS_PN = "3";
BODY = "PICOPROBE_BXA","I68": #LOCATION = "J70" !CDS_LOCATION = "J70" #SEC = "1" !CDS_SEC = "1";
"1_P":   PN = "1"  !CDS_PN = "1";
"2_N":   PN = "2"  !CDS_PN = "2";
"3_G":   PN = "3"  !CDS_PN = "3";
BODY = "PICOPROBE_BXA","I69": #LOCATION = "J65" !CDS_LOCATION = "J65" #SEC = "1" !CDS_SEC = "1";
"1_P":   PN = "1"  !CDS_PN = "1";
"2_N":   PN = "2"  !CDS_PN = "2";
"3_G":   PN = "3"  !CDS_PN = "3";
BODY = "PICOPROBE_BXA","I70": #LOCATION = "J71" !CDS_LOCATION = "J71" #SEC = "1" !CDS_SEC = "1";
"1_P":   PN = "1"  !CDS_PN = "1";
"2_N":   PN = "2"  !CDS_PN = "2";
"3_G":   PN = "3"  !CDS_PN = "3";
BODY = "PICOPROBE_BXA","I71": #LOCATION = "J66" !CDS_LOCATION = "J66" #SEC = "1" !CDS_SEC = "1";
"1_P":   PN = "1"  !CDS_PN = "1";
"2_N":   PN = "2"  !CDS_PN = "2";
"3_G":   PN = "3"  !CDS_PN = "3";
BODY = "PICOPROBE_BXA","I72": #LOCATION = "J72" !CDS_LOCATION = "J72" #SEC = "1" !CDS_SEC = "1";
"1_P":   PN = "1"  !CDS_PN = "1";
"2_N":   PN = "2"  !CDS_PN = "2";
"3_G":   PN = "3"  !CDS_PN = "3";
BODY = "PICOPROBE_BXA","I73": #LOCATION = "J8067" !CDS_LOCATION = "J8067" #SEC = "1" !CDS_SEC = "1";
"1_P":   PN = "1"  !CDS_PN = "1";
"2_N":   PN = "2"  !CDS_PN = "2";
"3_G":   PN = "3"  !CDS_PN = "3";
BODY = "PICOPROBE_BXA","I74": #LOCATION = "J73" !CDS_LOCATION = "J73" #SEC = "1" !CDS_SEC = "1";
"1_P":   PN = "1"  !CDS_PN = "1";
"2_N":   PN = "2"  !CDS_PN = "2";
"3_G":   PN = "3"  !CDS_PN = "3";
BODY = "PICOPROBE_BXA","I75": #LOCATION = "J8068" !CDS_LOCATION = "J8068" #SEC = "1" !CDS_SEC = "1";
"1_P":   PN = "1"  !CDS_PN = "1";
"2_N":   PN = "2"  !CDS_PN = "2";
"3_G":   PN = "3"  !CDS_PN = "3";
BODY = "PICOPROBE_BXA","I76": #LOCATION = "J74" !CDS_LOCATION = "J74" #SEC = "1" !CDS_SEC = "1";
"1_P":   PN = "1"  !CDS_PN = "1";
"2_N":   PN = "2"  !CDS_PN = "2";
"3_G":   PN = "3"  !CDS_PN = "3";
BODY = "PICOPROBE_BXA","I77": #LOCATION = "J114" !CDS_LOCATION = "J114" #SEC = "1" !CDS_SEC = "1";
"1_P":   PN = "1"  !CDS_PN = "1";
"2_N":   PN = "2"  !CDS_PN = "2";
"3_G":   PN = "3"  !CDS_PN = "3";
BODY = "PICOPROBE_BXA","I78": #LOCATION = "J116" !CDS_LOCATION = "J116" #SEC = "1" !CDS_SEC = "1";
"1_P":   PN = "1"  !CDS_PN = "1";
"2_N":   PN = "2"  !CDS_PN = "2";
"3_G":   PN = "3"  !CDS_PN = "3";
BODY = "PICOPROBE_BXA","I79": #LOCATION = "J115" !CDS_LOCATION = "J115" #SEC = "1" !CDS_SEC = "1";
"1_P":   PN = "1"  !CDS_PN = "1";
"2_N":   PN = "2"  !CDS_PN = "2";
"3_G":   PN = "3"  !CDS_PN = "3";
BODY = "PICOPROBE_BXA","I80": #LOCATION = "J117" !CDS_LOCATION = "J117" #SEC = "1" !CDS_SEC = "1";
"1_P":   PN = "1"  !CDS_PN = "1";
"2_N":   PN = "2"  !CDS_PN = "2";
"3_G":   PN = "3"  !CDS_PN = "3";
BODY = "PICOPROBE_BXA","I81": #LOCATION = "J75" !CDS_LOCATION = "J75" #SEC = "1" !CDS_SEC = "1";
"1_P":   PN = "1"  !CDS_PN = "1";
"2_N":   PN = "2"  !CDS_PN = "2";
"3_G":   PN = "3"  !CDS_PN = "3";
BODY = "PICOPROBE_BXA","I82": #LOCATION = "J81" !CDS_LOCATION = "J81" #SEC = "1" !CDS_SEC = "1";
"1_P":   PN = "1"  !CDS_PN = "1";
"2_N":   PN = "2"  !CDS_PN = "2";
"3_G":   PN = "3"  !CDS_PN = "3";
BODY = "PICOPROBE_BXA","I83": #LOCATION = "J76" !CDS_LOCATION = "J76" #SEC = "1" !CDS_SEC = "1";
"1_P":   PN = "1"  !CDS_PN = "1";
"2_N":   PN = "2"  !CDS_PN = "2";
"3_G":   PN = "3"  !CDS_PN = "3";
BODY = "PICOPROBE_BXA","I84": #LOCATION = "J82" !CDS_LOCATION = "J82" #SEC = "1" !CDS_SEC = "1";
"1_P":   PN = "1"  !CDS_PN = "1";
"2_N":   PN = "2"  !CDS_PN = "2";
"3_G":   PN = "3"  !CDS_PN = "3";
BODY = "PICOPROBE_BXA","I85": #LOCATION = "J77" !CDS_LOCATION = "J77" #SEC = "1" !CDS_SEC = "1";
"1_P":   PN = "1"  !CDS_PN = "1";
"2_N":   PN = "2"  !CDS_PN = "2";
"3_G":   PN = "3"  !CDS_PN = "3";
BODY = "PICOPROBE_BXA","I86": #LOCATION = "J83" !CDS_LOCATION = "J83" #SEC = "1" !CDS_SEC = "1";
"1_P":   PN = "1"  !CDS_PN = "1";
"2_N":   PN = "2"  !CDS_PN = "2";
"3_G":   PN = "3"  !CDS_PN = "3";
BODY = "PICOPROBE_BXA","I87": #LOCATION = "J78" !CDS_LOCATION = "J78" #SEC = "1" !CDS_SEC = "1";
"1_P":   PN = "1"  !CDS_PN = "1";
"2_N":   PN = "2"  !CDS_PN = "2";
"3_G":   PN = "3"  !CDS_PN = "3";
BODY = "PICOPROBE_BXA","I88": #LOCATION = "J84" !CDS_LOCATION = "J84" #SEC = "1" !CDS_SEC = "1";
"1_P":   PN = "1"  !CDS_PN = "1";
"2_N":   PN = "2"  !CDS_PN = "2";
"3_G":   PN = "3"  !CDS_PN = "3";
BODY = "PICOPROBE_BXA","I89": #LOCATION = "J79" !CDS_LOCATION = "J79" #SEC = "1" !CDS_SEC = "1";
"1_P":   PN = "1"  !CDS_PN = "1";
"2_N":   PN = "2"  !CDS_PN = "2";
"3_G":   PN = "3"  !CDS_PN = "3";
BODY = "PICOPROBE_BXA","I90": #LOCATION = "J85" !CDS_LOCATION = "J85" #SEC = "1" !CDS_SEC = "1";
"1_P":   PN = "1"  !CDS_PN = "1";
"2_N":   PN = "2"  !CDS_PN = "2";
"3_G":   PN = "3"  !CDS_PN = "3";
BODY = "PICOPROBE_BXA","I91": #LOCATION = "J80" !CDS_LOCATION = "J80" #SEC = "1" !CDS_SEC = "1";
"1_P":   PN = "1"  !CDS_PN = "1";
"2_N":   PN = "2"  !CDS_PN = "2";
"3_G":   PN = "3"  !CDS_PN = "3";
BODY = "PICOPROBE_BXA","I92": #LOCATION = "J86" !CDS_LOCATION = "J86" #SEC = "1" !CDS_SEC = "1";
"1_P":   PN = "1"  !CDS_PN = "1";
"2_N":   PN = "2"  !CDS_PN = "2";
"3_G":   PN = "3"  !CDS_PN = "3";
BODY = "PICOPROBE_BXA","I93": #LOCATION = "J118" !CDS_LOCATION = "J118" #SEC = "1" !CDS_SEC = "1";
"1_P":   PN = "1"  !CDS_PN = "1";
"2_N":   PN = "2"  !CDS_PN = "2";
"3_G":   PN = "3"  !CDS_PN = "3";
BODY = "PICOPROBE_BXA","I94": #LOCATION = "J120" !CDS_LOCATION = "J120" #SEC = "1" !CDS_SEC = "1";
"1_P":   PN = "1"  !CDS_PN = "1";
"2_N":   PN = "2"  !CDS_PN = "2";
"3_G":   PN = "3"  !CDS_PN = "3";
BODY = "PICOPROBE_BXA","I95": #LOCATION = "J119" !CDS_LOCATION = "J119" #SEC = "1" !CDS_SEC = "1";
"1_P":   PN = "1"  !CDS_PN = "1";
"2_N":   PN = "2"  !CDS_PN = "2";
"3_G":   PN = "3"  !CDS_PN = "3";
BODY = "PICOPROBE_BXA","I96": #LOCATION = "J121" !CDS_LOCATION = "J121" #SEC = "1" !CDS_SEC = "1";
"1_P":   PN = "1"  !CDS_PN = "1";
"2_N":   PN = "2"  !CDS_PN = "2";
"3_G":   PN = "3"  !CDS_PN = "3";
DRAWING = "@t6g_mb_lib.t6g(sch_1):page146";
BODY = "Q_RES","I2": #LOCATION = "R700" !CDS_LOCATION = "R700" &SEC = "1" #&CDS_SEC = "1";
"A":   PN = "1"  !CDS_PN = "1";
"B":   PN = "2"  !CDS_PN = "2";
BODY = "Q_RES","I3": #LOCATION = "R855" !CDS_LOCATION = "R855" &SEC = "1" #&CDS_SEC = "1";
"A":   PN = "1"  !CDS_PN = "1";
"B":   PN = "2"  !CDS_PN = "2";
BODY = "SCHOTTKY_DUAL_12A_3C","I5": #LOCATION = "U57" !CDS_LOCATION = "U57" #SEC = "1" !CDS_SEC = "1";
"A":   PN = "2"  !CDS_PN = "2";
"B":   PN = "1"  !CDS_PN = "1";
"C":   PN = "3"  !CDS_PN = "3";
BODY = "Q_CAP","I6": #LOCATION = "C1113" !CDS_LOCATION = "C1113" &SEC = "1" #&CDS_SEC = "1";
"A":   PN = "1"  !CDS_PN = "1";
"B":   PN = "2"  !CDS_PN = "2";
BODY = "MOSFET_PCH_GDS_ESD_PROTECTED","I10": #LOCATION = "Q7000" !CDS_LOCATION = "Q7000" #SEC = "1" !CDS_SEC = "1";
"D":   PN = "D"  !CDS_PN = "D";
"G":   PN = "G"  !CDS_PN = "G";
"S":   PN = "S"  !CDS_PN = "S";
BODY = "Q_RES","I11": #LOCATION = "R1007" !CDS_LOCATION = "R1007" &SEC = "1" #&CDS_SEC = "1";
"A":   PN = "1"  !CDS_PN = "1";
"B":   PN = "2"  !CDS_PN = "2";
BODY = "Q_RES","I12": #LOCATION = "R1049" !CDS_LOCATION = "R1049" &SEC = "1" #&CDS_SEC = "1";
"A":   PN = "1"  !CDS_PN = "1";
"B":   PN = "2"  !CDS_PN = "2";
BODY = "Q_RES","I14": #LOCATION = "R1474" !CDS_LOCATION = "R1474" &SEC = "1" #&CDS_SEC = "1";
"A":   PN = "1"  !CDS_PN = "1";
"B":   PN = "2"  !CDS_PN = "2";
BODY = "MOSFET_NCH_1D3S","I16": #LOCATION = "Q7001" !CDS_LOCATION = "Q7001" &SEC = "1" #&CDS_SEC = "1";
"1":   PN = "1"  !CDS_PN = "1";
"2":   PN = "2"  !CDS_PN = "2";
"3":   PN = "3"  !CDS_PN = "3";
"4":   PN = "4"  !CDS_PN = "4";
"5":   PN = "5"  !CDS_PN = "5";
BODY = "Q_RES","I19": #LOCATION = "R1480" !CDS_LOCATION = "R1480" &SEC = "1" #&CDS_SEC = "1";
"A":   PN = "1"  !CDS_PN = "1";
"B":   PN = "2"  !CDS_PN = "2";
BODY = "Q_RES","I21": #LOCATION = "R1481" !CDS_LOCATION = "R1481" &SEC = "1" #&CDS_SEC = "1";
"A":   PN = "1"  !CDS_PN = "1";
"B":   PN = "2"  !CDS_PN = "2";
BODY = "MOSFET_NCH_1D3S","I22": #LOCATION = "Q7003" !CDS_LOCATION = "Q7003" &SEC = "1" #&CDS_SEC = "1";
"1":   PN = "1"  !CDS_PN = "1";
"2":   PN = "2"  !CDS_PN = "2";
"3":   PN = "3"  !CDS_PN = "3";
"4":   PN = "4"  !CDS_PN = "4";
"5":   PN = "5"  !CDS_PN = "5";
BODY = "MOSFET_PCH_GDS_ESD_PROTECTED","I23": #LOCATION = "Q7002" !CDS_LOCATION = "Q7002" &SEC = "1" #&CDS_SEC = "1";
"D":   PN = "D"  !CDS_PN = "D";
"G":   PN = "G"  !CDS_PN = "G";
"S":   PN = "S"  !CDS_PN = "S";
BODY = "SCHOTTKY_DUAL_12A_3C","I25": #LOCATION = "U60" !CDS_LOCATION = "U60" &SEC = "1" #&CDS_SEC = "1";
"A":   PN = "2"  !CDS_PN = "2";
"B":   PN = "1"  !CDS_PN = "1";
"C":   PN = "3"  !CDS_PN = "3";
BODY = "Q_RES","I28": #LOCATION = "R1475" !CDS_LOCATION = "R1475" &SEC = "1" #&CDS_SEC = "1";
"A":   PN = "1"  !CDS_PN = "1";
"B":   PN = "2"  !CDS_PN = "2";
BODY = "Q_CAP","I30": #LOCATION = "C1114" !CDS_LOCATION = "C1114" &SEC = "1" #&CDS_SEC = "1";
"A":   PN = "1"  !CDS_PN = "1";
"B":   PN = "2"  !CDS_PN = "2";
BODY = "Q_RES","I35": #LOCATION = "R896" !CDS_LOCATION = "R896" &SEC = "1" #&CDS_SEC = "1";
"A":   PN = "1"  !CDS_PN = "1";
"B":   PN = "2"  !CDS_PN = "2";
BODY = "Q_RES","I36": #LOCATION = "R954" !CDS_LOCATION = "R954" &SEC = "1" #&CDS_SEC = "1";
"A":   PN = "1"  !CDS_PN = "1";
"B":   PN = "2"  !CDS_PN = "2";
BODY = "Q_RES","I38": #LOCATION = "R1052" !CDS_LOCATION = "R1052" &SEC = "1" #&CDS_SEC = "1";
"A":   PN = "1"  !CDS_PN = "1";
"B":   PN = "2"  !CDS_PN = "2";
BODY = "Q_RES","I39": #LOCATION = "R1092" !CDS_LOCATION = "R1092" &SEC = "1" #&CDS_SEC = "1";
"A":   PN = "1"  !CDS_PN = "1";
"B":   PN = "2"  !CDS_PN = "2";
END.
